G04 ================== begin FILE IDENTIFICATION RECORD ==================*
G04 Layout Name:  14545-sa.brd*
G04 Film Name:    L1*
G04 File Format:  Gerber RS274X*
G04 File Origin:  Cadence Allegro 16.5-S056*
G04 Origin Date:  Fri Aug 01 17:58:35 2014*
G04 *
G04 Layer:  VIA CLASS/TOP*
G04 Layer:  PIN/TOP*
G04 Layer:  ETCH/TOP*
G04 Layer:  DRAWING FORMAT/LAYER_PCB_STORY*
G04 Layer:  DRAWING FORMAT/LAYER_L1*
G04 *
G04 Offset:    (0.00 0.00)*
G04 Mirror:    No*
G04 Mode:      Positive*
G04 Rotation:  0*
G04 FullContactRelief:  No*
G04 UndefLineWidth:     6.00*
G04 ================== end FILE IDENTIFICATION RECORD ====================*
%FSLAX35Y35*MOIN*%
%IR0*IPPOS*OFA0.00000B0.00000*MIA0B0*SFA1.00000B1.00000*%
%AMMACRO47*
4,1,40,.017,-.013,
.017,.013,
.016939,.013695,
.016759,.014368,
.016464,.015,
.016064,.015571,
.015571,.016064,
.015,.016464,
.014368,.016759,
.013695,.016939,
.013,.017,
-.013,.017,
-.013695,.016939,
-.014368,.016759,
-.015,.016464,
-.015571,.016064,
-.016064,.015571,
-.016464,.015,
-.016759,.014368,
-.016939,.013695,
-.017,.013,
-.017,-.013,
-.016939,-.013695,
-.016759,-.014368,
-.016464,-.015,
-.016064,-.015571,
-.015571,-.016064,
-.015,-.016464,
-.014368,-.016759,
-.013695,-.016939,
-.013,-.017,
.013,-.017,
.013695,-.016939,
.014368,-.016759,
.015,-.016464,
.015571,-.016064,
.016064,-.015571,
.016464,-.015,
.016759,-.014368,
.016939,-.013695,
.017,-.013,
0.0*
%
%ADD47MACRO47*%
%AMMACRO20*
4,1,40,.013,.017,
-.013,.017,
-.013695,.016939,
-.014368,.016759,
-.015,.016464,
-.015571,.016064,
-.016064,.015571,
-.016464,.015,
-.016759,.014368,
-.016939,.013695,
-.017,.013,
-.017,-.013,
-.016939,-.013695,
-.016759,-.014368,
-.016464,-.015,
-.016064,-.015571,
-.015571,-.016064,
-.015,-.016464,
-.014368,-.016759,
-.013695,-.016939,
-.013,-.017,
.013,-.017,
.013695,-.016939,
.014368,-.016759,
.015,-.016464,
.015571,-.016064,
.016064,-.015571,
.016464,-.015,
.016759,-.014368,
.016939,-.013695,
.017,-.013,
.017,.013,
.016939,.013695,
.016759,.014368,
.016464,.015,
.016064,.015571,
.015571,.016064,
.015,.016464,
.014368,.016759,
.013695,.016939,
.013,.017,
0.0*
%
%ADD20MACRO20*%
%AMMACRO84*
4,1,40,.019,.017,
-.019,.017,
-.019695,.016939,
-.020368,.016759,
-.021,.016464,
-.021571,.016064,
-.022064,.015571,
-.022464,.015,
-.022759,.014368,
-.022939,.013695,
-.023,.013,
-.023,-.013,
-.022939,-.013695,
-.022759,-.014368,
-.022464,-.015,
-.022064,-.015571,
-.021571,-.016064,
-.021,-.016464,
-.020368,-.016759,
-.019695,-.016939,
-.019,-.017,
.019,-.017,
.019695,-.016939,
.020368,-.016759,
.021,-.016464,
.021571,-.016064,
.022064,-.015571,
.022464,-.015,
.022759,-.014368,
.022939,-.013695,
.023,-.013,
.023,.013,
.022939,.013695,
.022759,.014368,
.022464,.015,
.022064,.015571,
.021571,.016064,
.021,.016464,
.020368,.016759,
.019695,.016939,
.019,.017,
0.0*
%
%ADD84MACRO84*%
%ADD17O,.103X.06*%
%ADD88R,.23X.032*%
%ADD61R,.045X.11*%
%ADD21R,.11X.045*%
%ADD11C,.01*%
%ADD13R,.142X.028*%
%ADD15C,.022*%
%ADD29C,.032*%
%ADD12C,.028*%
%ADD10R,.05X.05*%
%AMMACRO66*
4,1,40,-.007,-.0225,
-.008389,-.022378,
-.009736,-.022018,
-.011,-.021428,
-.012142,-.020628,
-.013128,-.019642,
-.013928,-.0185,
-.014518,-.017236,
-.014878,-.015889,
-.015,-.0145,
-.015,.0145,
-.014878,.015889,
-.014518,.017236,
-.013928,.0185,
-.013128,.019642,
-.012142,.020628,
-.011,.021428,
-.009736,.022018,
-.008389,.022378,
-.007,.0225,
.007,.0225,
.008389,.022378,
.009736,.022018,
.011,.021428,
.012142,.020628,
.013128,.019642,
.013928,.0185,
.014518,.017236,
.014878,.015889,
.015,.0145,
.015,-.0145,
.014878,-.015889,
.014518,-.017236,
.013928,-.0185,
.013128,-.019642,
.012142,-.020628,
.011,-.021428,
.009736,-.022018,
.008389,-.022378,
.007,-.0225,
-.007,-.0225,
0.0*
%
%ADD66MACRO66*%
%AMMACRO86*
4,1,8,.197,-.186,
-.197,-.186,
-.197,.186,
.197,.186,
.197,.00925,
-.059,.00925,
-.059,-.00925,
.197,-.00925,
.197,-.186,
0.0*
%
%ADD86MACRO86*%
%AMMACRO30*
4,1,40,.011,-.007,
.011,.007,
.010939,.007695,
.010759,.008368,
.010464,.009,
.010064,.009571,
.009571,.010064,
.009,.010464,
.008368,.010759,
.007695,.010939,
.007,.011,
-.007,.011,
-.007695,.010939,
-.008368,.010759,
-.009,.010464,
-.009571,.010064,
-.010064,.009571,
-.010464,.009,
-.010759,.008368,
-.010939,.007695,
-.011,.007,
-.011,-.007,
-.010939,-.007695,
-.010759,-.008368,
-.010464,-.009,
-.010064,-.009571,
-.009571,-.010064,
-.009,-.010464,
-.008368,-.010759,
-.007695,-.010939,
-.007,-.011,
.007,-.011,
.007695,-.010939,
.008368,-.010759,
.009,-.010464,
.009571,-.010064,
.010064,-.009571,
.010464,-.009,
.010759,-.008368,
.010939,-.007695,
.011,-.007,
0.0*
%
%ADD30MACRO30*%
%AMMACRO24*
4,1,40,.007,.011,
-.007,.011,
-.007695,.010939,
-.008368,.010759,
-.009,.010464,
-.009571,.010064,
-.010064,.009571,
-.010464,.009,
-.010759,.008368,
-.010939,.007695,
-.011,.007,
-.011,-.007,
-.010939,-.007695,
-.010759,-.008368,
-.010464,-.009,
-.010064,-.009571,
-.009571,-.010064,
-.009,-.010464,
-.008368,-.010759,
-.007695,-.010939,
-.007,-.011,
.007,-.011,
.007695,-.010939,
.008368,-.010759,
.009,-.010464,
.009571,-.010064,
.010064,-.009571,
.010464,-.009,
.010759,-.008368,
.010939,-.007695,
.011,-.007,
.011,.007,
.010939,.007695,
.010759,.008368,
.010464,.009,
.010064,.009571,
.009571,.010064,
.009,.010464,
.008368,.010759,
.007695,.010939,
.007,.011,
0.0*
%
%ADD24MACRO24*%
%AMMACRO45*
4,1,40,-.012,.008,
-.012,-.008,
-.011939,-.008695,
-.011759,-.009368,
-.011464,-.01,
-.011064,-.010571,
-.010571,-.011064,
-.01,-.011464,
-.009368,-.011759,
-.008695,-.011939,
-.008,-.012,
.008,-.012,
.008695,-.011939,
.009368,-.011759,
.01,-.011464,
.010571,-.011064,
.011064,-.010571,
.011464,-.01,
.011759,-.009368,
.011939,-.008695,
.012,-.008,
.012,.008,
.011939,.008695,
.011759,.009368,
.011464,.01,
.011064,.010571,
.010571,.011064,
.01,.011464,
.009368,.011759,
.008695,.011939,
.008,.012,
-.008,.012,
-.008695,.011939,
-.009368,.011759,
-.01,.011464,
-.010571,.011064,
-.011064,.010571,
-.011464,.01,
-.011759,.009368,
-.011939,.008695,
-.012,.008,
0.0*
%
%ADD45MACRO45*%
%AMMACRO59*
4,1,40,.008,.012,
-.008,.012,
-.008695,.011939,
-.009368,.011759,
-.01,.011464,
-.010571,.011064,
-.011064,.010571,
-.011464,.01,
-.011759,.009368,
-.011939,.008695,
-.012,.008,
-.012,-.008,
-.011939,-.008695,
-.011759,-.009368,
-.011464,-.01,
-.011064,-.010571,
-.010571,-.011064,
-.01,-.011464,
-.009368,-.011759,
-.008695,-.011939,
-.008,-.012,
.008,-.012,
.008695,-.011939,
.009368,-.011759,
.01,-.011464,
.010571,-.011064,
.011064,-.010571,
.011464,-.01,
.011759,-.009368,
.011939,-.008695,
.012,-.008,
.012,.008,
.011939,.008695,
.011759,.009368,
.011464,.01,
.011064,.010571,
.010571,.011064,
.01,.011464,
.009368,.011759,
.008695,.011939,
.008,.012,
0.0*
%
%ADD59MACRO59*%
%AMMACRO72*
4,1,6,.0135,-.025,
-.0065,-.005,
-.0135,-.005,
-.0135,.005,
-.0065,.005,
.0135,.025,
.0135,-.025,
0.0*
%
%ADD72MACRO72*%
%AMMACRO38*
4,1,40,-.013,-.017,
.013,-.017,
.013695,-.016939,
.014368,-.016759,
.015,-.016464,
.015571,-.016064,
.016064,-.015571,
.016464,-.015,
.016759,-.014368,
.016939,-.013695,
.017,-.013,
.017,.013,
.016939,.013695,
.016759,.014368,
.016464,.015,
.016064,.015571,
.015571,.016064,
.015,.016464,
.014368,.016759,
.013695,.016939,
.013,.017,
-.013,.017,
-.013695,.016939,
-.014368,.016759,
-.015,.016464,
-.015571,.016064,
-.016064,.015571,
-.016464,.015,
-.016759,.014368,
-.016939,.013695,
-.017,.013,
-.017,-.013,
-.016939,-.013695,
-.016759,-.014368,
-.016464,-.015,
-.016064,-.015571,
-.015571,-.016064,
-.015,-.016464,
-.014368,-.016759,
-.013695,-.016939,
-.013,-.017,
0.0*
%
%ADD38MACRO38*%
%AMMACRO48*
4,1,40,-.017,.013,
-.017,-.013,
-.016939,-.013695,
-.016759,-.014368,
-.016464,-.015,
-.016064,-.015571,
-.015571,-.016064,
-.015,-.016464,
-.014368,-.016759,
-.013695,-.016939,
-.013,-.017,
.013,-.017,
.013695,-.016939,
.014368,-.016759,
.015,-.016464,
.015571,-.016064,
.016064,-.015571,
.016464,-.015,
.016759,-.014368,
.016939,-.013695,
.017,-.013,
.017,.013,
.016939,.013695,
.016759,.014368,
.016464,.015,
.016064,.015571,
.015571,.016064,
.015,.016464,
.014368,.016759,
.013695,.016939,
.013,.017,
-.013,.017,
-.013695,.016939,
-.014368,.016759,
-.015,.016464,
-.015571,.016064,
-.016064,.015571,
-.016464,.015,
-.016759,.014368,
-.016939,.013695,
-.017,.013,
0.0*
%
%ADD48MACRO48*%
%AMMACRO54*
4,1,6,.005,.0135,
.005,.0065,
.025,-.0135,
-.025,-.0135,
-.005,.0065,
-.005,.0135,
.005,.0135,
0.0*
%
%ADD54MACRO54*%
%AMMACRO69*
4,1,20,.0655,-.1095,
.051,-.1095,
.051,-.12,
.0375,-.12,
.0375,-.1095,
-.0375,-.1095,
-.0375,-.12,
-.051,-.12,
-.051,-.1095,
-.0655,-.1095,
-.0655,.1095,
-.051,.1095,
-.051,.12,
-.0375,.12,
-.0375,.1095,
.0375,.1095,
.0375,.12,
.051,.12,
.051,.1095,
.0655,.1095,
.0655,-.1095,
0.0*
%
%ADD69MACRO69*%
%AMMACRO31*
4,1,40,.011,-.007,
.011,.007,
.010939,.007695,
.010759,.008368,
.010464,.009,
.010064,.009571,
.009571,.010064,
.009,.010464,
.008368,.010759,
.007695,.010939,
.007,.011,
-.007,.011,
-.007695,.010939,
-.008368,.010759,
-.009,.010464,
-.009571,.010064,
-.010064,.009571,
-.010464,.009,
-.010759,.008368,
-.010939,.007695,
-.011,.007,
-.011,-.007,
-.010939,-.007695,
-.010759,-.008368,
-.010464,-.009,
-.010064,-.009571,
-.009571,-.010064,
-.009,-.010464,
-.008368,-.010759,
-.007695,-.010939,
-.007,-.011,
.007,-.011,
.007695,-.010939,
.008368,-.010759,
.009,-.010464,
.009571,-.010064,
.010064,-.009571,
.010464,-.009,
.010759,-.008368,
.010939,-.007695,
.011,-.007,
0.0*
%
%ADD31MACRO31*%
%AMMACRO25*
4,1,40,.007,.011,
-.007,.011,
-.007695,.010939,
-.008368,.010759,
-.009,.010464,
-.009571,.010064,
-.010064,.009571,
-.010464,.009,
-.010759,.008368,
-.010939,.007695,
-.011,.007,
-.011,-.007,
-.010939,-.007695,
-.010759,-.008368,
-.010464,-.009,
-.010064,-.009571,
-.009571,-.010064,
-.009,-.010464,
-.008368,-.010759,
-.007695,-.010939,
-.007,-.011,
.007,-.011,
.007695,-.010939,
.008368,-.010759,
.009,-.010464,
.009571,-.010064,
.010064,-.009571,
.010464,-.009,
.010759,-.008368,
.010939,-.007695,
.011,-.007,
.011,.007,
.010939,.007695,
.010759,.008368,
.010464,.009,
.010064,.009571,
.009571,.010064,
.009,.010464,
.008368,.010759,
.007695,.010939,
.007,.011,
0.0*
%
%ADD25MACRO25*%
%AMMACRO44*
4,1,40,-.012,.008,
-.012,-.008,
-.011939,-.008695,
-.011759,-.009368,
-.011464,-.01,
-.011064,-.010571,
-.010571,-.011064,
-.01,-.011464,
-.009368,-.011759,
-.008695,-.011939,
-.008,-.012,
.008,-.012,
.008695,-.011939,
.009368,-.011759,
.01,-.011464,
.010571,-.011064,
.011064,-.010571,
.011464,-.01,
.011759,-.009368,
.011939,-.008695,
.012,-.008,
.012,.008,
.011939,.008695,
.011759,.009368,
.011464,.01,
.011064,.010571,
.010571,.011064,
.01,.011464,
.009368,.011759,
.008695,.011939,
.008,.012,
-.008,.012,
-.008695,.011939,
-.009368,.011759,
-.01,.011464,
-.010571,.011064,
-.011064,.010571,
-.011464,.01,
-.011759,.009368,
-.011939,.008695,
-.012,.008,
0.0*
%
%ADD44MACRO44*%
%AMMACRO58*
4,1,40,.008,.012,
-.008,.012,
-.008695,.011939,
-.009368,.011759,
-.01,.011464,
-.010571,.011064,
-.011064,.010571,
-.011464,.01,
-.011759,.009368,
-.011939,.008695,
-.012,.008,
-.012,-.008,
-.011939,-.008695,
-.011759,-.009368,
-.011464,-.01,
-.011064,-.010571,
-.010571,-.011064,
-.01,-.011464,
-.009368,-.011759,
-.008695,-.011939,
-.008,-.012,
.008,-.012,
.008695,-.011939,
.009368,-.011759,
.01,-.011464,
.010571,-.011064,
.011064,-.010571,
.011464,-.01,
.011759,-.009368,
.011939,-.008695,
.012,-.008,
.012,.008,
.011939,.008695,
.011759,.009368,
.011464,.01,
.011064,.010571,
.010571,.011064,
.01,.011464,
.009368,.011759,
.008695,.011939,
.008,.012,
0.0*
%
%ADD58MACRO58*%
%AMMACRO39*
4,1,40,-.013,-.017,
.013,-.017,
.013695,-.016939,
.014368,-.016759,
.015,-.016464,
.015571,-.016064,
.016064,-.015571,
.016464,-.015,
.016759,-.014368,
.016939,-.013695,
.017,-.013,
.017,.013,
.016939,.013695,
.016759,.014368,
.016464,.015,
.016064,.015571,
.015571,.016064,
.015,.016464,
.014368,.016759,
.013695,.016939,
.013,.017,
-.013,.017,
-.013695,.016939,
-.014368,.016759,
-.015,.016464,
-.015571,.016064,
-.016064,.015571,
-.016464,.015,
-.016759,.014368,
-.016939,.013695,
-.017,.013,
-.017,-.013,
-.016939,-.013695,
-.016759,-.014368,
-.016464,-.015,
-.016064,-.015571,
-.015571,-.016064,
-.015,-.016464,
-.014368,-.016759,
-.013695,-.016939,
-.013,-.017,
0.0*
%
%ADD39MACRO39*%
%AMMACRO49*
4,1,40,-.017,.013,
-.017,-.013,
-.016939,-.013695,
-.016759,-.014368,
-.016464,-.015,
-.016064,-.015571,
-.015571,-.016064,
-.015,-.016464,
-.014368,-.016759,
-.013695,-.016939,
-.013,-.017,
.013,-.017,
.013695,-.016939,
.014368,-.016759,
.015,-.016464,
.015571,-.016064,
.016064,-.015571,
.016464,-.015,
.016759,-.014368,
.016939,-.013695,
.017,-.013,
.017,.013,
.016939,.013695,
.016759,.014368,
.016464,.015,
.016064,.015571,
.015571,.016064,
.015,.016464,
.014368,.016759,
.013695,.016939,
.013,.017,
-.013,.017,
-.013695,.016939,
-.014368,.016759,
-.015,.016464,
-.015571,.016064,
-.016064,.015571,
-.016464,.015,
-.016759,.014368,
-.016939,.013695,
-.017,.013,
0.0*
%
%ADD49MACRO49*%
%ADD85R,.001X.001*%
%ADD35R,.04X.022*%
%ADD76R,.06X.012*%
%ADD75R,.022X.04*%
%ADD81R,.023X.04*%
%ADD77R,.06X.014*%
%ADD70R,.044X.012*%
%ADD60R,.04X.016*%
%ADD65R,.014X.06*%
%ADD63R,.016X.04*%
%ADD52R,.012X.044*%
%ADD28R,.045X.03*%
%ADD53R,.133X.128*%
%ADD56R,.128X.133*%
%ADD22R,.075X.02*%
%ADD80R,.05X.065*%
%ADD23R,.036X.024*%
%ADD41R,.065X.05*%
%ADD40R,.065X.025*%
%ADD16C,.315*%
%ADD67R,.025X.065*%
%ADD64R,.048X.016*%
%ADD14R,.045X.055*%
%ADD62R,.016X.048*%
%ADD50R,.055X.045*%
%ADD87R,.394X.172*%
%ADD68R,.054X.074*%
%ADD18R,.094X.026*%
%ADD79R,.0615X.055*%
%ADD34R,.09X.095*%
%AMMACRO74*
4,1,40,-.0225,.007,
-.022378,.008389,
-.022018,.009736,
-.021428,.011,
-.020628,.012142,
-.019642,.013128,
-.0185,.013928,
-.017236,.014518,
-.015889,.014878,
-.0145,.015,
.0145,.015,
.015889,.014878,
.017236,.014518,
.0185,.013928,
.019642,.013128,
.020628,.012142,
.021428,.011,
.022018,.009736,
.022378,.008389,
.0225,.007,
.0225,-.007,
.022378,-.008389,
.022018,-.009736,
.021428,-.011,
.020628,-.012142,
.019642,-.013128,
.0185,-.013928,
.017236,-.014518,
.015889,-.014878,
.0145,-.015,
-.0145,-.015,
-.015889,-.014878,
-.017236,-.014518,
-.0185,-.013928,
-.019642,-.013128,
-.020628,-.012142,
-.021428,-.011,
-.022018,-.009736,
-.022378,-.008389,
-.0225,-.007,
-.0225,.007,
0.0*
%
%ADD74MACRO74*%
%AMMACRO73*
4,1,40,.007,.0225,
.008389,.022378,
.009736,.022018,
.011,.021428,
.012142,.020628,
.013128,.019642,
.013928,.0185,
.014518,.017236,
.014878,.015889,
.015,.0145,
.015,-.0145,
.014878,-.015889,
.014518,-.017236,
.013928,-.0185,
.013128,-.019642,
.012142,-.020628,
.011,-.021428,
.009736,-.022018,
.008389,-.022378,
.007,-.0225,
-.007,-.0225,
-.008389,-.022378,
-.009736,-.022018,
-.011,-.021428,
-.012142,-.020628,
-.013128,-.019642,
-.013928,-.0185,
-.014518,-.017236,
-.014878,-.015889,
-.015,-.0145,
-.015,.0145,
-.014878,.015889,
-.014518,.017236,
-.013928,.0185,
-.013128,.019642,
-.012142,.020628,
-.011,.021428,
-.009736,.022018,
-.008389,.022378,
-.007,.0225,
.007,.0225,
0.0*
%
%ADD73MACRO73*%
%ADD57R,.095X.09*%
%ADD78R,.06176X.055*%
%ADD82R,.089X.059*%
%AMMACRO43*
4,1,40,-.008,-.012,
.008,-.012,
.008695,-.011939,
.009368,-.011759,
.01,-.011464,
.010571,-.011064,
.011064,-.010571,
.011464,-.01,
.011759,-.009368,
.011939,-.008695,
.012,-.008,
.012,.008,
.011939,.008695,
.011759,.009368,
.011464,.01,
.011064,.010571,
.010571,.011064,
.01,.011464,
.009368,.011759,
.008695,.011939,
.008,.012,
-.008,.012,
-.008695,.011939,
-.009368,.011759,
-.01,.011464,
-.010571,.011064,
-.011064,.010571,
-.011464,.01,
-.011759,.009368,
-.011939,.008695,
-.012,.008,
-.012,-.008,
-.011939,-.008695,
-.011759,-.009368,
-.011464,-.01,
-.011064,-.010571,
-.010571,-.011064,
-.01,-.011464,
-.009368,-.011759,
-.008695,-.011939,
-.008,-.012,
0.0*
%
%ADD43MACRO43*%
%AMMACRO37*
4,1,40,.012,-.008,
.012,.008,
.011939,.008695,
.011759,.009368,
.011464,.01,
.011064,.010571,
.010571,.011064,
.01,.011464,
.009368,.011759,
.008695,.011939,
.008,.012,
-.008,.012,
-.008695,.011939,
-.009368,.011759,
-.01,.011464,
-.010571,.011064,
-.011064,.010571,
-.011464,.01,
-.011759,.009368,
-.011939,.008695,
-.012,.008,
-.012,-.008,
-.011939,-.008695,
-.011759,-.009368,
-.011464,-.01,
-.011064,-.010571,
-.010571,-.011064,
-.01,-.011464,
-.009368,-.011759,
-.008695,-.011939,
-.008,-.012,
.008,-.012,
.008695,-.011939,
.009368,-.011759,
.01,-.011464,
.010571,-.011064,
.011064,-.010571,
.011464,-.01,
.011759,-.009368,
.011939,-.008695,
.012,-.008,
0.0*
%
%ADD37MACRO37*%
%AMMACRO26*
4,1,40,-.007,-.011,
.007,-.011,
.007695,-.010939,
.008368,-.010759,
.009,-.010464,
.009571,-.010064,
.010064,-.009571,
.010464,-.009,
.010759,-.008368,
.010939,-.007695,
.011,-.007,
.011,.007,
.010939,.007695,
.010759,.008368,
.010464,.009,
.010064,.009571,
.009571,.010064,
.009,.010464,
.008368,.010759,
.007695,.010939,
.007,.011,
-.007,.011,
-.007695,.010939,
-.008368,.010759,
-.009,.010464,
-.009571,.010064,
-.010064,.009571,
-.010464,.009,
-.010759,.008368,
-.010939,.007695,
-.011,.007,
-.011,-.007,
-.010939,-.007695,
-.010759,-.008368,
-.010464,-.009,
-.010064,-.009571,
-.009571,-.010064,
-.009,-.010464,
-.008368,-.010759,
-.007695,-.010939,
-.007,-.011,
0.0*
%
%ADD26MACRO26*%
%AMMACRO32*
4,1,40,-.011,.007,
-.011,-.007,
-.010939,-.007695,
-.010759,-.008368,
-.010464,-.009,
-.010064,-.009571,
-.009571,-.010064,
-.009,-.010464,
-.008368,-.010759,
-.007695,-.010939,
-.007,-.011,
.007,-.011,
.007695,-.010939,
.008368,-.010759,
.009,-.010464,
.009571,-.010064,
.010064,-.009571,
.010464,-.009,
.010759,-.008368,
.010939,-.007695,
.011,-.007,
.011,.007,
.010939,.007695,
.010759,.008368,
.010464,.009,
.010064,.009571,
.009571,.010064,
.009,.010464,
.008368,.010759,
.007695,.010939,
.007,.011,
-.007,.011,
-.007695,.010939,
-.008368,.010759,
-.009,.010464,
-.009571,.010064,
-.010064,.009571,
-.010464,.009,
-.010759,.008368,
-.010939,.007695,
-.011,.007,
0.0*
%
%ADD32MACRO32*%
%AMMACRO55*
4,1,6,.025,.0135,
.005,-.0065,
.005,-.0135,
-.005,-.0135,
-.005,-.0065,
-.025,.0135,
.025,.0135,
0.0*
%
%ADD55MACRO55*%
%AMMACRO46*
4,1,40,.017,-.013,
.017,.013,
.016939,.013695,
.016759,.014368,
.016464,.015,
.016064,.015571,
.015571,.016064,
.015,.016464,
.014368,.016759,
.013695,.016939,
.013,.017,
-.013,.017,
-.013695,.016939,
-.014368,.016759,
-.015,.016464,
-.015571,.016064,
-.016064,.015571,
-.016464,.015,
-.016759,.014368,
-.016939,.013695,
-.017,.013,
-.017,-.013,
-.016939,-.013695,
-.016759,-.014368,
-.016464,-.015,
-.016064,-.015571,
-.015571,-.016064,
-.015,-.016464,
-.014368,-.016759,
-.013695,-.016939,
-.013,-.017,
.013,-.017,
.013695,-.016939,
.014368,-.016759,
.015,-.016464,
.015571,-.016064,
.016064,-.015571,
.016464,-.015,
.016759,-.014368,
.016939,-.013695,
.017,-.013,
0.0*
%
%ADD46MACRO46*%
%AMMACRO19*
4,1,40,.013,.017,
-.013,.017,
-.013695,.016939,
-.014368,.016759,
-.015,.016464,
-.015571,.016064,
-.016064,.015571,
-.016464,.015,
-.016759,.014368,
-.016939,.013695,
-.017,.013,
-.017,-.013,
-.016939,-.013695,
-.016759,-.014368,
-.016464,-.015,
-.016064,-.015571,
-.015571,-.016064,
-.015,-.016464,
-.014368,-.016759,
-.013695,-.016939,
-.013,-.017,
.013,-.017,
.013695,-.016939,
.014368,-.016759,
.015,-.016464,
.015571,-.016064,
.016064,-.015571,
.016464,-.015,
.016759,-.014368,
.016939,-.013695,
.017,-.013,
.017,.013,
.016939,.013695,
.016759,.014368,
.016464,.015,
.016064,.015571,
.015571,.016064,
.015,.016464,
.014368,.016759,
.013695,.016939,
.013,.017,
0.0*
%
%ADD19MACRO19*%
%AMMACRO83*
4,1,40,-.023,.013,
-.023,-.013,
-.022939,-.013695,
-.022759,-.014368,
-.022464,-.015,
-.022064,-.015571,
-.021571,-.016064,
-.021,-.016464,
-.020368,-.016759,
-.019695,-.016939,
-.019,-.017,
.019,-.017,
.019695,-.016939,
.020368,-.016759,
.021,-.016464,
.021571,-.016064,
.022064,-.015571,
.022464,-.015,
.022759,-.014368,
.022939,-.013695,
.023,-.013,
.023,.013,
.022939,.013695,
.022759,.014368,
.022464,.015,
.022064,.015571,
.021571,.016064,
.021,.016464,
.020368,.016759,
.019695,.016939,
.019,.017,
-.019,.017,
-.019695,.016939,
-.020368,.016759,
-.021,.016464,
-.021571,.016064,
-.022064,.015571,
-.022464,.015,
-.022759,.014368,
-.022939,.013695,
-.023,.013,
0.0*
%
%ADD83MACRO83*%
%AMMACRO51*
4,1,20,.1095,.0655,
.1095,.051,
.12,.051,
.12,.0375,
.1095,.0375,
.1095,-.0375,
.12,-.0375,
.12,-.051,
.1095,-.051,
.1095,-.0655,
-.1095,-.0655,
-.1095,-.051,
-.12,-.051,
-.12,-.0375,
-.1095,-.0375,
-.1095,.0375,
-.12,.0375,
-.12,.051,
-.1095,.051,
-.1095,.0655,
.1095,.0655,
0.0*
%
%ADD51MACRO51*%
%AMMACRO71*
4,1,6,.0135,-.005,
.0065,-.005,
-.0135,-.025,
-.0135,.025,
.0065,.005,
.0135,.005,
.0135,-.005,
0.0*
%
%ADD71MACRO71*%
%AMMACRO42*
4,1,40,-.008,-.012,
.008,-.012,
.008695,-.011939,
.009368,-.011759,
.01,-.011464,
.010571,-.011064,
.011064,-.010571,
.011464,-.01,
.011759,-.009368,
.011939,-.008695,
.012,-.008,
.012,.008,
.011939,.008695,
.011759,.009368,
.011464,.01,
.011064,.010571,
.010571,.011064,
.01,.011464,
.009368,.011759,
.008695,.011939,
.008,.012,
-.008,.012,
-.008695,.011939,
-.009368,.011759,
-.01,.011464,
-.010571,.011064,
-.011064,.010571,
-.011464,.01,
-.011759,.009368,
-.011939,.008695,
-.012,.008,
-.012,-.008,
-.011939,-.008695,
-.011759,-.009368,
-.011464,-.01,
-.011064,-.010571,
-.010571,-.011064,
-.01,-.011464,
-.009368,-.011759,
-.008695,-.011939,
-.008,-.012,
0.0*
%
%ADD42MACRO42*%
%AMMACRO36*
4,1,40,.012,-.008,
.012,.008,
.011939,.008695,
.011759,.009368,
.011464,.01,
.011064,.010571,
.010571,.011064,
.01,.011464,
.009368,.011759,
.008695,.011939,
.008,.012,
-.008,.012,
-.008695,.011939,
-.009368,.011759,
-.01,.011464,
-.010571,.011064,
-.011064,.010571,
-.011464,.01,
-.011759,.009368,
-.011939,.008695,
-.012,.008,
-.012,-.008,
-.011939,-.008695,
-.011759,-.009368,
-.011464,-.01,
-.011064,-.010571,
-.010571,-.011064,
-.01,-.011464,
-.009368,-.011759,
-.008695,-.011939,
-.008,-.012,
.008,-.012,
.008695,-.011939,
.009368,-.011759,
.01,-.011464,
.010571,-.011064,
.011064,-.010571,
.011464,-.01,
.011759,-.009368,
.011939,-.008695,
.012,-.008,
0.0*
%
%ADD36MACRO36*%
%AMMACRO27*
4,1,40,-.007,-.011,
.007,-.011,
.007695,-.010939,
.008368,-.010759,
.009,-.010464,
.009571,-.010064,
.010064,-.009571,
.010464,-.009,
.010759,-.008368,
.010939,-.007695,
.011,-.007,
.011,.007,
.010939,.007695,
.010759,.008368,
.010464,.009,
.010064,.009571,
.009571,.010064,
.009,.010464,
.008368,.010759,
.007695,.010939,
.007,.011,
-.007,.011,
-.007695,.010939,
-.008368,.010759,
-.009,.010464,
-.009571,.010064,
-.010064,.009571,
-.010464,.009,
-.010759,.008368,
-.010939,.007695,
-.011,.007,
-.011,-.007,
-.010939,-.007695,
-.010759,-.008368,
-.010464,-.009,
-.010064,-.009571,
-.009571,-.010064,
-.009,-.010464,
-.008368,-.010759,
-.007695,-.010939,
-.007,-.011,
0.0*
%
%ADD27MACRO27*%
%AMMACRO33*
4,1,40,-.011,.007,
-.011,-.007,
-.010939,-.007695,
-.010759,-.008368,
-.010464,-.009,
-.010064,-.009571,
-.009571,-.010064,
-.009,-.010464,
-.008368,-.010759,
-.007695,-.010939,
-.007,-.011,
.007,-.011,
.007695,-.010939,
.008368,-.010759,
.009,-.010464,
.009571,-.010064,
.010064,-.009571,
.010464,-.009,
.010759,-.008368,
.010939,-.007695,
.011,-.007,
.011,.007,
.010939,.007695,
.010759,.008368,
.010464,.009,
.010064,.009571,
.009571,.010064,
.009,.010464,
.008368,.010759,
.007695,.010939,
.007,.011,
-.007,.011,
-.007695,.010939,
-.008368,.010759,
-.009,.010464,
-.009571,.010064,
-.010064,.009571,
-.010464,.009,
-.010759,.008368,
-.010939,.007695,
-.011,.007,
0.0*
%
%ADD33MACRO33*%
%ADD89C,.02*%
%ADD90C,.03*%
%ADD91C,.012*%
%ADD92C,.04*%
%ADD93C,.014*%
%ADD94C,.015*%
%ADD95C,.016*%
%ADD96C,.025*%
%ADD97C,.006*%
%ADD98C,.00375*%
%ADD99C,.00438*%
%ADD108O,.12702X.08402*%
%ADD103C,.05204*%
%ADD101C,.04604*%
%ADD109R,.16604X.09141*%
%ADD105C,.09704*%
%ADD100R,.01X.01*%
%ADD112R,.021X.01*%
%ADD111R,.01X.021*%
%ADD107C,.11504*%
%ADD104R,.11804X.15004*%
%ADD110C,.17004*%
%ADD106R,.17202X.17204*%
%ADD102C,.33904*%
G75*
%LPD*%
G75*
G36*
G01X113267Y499733D02*
X110478Y496943D01*
G02X109796Y497200I-283J283D01*
G03X105447Y498094I-2297J-150D01*
G01X91532D01*
Y499154D01*
X79728D01*
Y494152D01*
X91532D01*
Y495252D01*
X106061D01*
G03X107349Y494753I1437J1798D01*
G02X107606Y494071I-26J-399D01*
G01X107026Y493491D01*
G03X105787Y492050I8975J-8970D01*
G01X92999D01*
X90999Y490050D01*
X80499D01*
X79499Y489050D01*
Y474350D01*
X80899Y472950D01*
X90199D01*
X90299Y472850D01*
Y470550D01*
X90099Y470350D01*
X80899D01*
X79699Y469150D01*
Y463950D01*
X80699Y462950D01*
X90199D01*
X90299Y462850D01*
Y460450D01*
X90199Y460350D01*
X80899D01*
X79699Y459150D01*
Y444250D01*
X79728Y444221D01*
Y444152D01*
X79798D01*
X81599Y442350D01*
X100399D01*
X101499Y441250D01*
Y437550D01*
X96199Y432250D01*
Y233250D01*
X84499Y221550D01*
X63945D01*
X63902Y221592D01*
X52433D01*
X52390Y221550D01*
X42220D01*
X42194Y221557D01*
G03X38897Y219032I-695J-2507D01*
G01X38898Y218949D01*
X36499Y216550D01*
Y209550D01*
X37999Y208050D01*
X42499D01*
X46499Y204050D01*
Y198550D01*
X48999Y196050D01*
X51778D01*
X51804Y196043D01*
G03X53194I695J2507D01*
G01X53220Y196050D01*
X94499D01*
X100499Y190050D01*
Y166550D01*
X97999Y164050D01*
X79499D01*
X78499Y163050D01*
Y132162D01*
X72214D01*
Y124609D01*
X78499D01*
Y122713D01*
X72214D01*
Y115160D01*
X78499D01*
Y89550D01*
X76999Y88050D01*
X70999D01*
X69499Y86550D01*
Y68550D01*
X71999Y66050D01*
X77499D01*
X78499Y65050D01*
Y39050D01*
X84999Y32550D01*
X103280D01*
Y32249D01*
G02X103241Y31842I-2197J5D01*
G03X105616Y30052I-242J-2792D01*
G03X106120Y32248I-4534J2196D01*
G01Y32550D01*
X120290D01*
G02X120511Y31817I-1J-400D01*
G03X120341Y3730I9409J-14101D01*
G02X120115Y3000I-226J-330D01*
G01X4000D01*
X3099Y3901D01*
Y195000D01*
X4599Y196500D01*
X20500D01*
X20679Y196679D01*
G02X21300Y196610I283J-283D01*
G03X25884Y196957I2200J1390D01*
G02X26616I366J-161D01*
G03Y199043I2384J1043D01*
G02X25884I-366J161D01*
G03X21680Y199859I-2384J-1043D01*
G02X21000Y200145I-280J286D01*
G01Y208000D01*
X27000Y214000D01*
Y220500D01*
X22000Y225500D01*
Y245000D01*
X21000Y246000D01*
X5099D01*
X3099Y248000D01*
Y365650D01*
X6499Y369050D01*
X22749D01*
X24326Y370626D01*
X36654D01*
G03X36521Y373468I2345J1534D01*
G01X30798D01*
G02X30399Y373887I0J400D01*
G03X29085Y376081I-2299J113D01*
G01X29053Y376096D01*
X28249Y376900D01*
Y382613D01*
G03X28610Y383853I-1950J1240D01*
G01Y387629D01*
G03X28249Y388870I-2311J1D01*
G01Y398360D01*
G03X28610Y399600I-1950J1240D01*
G01Y403376D01*
G03X24132Y404180I-2311J0D01*
G01X24084Y404050D01*
X23499D01*
X21999Y405550D01*
Y409150D01*
X22846Y409996D01*
X35305D01*
X35622Y410313D01*
X35715Y410306D01*
G03X37484Y410930I185J2294D01*
G01X40546D01*
G03X42000Y409998I1455J669D01*
G01X43400D01*
G03X43962Y410100I0J1602D01*
G02X44502Y409701I141J-374D01*
G03X44498Y409600I1597J-114D01*
G01Y408200D01*
G03X44587Y407674I1602J1D01*
G01X44598Y407642D01*
Y407164D01*
G03X47819Y404093I1203J-1963D01*
G01Y404094D01*
X47833Y404119D01*
X49002Y405288D01*
Y407609D01*
X49013Y407674D01*
G03X49102Y408200I-1513J527D01*
G01Y409600D01*
G03X48751Y410600I-1602J-1D01*
G03X48954Y410930I-1252J998D01*
G01X49362D01*
X50980Y409312D01*
Y408395D01*
G03X53820Y408832I1750J-1925D01*
G01Y410488D01*
X50538Y413770D01*
X48904D01*
G03X47500Y414602I-1404J-769D01*
G01X46100D01*
G03X45020Y414182I1J-1602D01*
G02X44480I-270J296D01*
G03X43400Y414602I-1081J-1182D01*
G01X42000D01*
G03X40596Y413770I0J-1601D01*
G01X37882D01*
G03X36885Y414680I-1982J-1170D01*
G02X36774Y415325I171J362D01*
G01X37999Y416550D01*
Y463550D01*
X40499Y466050D01*
X65050D01*
X65999Y466999D01*
Y469374D01*
G03X66714Y471116I-1596J1673D01*
G01Y471119D01*
X66708Y474442D01*
Y474450D01*
G03X65999Y476112I-2311J-4D01*
G01Y484460D01*
G03X66910Y486243I-1400J1839D01*
G01Y486244D01*
X67010Y489632D01*
G03X65999Y491612I-2310J68D01*
G01Y493001D01*
X65000Y494000D01*
X41549D01*
X37999Y497550D01*
Y516016D01*
G03X38810Y517774I-1500J1758D01*
G01Y521552D01*
G03X37999Y523309I-2311J-1D01*
G01Y529050D01*
X41999Y533050D01*
X57970D01*
G03X62314Y534218I2033J1100D01*
G01Y534221D01*
X62310Y537547D01*
Y537553D01*
G03X62024Y538665I-2311J-2D01*
G01X61999Y538710D01*
Y539550D01*
X60999Y540550D01*
X38999D01*
X37999Y541550D01*
Y542330D01*
X61162D01*
X64178Y539313D01*
Y516061D01*
G03X67020I1421J-1811D01*
G01Y540489D01*
X62338Y545170D01*
X37999D01*
Y547794D01*
X40656D01*
X40704Y547662D01*
G03X43961Y550475I2163J788D01*
G02X43868Y551110I190J352D01*
G01X44287Y551530D01*
X44485D01*
X44545Y551459D01*
G03X45865Y555211I1754J1491D01*
G02X45391Y555640I-76J393D01*
G03X41028Y556855I-2292J210D01*
G02X40453Y556692I-360J174D01*
G03X38520Y556944I-1236J-1942D01*
G02X37999Y557325I-121J381D01*
G01Y564550D01*
X39499Y566050D01*
X41164D01*
G03X44034I1435J1800D01*
G01X76999D01*
X79045Y568096D01*
G02X79728Y567814I283J-283D01*
G01Y559151D01*
X91532D01*
Y560050D01*
X100499D01*
X103249Y562800D01*
Y597721D01*
G02X103864Y598058I400J0D01*
G03Y601942I1236J1942D01*
G02X103249Y602279I-215J337D01*
G01Y605050D01*
X104999Y606800D01*
X105462D01*
Y606515D01*
X105401Y606456D01*
G03X108948Y603573I1599J-1656D01*
G02X109590Y603620I338J-213D01*
G02X110300Y602604I-4800J-4111D01*
G01Y597286D01*
G03X110196Y596497I2400J-718D01*
G01Y595486D01*
G03X110300Y594697I2504J-71D01*
G01Y591376D01*
G03X110196Y590587I2400J-718D01*
G01Y589576D01*
G03X110300Y588787I2504J-71D01*
G01Y579760D01*
G03X110196Y578971I2400J-718D01*
G01Y577960D01*
G03X110300Y577171I2504J-71D01*
G01Y573850D01*
G03X110196Y573061I2400J-718D01*
G01Y572050D01*
G03X110300Y571261I2504J-71D01*
G01Y567940D01*
G03X110196Y567151I2400J-718D01*
G01Y566140D01*
G03X110300Y565351I2504J-71D01*
G01Y562030D01*
G03X110196Y561241I2400J-718D01*
G01Y560230D01*
G03X110300Y559441I2504J-71D01*
G01Y555550D01*
X108800Y554050D01*
X91532D01*
Y554155D01*
X79728D01*
Y552779D01*
X77999Y551050D01*
Y546550D01*
X79728Y544821D01*
Y544151D01*
X80398D01*
X80499Y544050D01*
X103336D01*
G02X103730Y543583I0J-400D01*
G03X107564Y541511I2270J-383D01*
G01X107622Y541564D01*
X107778D01*
X107836Y541511D01*
G03X111670Y543583I1564J1689D01*
G02X112064Y544050I394J67D01*
G01X113999D01*
X115610Y542438D01*
Y505389D01*
G02X113267Y499733I-7999J0D01*
G37*
G36*
G01X81499Y644852D02*
G02X80859Y644532I-400J0D01*
G03X80670Y644654I-961J-1281D01*
G01Y648388D01*
X76837Y652220D01*
X70412D01*
X70342Y652151D01*
G02X70001Y652292I-141J141D01*
G01Y654602D01*
X63098D01*
Y654455D01*
G02X62388Y654202I-400J0D01*
G03X62367Y654227I-1237J-1018D01*
G02Y654747I304J260D01*
G03X62750Y655785I-1218J1039D01*
G01Y657187D01*
G03X62012Y658536I-1602J0D01*
G01X61920Y658595D01*
Y658751D01*
X62111Y658950D01*
G03X59434Y661113I-112J2600D01*
G01X59451Y661011D01*
X59078Y660638D01*
Y658641D01*
G03X58749Y658438I670J-1454D01*
G03X57883Y658783I-1000J-1251D01*
G01X57810Y658789D01*
X56848Y659752D01*
X44886D01*
G03Y655348I-1387J-2202D01*
G01X54803D01*
X54851Y655219D01*
G03X55131Y654747I1497J569D01*
G02Y654227I-304J-260D01*
G03X54954Y653973I1219J-1038D01*
G01X54940Y653949D01*
X52080Y651088D01*
Y645912D01*
X61080Y636912D01*
Y635480D01*
G03Y631120I1420J-2180D01*
G01Y618989D01*
G02X60642Y618591I-400J0D01*
G03X58750Y618012I-242J-2591D01*
G02X58097Y618345I-254J309D01*
G03X56940Y620668I-2597J156D01*
G01Y632569D01*
X54787Y634722D01*
X54794Y634814D01*
G03X51105Y636831I-2294J186D01*
G02X50510Y636959I-243J318D01*
G03X50282Y637280I-1410J-760D01*
G02Y637820I296J270D01*
G03X50702Y638900I-1182J1081D01*
G01Y640300D01*
G03X50470Y641129I-1602J-1D01*
G03X46921Y641910I-1471J1771D01*
G02X46847Y641655I-181J-86D01*
G03X46700Y641551I850J-1357D01*
G03X45700Y641902I-1001J-1251D01*
G01X44300D01*
G03X44184Y641897I11J-1602D01*
G02X43762Y642371I-29J399D01*
G03X39705Y641359I-2262J429D01*
G02X39679Y641082I-156J-125D01*
G03X39719Y637088I1688J-1980D01*
G02X39767Y636515I-253J-310D01*
G03X39437Y636022I1732J-1516D01*
G01X39258Y635911D01*
X39182Y635926D01*
G03X38384Y636100I-882J-2126D01*
G02X37999Y636500I15J400D01*
G01Y656550D01*
X45000Y663551D01*
Y695408D01*
X47998D01*
G02X48138Y695404I12J-2019D01*
G01X48173Y695258D01*
G03X52709Y695910I2237J544D01*
G01Y695911D01*
X52602Y699237D01*
Y699238D01*
G03X48019Y699513I-2302J-38D01*
G02X47700Y699490I-320J2208D01*
G01X45000D01*
Y702550D01*
X6999D01*
X4999Y704550D01*
Y713458D01*
G02X5688Y713734I400J0D01*
G03Y721688I4155J3977D01*
G02X4999Y721964I-289J276D01*
G01Y758364D01*
G02X5688Y758640I400J0D01*
G03Y766594I4155J3977D01*
G02X4999Y766870I-289J276D01*
G01Y771050D01*
X11999Y778050D01*
X38499D01*
X44466Y784018D01*
X44835D01*
X54868Y794050D01*
X82341D01*
X87612Y788780D01*
X108689D01*
G03Y791620I1811J1420D01*
G01X88788D01*
X87042Y793367D01*
G02X87324Y794050I283J283D01*
G01X107650D01*
X107880Y794280D01*
X108889D01*
G03X112542Y797080I1811J1420D01*
G02X112616Y797635I320J240D01*
G03X112818Y797812I-1414J1817D01*
G02X113499Y797528I281J-284D01*
G01Y763910D01*
X113420Y763820D01*
X85700Y736100D01*
Y666574D01*
X83474D01*
X82499Y667550D01*
X74999D01*
Y665709D01*
G03Y663391I2000J-1159D01*
G01Y660050D01*
X81499Y653550D01*
Y644852D01*
G37*
G36*
G01X113499Y801372D02*
G02X112818Y801088I-400J0D01*
G03X111981Y801615I-1616J-1639D01*
G02X111759Y802171I136J376D01*
G03X111448Y804698I-2059J1029D01*
G02X111458Y804970I152J131D01*
G03X111678Y807973I-1627J1629D01*
G02X111707Y808243I160J119D01*
G03X111887Y811540I-1512J1736D01*
G02X111888Y811811I147J135D01*
G03X108391Y814800I-1686J1568D01*
G01X102700D01*
X98600Y818900D01*
Y820050D01*
G02X98792Y820250I200J0D01*
G03Y824850I-92J2300D01*
G02X98600Y825050I8J200D01*
G01Y827580D01*
X101537D01*
X105960Y832002D01*
X106062Y831985D01*
G03X108418Y832793I437J2565D01*
G02X108977Y832823I295J-270D01*
G03Y836277I1522J1727D01*
G02X108418Y836307I-264J300D01*
G03X103934Y834113I-1919J-1757D01*
G01X103951Y834011D01*
X100361Y830420D01*
X98600D01*
Y831273D01*
X98736Y831319D01*
G03Y835681I-736J2181D01*
G01X98600Y835727D01*
Y840100D01*
G02X98792Y840300I200J0D01*
G03X96889Y844020I-92J2300D01*
G01X95280D01*
X93300Y846000D01*
X91709D01*
X90388Y847320D01*
X78202D01*
G02X77802Y847717I0J400D01*
G03X77586Y848673I-2302J-18D01*
G02X77669Y848932I181J85D01*
G03X76821Y853223I-1129J2006D01*
G02X76477Y853698I48J397D01*
G03X72582Y852532I-2257J452D01*
G02X72307Y851851I-284J-281D01*
G03X70207Y848741I55J-2301D01*
G02X69833Y848200I-374J-141D01*
G01X60200D01*
X49526Y858874D01*
X33174D01*
X30999Y861050D01*
X29362D01*
G02X28962Y861465I0J400D01*
G03X25916Y863728I-2300J85D01*
G02X25418Y863950I-130J378D01*
G03X21444Y861687I-2119J-900D01*
G02X21122Y861050I-322J-237D01*
G01X5450D01*
X3000Y863500D01*
Y1091500D01*
X5500Y1094000D01*
X16500D01*
X18500Y1096000D01*
Y1121000D01*
X16000Y1123500D01*
X4000D01*
X3000Y1124500D01*
Y1180000D01*
X4100Y1181100D01*
X19500D01*
Y1181000D01*
X20000Y1180500D01*
Y1177222D01*
X19993Y1177196D01*
G03Y1175804I2507J-696D01*
G01X20000Y1175778D01*
Y1170722D01*
X19993Y1170696D01*
G03Y1169304I2507J-696D01*
G01X20000Y1169278D01*
Y1165222D01*
X19993Y1165196D01*
G03Y1163804I2507J-696D01*
G01X20000Y1163778D01*
Y1157730D01*
G03Y1154904I1817J-1413D01*
G01Y1153499D01*
X24499Y1149000D01*
Y1089702D01*
X11798D01*
Y1088452D01*
X9423D01*
X9396Y1088460D01*
G03Y1084040I-646J-2210D01*
G01X9423Y1084048D01*
X11798D01*
Y1082798D01*
X24499D01*
Y1071900D01*
X22300Y1069701D01*
Y1063385D01*
X21542Y1062626D01*
X17398D01*
Y1057224D01*
X24300D01*
Y1060434D01*
G02X24983Y1060717I400J0D01*
G01X26266Y1059434D01*
G02X25983Y1058752I-283J-282D01*
G01X24898D01*
Y1053348D01*
X31800D01*
X31891Y1053386D01*
X52580Y1032698D01*
Y1023508D01*
X53973Y1022114D01*
X53956Y1022013D01*
G03X53934Y1021750I1580J-265D01*
G01Y1020350D01*
G03X54344Y1019280I1601J0D01*
G02X54357Y1018761I-298J-267D01*
G03X53998Y1017750I1242J-1010D01*
G01Y1016807D01*
X53238Y1016048D01*
X53128Y1016075D01*
G03X55091Y1013781I-629J-2525D01*
G01X55082Y1013874D01*
X55956Y1014748D01*
X56999D01*
G03X57999Y1015099I-1J1602D01*
G03X58999Y1014748I1001J1251D01*
G01X59187D01*
X64637Y1009298D01*
X65612D01*
X65659Y1009270D01*
G03X66300Y1014006I1341J2230D01*
G01X66188Y1013975D01*
X65792Y1014370D01*
G02X66075Y1015053I283J283D01*
G01X69606D01*
G02X69961Y1014468I0J-400D01*
G03X70509Y1011646I2039J-1068D01*
G01X70580Y1011586D01*
Y1011412D01*
X74912Y1007080D01*
X79170D01*
G03X79337Y1006815I1432J717D01*
G02X79270Y1006255I-315J-246D01*
G03X79151Y1002746I1429J-1805D01*
G02Y1002154I-269J-296D01*
G03X81345Y998240I1548J-1704D01*
G01X81372Y998248D01*
X82641D01*
X82673Y998237D01*
G03X83199Y998148I527J1513D01*
G01X84599D01*
G03X85599Y998499I-1J1602D01*
G03X86599Y998148I1001J1251D01*
G01X87642D01*
X88580Y997211D01*
Y994911D01*
G03X92288Y993355I1420J-1811D01*
G02X92673Y993799I397J44D01*
G03X92857Y993812I-70J2301D01*
G02X93302Y993415I45J-397D01*
G01Y992089D01*
X93372Y992029D01*
G02X93646Y991755I-1485J-1759D01*
G01X93706Y991684D01*
X93999D01*
Y980050D01*
X89499Y975550D01*
X80499D01*
X79499Y974550D01*
Y949550D01*
X80499Y948550D01*
X89999D01*
X90499Y948050D01*
Y946050D01*
X89799Y945350D01*
X87499D01*
X85699Y943550D01*
X70999D01*
X68499Y941050D01*
Y929550D01*
X71499Y926550D01*
X72214D01*
Y926184D01*
X82118D01*
Y926550D01*
X97477D01*
G03X98945Y925588I1468J639D01*
G01X100545D01*
G03X101545Y925938I1J1601D01*
G03X102545Y925588I999J1251D01*
G01X104145D01*
G03X105613Y926550I0J1601D01*
G01X107533D01*
G03X109834Y926058I1567J1700D01*
G01X109951Y926098D01*
X113499Y922550D01*
Y801372D01*
G37*
G36*
G01X12500Y1095500D02*
X4500D01*
X3001Y1096999D01*
Y1121001D01*
X4000Y1122000D01*
X14500D01*
X16500Y1120000D01*
Y1096500D01*
X15500Y1095500D01*
X13500D01*
Y1096500D01*
X12500D01*
Y1095500D01*
G37*
G36*
G01X20176Y1349900D02*
X20209Y1349888D01*
G03X20443Y1349816I793J2161D01*
G01X20497Y1349803D01*
X24600Y1345700D01*
Y1219500D01*
X23200Y1218100D01*
X3801D01*
X3001Y1218900D01*
Y1347701D01*
X5200Y1349900D01*
X20176D01*
G37*
G36*
G01X58230Y1864280D02*
X46601Y1852651D01*
X46518Y1852652D01*
G03X43897Y1850031I-19J-2602D01*
G01X43898Y1849948D01*
X41000Y1847050D01*
X6499D01*
X4999Y1848550D01*
Y1855215D01*
G02X5688Y1855491I400J0D01*
G03Y1863445I4155J3977D01*
G02X4999Y1863721I-289J276D01*
G01Y1890926D01*
G02X5683Y1891207I400J0D01*
G03X34291Y1906717I12037J11937D01*
G02X34965Y1907084I391J84D01*
G01X40366Y1901683D01*
X40381Y1901647D01*
G03X41393Y1900531I2118J903D01*
G01X41418Y1900517D01*
X42337Y1899598D01*
X42450D01*
X48999Y1893050D01*
Y1878050D01*
X51499Y1875550D01*
X74999D01*
X77499Y1873050D01*
Y1864550D01*
X77229Y1864280D01*
X58230D01*
G37*
G36*
G01X117620Y1539486D02*
X102748Y1554359D01*
G02X102889Y1554700I142J141D01*
G01X103200D01*
X109000Y1560500D01*
Y1600000D01*
X110050Y1601050D01*
X158564D01*
G02X158806Y1600332I0J-400D01*
G03X157950Y1598985I1394J-1832D01*
G02X157726Y1598829I-196J42D01*
G03X159650Y1596065I-326J-2279D01*
G02X159874Y1596221I196J-42D01*
G03X161594Y1600332I326J2279D01*
G02X161836Y1601050I242J318D01*
G01X327097D01*
X398890Y1576497D01*
X398825Y1576307D01*
G03X403181Y1574817I2174J-757D01*
G01Y1574818D01*
X403246Y1575007D01*
X850499Y1422050D01*
X884999D01*
X885999Y1423050D01*
Y1447050D01*
X884999Y1448050D01*
X833960D01*
X331060Y1613070D01*
X328101Y1614300D01*
X314830D01*
X314812Y1614282D01*
X207267D01*
X206499Y1615050D01*
Y1629192D01*
X212701D01*
X218020Y1634512D01*
Y1662988D01*
X186548Y1694461D01*
X186565Y1694563D01*
G03X183563Y1697565I-2565J437D01*
G01X183461Y1697548D01*
X181838Y1699170D01*
X180754D01*
G03X179300Y1700102I-1455J-669D01*
G01X177700D01*
G03X177459Y1700083I5J-1602D01*
G02X176999Y1700478I-60J396D01*
G01Y1733750D01*
X173199Y1737550D01*
X146999D01*
X146499Y1738050D01*
X115499D01*
X114999Y1738550D01*
Y1740300D01*
X112150D01*
G02X111750Y1740710I0J400D01*
G01X111778Y1741841D01*
X111780Y1741914D01*
X111820Y1743494D01*
X111817D01*
X111806Y1743682D01*
G03X107753Y1745064I-2307J-132D01*
G02X107181Y1745031I-302J262D01*
G03X106099Y1745452I-1082J-1180D01*
G01X104499D01*
G03X103499Y1745101I1J-1602D01*
G03X102499Y1745452I-1001J-1251D01*
G01X100899D01*
G03X99298Y1743852I0J-1601D01*
G01Y1743242D01*
G02X99199Y1743240I-87J1867D01*
G01X83361D01*
G02X83173Y1743318I0J266D01*
G03X82414Y1743804I-1491J-1493D01*
G01X82373Y1743819D01*
X82244Y1743948D01*
X82118D01*
Y1744761D01*
X72999D01*
Y1746657D01*
X82118D01*
Y1748267D01*
G03X82277Y1748416I-2156J2460D01*
G01X82521Y1748660D01*
X82884D01*
X82899Y1748562D01*
G03X87504Y1748748I2295J287D01*
G01X87651Y1752145D01*
G03X83100Y1752814I-2310J100D01*
G01X83078Y1752740D01*
X82684D01*
X82627Y1752790D01*
G03X82355Y1752980I-926J-1036D01*
G03X82118Y1753095I-1617J-3030D01*
G01Y1754210D01*
X72999D01*
Y1775591D01*
G02X73547Y1775962I400J-1D01*
G03Y1780238I853J2138D01*
G02X72999Y1780609I-148J372D01*
G01Y1783050D01*
X80999Y1791050D01*
X90022D01*
G02X90208Y1790875I-2914J-3283D01*
G01X94515Y1786568D01*
X94987Y1786095D01*
X94989Y1786093D01*
G03X95018Y1786063I1013J951D01*
G02X95109Y1785845I-217J-219D01*
G01Y1785796D01*
X95110Y1785792D01*
Y1782940D01*
X93575D01*
X92782Y1783732D01*
G03X91669Y1784420I-2012J-2010D01*
G01X91532Y1784465D01*
Y1785691D01*
X79728D01*
Y1775687D01*
X91532D01*
Y1777063D01*
G03X92084Y1777459I-1087J2098D01*
G03X92823Y1778707I-1655J1823D01*
G01X92860Y1778860D01*
X95227D01*
G03X97150Y1779349I22J3940D01*
G03X97203Y1779379I-658J1224D01*
G03X99188Y1782799I-1955J3420D01*
G01Y1783411D01*
X99489D01*
X99549Y1783330D01*
G03X103342Y1783465I1850J1370D01*
G02X103962Y1783534I338J-214D01*
G01X110884Y1776612D01*
G02X111210Y1775826I-786J-787D01*
G01Y1769186D01*
G02X110884Y1768400I-1112J1D01*
G01X110649Y1768165D01*
G02X110234Y1767903I-786J786D01*
G02X109700Y1768280I-134J377D01*
G01Y1768350D01*
G03X108099Y1769952I-1602J0D01*
G01X106499D01*
G03X105499Y1769601I1J-1602D01*
G03X104499Y1769952I-1001J-1251D01*
G01X102899D01*
G03X101298Y1768352I0J-1601D01*
G01Y1767761D01*
G02X100794Y1767716I-499J2744D01*
G01X92595D01*
X92557Y1767866D01*
G03X92471Y1768124I-1890J-487D01*
G01X92424Y1768236D01*
G03X91532Y1769216I-1805J-747D01*
G01Y1770691D01*
X79728D01*
Y1760687D01*
X91532D01*
Y1762114D01*
G03X91952Y1762442I-1131J1882D01*
G03X92028Y1762524I-980J985D01*
G03X92385Y1763108I-1672J1423D01*
G01X92451Y1763267D01*
Y1763268D01*
G03X92530Y1763493I-2028J838D01*
G01X92572Y1763636D01*
X96852D01*
G02X97199Y1763039I-1J-400D01*
G03X101479Y1761585I2000J-1140D01*
G02X102080Y1761874I396J-55D01*
G03X102899Y1761648I820J1376D01*
G01X104499D01*
G03X105499Y1761999I-1J1602D01*
G03X106499Y1761648I1001J1251D01*
G01X108099D01*
G03X108148Y1761649I-8J1602D01*
G01X108154D01*
G02X108354Y1761449I0J-200D01*
G01X108310Y1761324D01*
G03X110000Y1762175I1789J-1449D01*
G02X109607Y1762709I-17J399D01*
G03X109700Y1763250I-1509J538D01*
G01Y1763561D01*
G02X109899Y1763761I200J0D01*
G03X113533Y1765279I-34J5191D01*
G01X113770Y1765516D01*
G03X115288Y1769183I-3673J3668D01*
G01Y1775829D01*
G03X113770Y1779496I-5191J-1D01*
G01X102899Y1790367D01*
G02X102999Y1791006I283J283D01*
G01Y1795650D01*
X90399Y1808250D01*
Y1813750D01*
X92399Y1815750D01*
X126499D01*
X138199Y1804050D01*
X160938D01*
G02X161306Y1803494I0J-400D01*
G03X165173Y1797650I3867J-1643D01*
G01X169473D01*
G03X173340Y1803494I0J4201D01*
G02X173708Y1804050I368J156D01*
G01X266499D01*
X291999Y1829550D01*
X871499D01*
X872999Y1828050D01*
X884999D01*
X885999Y1829050D01*
Y1853050D01*
X884999Y1854050D01*
X871499D01*
X870499Y1853050D01*
X843999D01*
X831999Y1841050D01*
X280999D01*
X262499Y1822550D01*
X142499D01*
X138999Y1826050D01*
Y1831432D01*
X143239D01*
X143290Y1831308D01*
G03X143815Y1830520I2226J914D01*
G03X144689Y1829903I2233J2235D01*
G01Y1828483D01*
X156493D01*
Y1838487D01*
X144689D01*
Y1836982D01*
G03X143719Y1836284I1665J-3336D01*
G01X143460Y1836026D01*
G03X143457Y1836023I981J-984D01*
G03X143095Y1835512I1326J-1323D01*
G01X138999D01*
Y1846432D01*
X143613D01*
X143646Y1846274D01*
G03X144221Y1845214I2071J437D01*
G01X144222Y1845213D01*
G03X144689Y1844861I1495J1498D01*
G01Y1843483D01*
X156493D01*
Y1853487D01*
X144689D01*
Y1852028D01*
G03X143692Y1850749I1221J-1980D01*
G01X143676Y1850699D01*
G03X143668Y1850675I1314J-451D01*
G03X143663Y1850656I1547J-417D01*
G01X143621Y1850512D01*
X140515D01*
X140499Y1850550D01*
X134303D01*
X134284Y1850728D01*
G03X132692Y1852156I-1592J-173D01*
G01X131092D01*
G03X130092Y1851805I1J-1602D01*
G03X129092Y1852156I-1001J-1251D01*
G01X127492D01*
G03X125900Y1850728I0J-1601D01*
G01X125881Y1850550D01*
X112349D01*
X109499Y1853400D01*
Y1893351D01*
X114698Y1898550D01*
X134999D01*
X136999Y1896550D01*
X210499D01*
X214524Y1892524D01*
X214500Y1892500D01*
Y1875000D01*
X219500Y1870000D01*
X245500D01*
X252000Y1876500D01*
Y1908500D01*
X252420Y1908920D01*
X252516Y1908909D01*
G03X252700Y1908898I187J1591D01*
G01X254300D01*
G03X254830Y1908989I-2J1602D01*
G01X254862Y1909000D01*
X256452D01*
G03X259725Y1911636I1047J2050D01*
G01X259696Y1911747D01*
X259999Y1912050D01*
X280999D01*
X285249Y1916300D01*
Y1926300D01*
X288499Y1929550D01*
X312137D01*
X312169Y1929539D01*
G03X312699Y1929448I532J1511D01*
G01X314299D01*
G03X314829Y1929539I-2J1602D01*
G01X314861Y1929550D01*
X323499D01*
X325999Y1932050D01*
Y1936886D01*
G03X326563Y1938994I-2000J1665D01*
G01X326545Y1939096D01*
X327499Y1940050D01*
X342999D01*
X345499Y1942550D01*
Y1948050D01*
X344998Y1948551D01*
X344985Y1948573D01*
G03X344163Y1949395I-1986J-1164D01*
G01X344141Y1949408D01*
X342499Y1951050D01*
X340450D01*
X338500Y1953000D01*
Y1958000D01*
X340500Y1960000D01*
Y1975000D01*
X339000Y1976500D01*
X321049D01*
X315999Y1981550D01*
X253499D01*
X251974Y1980026D01*
X246026D01*
X241000Y1975000D01*
Y1961050D01*
X239500Y1959550D01*
X217499D01*
X215499Y1961550D01*
X200999D01*
X196423Y1956974D01*
X143874D01*
X142499Y1958350D01*
Y1979501D01*
X138500Y1983500D01*
X121700D01*
X121600Y1983400D01*
X116100D01*
X106700Y1974000D01*
X97500D01*
X95400Y1971900D01*
X55100D01*
X53000Y1974000D01*
Y1974048D01*
X50499Y1976550D01*
X48539D01*
X48002Y1977088D01*
X46011D01*
G03X43283Y1977116I-1387J-2202D01*
G01X43236Y1977088D01*
X42745D01*
X42208Y1976550D01*
X41499D01*
X39750Y1974802D01*
X39749D01*
X39499Y1974552D01*
X39387D01*
X39386Y1974550D01*
X35999D01*
X35499Y1975050D01*
Y1980050D01*
X34499Y1981050D01*
X32939D01*
G03X30703Y1981074I-1140J-2000D01*
G01X30658Y1981050D01*
X30499D01*
X29499Y1980050D01*
Y1979142D01*
G03Y1978958I2300J-92D01*
G01Y1977550D01*
X27931Y1975982D01*
X27814Y1976021D01*
G03X25335Y1975550I-815J-2471D01*
G01X21788D01*
Y1976252D01*
X18386D01*
Y1975550D01*
X8000D01*
X6000Y1977550D01*
Y1986500D01*
X8500Y1989000D01*
X1029500D01*
X1030399Y1988101D01*
Y1744601D01*
X1030400Y1744600D01*
Y1697400D01*
X1028360Y1695360D01*
G02X1027682Y1695578I-283J282D01*
G03X1017925Y1685821I-8391J-1366D01*
G02X1018143Y1685143I-64J-395D01*
G01X1015700Y1682700D01*
Y1676300D01*
X1013900Y1674500D01*
X974000D01*
X971500Y1672000D01*
Y1668402D01*
X969700D01*
G03X968098Y1666800I0J-1602D01*
G01Y1664200D01*
G03X968506Y1663133I1602J1D01*
G02Y1662867I-150J-133D01*
G03X968098Y1661800I1194J-1068D01*
G01Y1659200D01*
G03X969700Y1657598I1602J0D01*
G01X971500D01*
Y1651000D01*
X972500Y1650000D01*
X979365D01*
G02X979762Y1649556I-1J-400D01*
G03X984352Y1649285I2288J-254D01*
G02X984752Y1649682I400J-3D01*
G01X989318D01*
X991500Y1647500D01*
X1015200D01*
X1015900Y1646800D01*
X1016000D01*
Y1645200D01*
X1015300Y1644500D01*
X974000D01*
X972220Y1642720D01*
X966362D01*
X964944Y1641303D01*
X964823Y1641350D01*
G03X961701Y1639091I-823J-2150D01*
G02X961242Y1638676I-400J-19D01*
G03X962432Y1634682I-342J-2276D01*
G01X985188D01*
X986086Y1635580D01*
X990920D01*
X993106Y1633395D01*
Y1633300D01*
X993200D01*
X994000Y1632500D01*
X1015100D01*
X1016000Y1631600D01*
Y1625200D01*
X1015300Y1624500D01*
X989802D01*
G02X989402Y1624900I0J400D01*
G03X984876Y1624307I-2302J0D01*
G02X984490Y1623804I-386J-103D01*
G01X983379D01*
G02X983057Y1624440I1J400D01*
G03X979343I-1857J1360D01*
G02X979021Y1623804I-323J-236D01*
G01X956217D01*
X952010Y1628010D01*
G03X948190Y1624190I-1910J-1910D01*
G01X953979Y1618400D01*
X983000D01*
X984500Y1616900D01*
Y1611900D01*
X987600Y1608800D01*
X1014000D01*
X1016100Y1606700D01*
Y1514700D01*
X1015100Y1513700D01*
X950200D01*
X944500Y1508000D01*
Y1434300D01*
X949800Y1429000D01*
X1017100D01*
X1020300Y1425800D01*
X1028300D01*
X1030000Y1424100D01*
Y4000D01*
X1029000Y3000D01*
X139725D01*
G02X139499Y3730I0J400D01*
G03X139329Y31817I-9579J13986D01*
G02X139550Y32550I222J333D01*
G01X177999D01*
X180499Y30050D01*
Y18550D01*
X183499Y15550D01*
X209999D01*
X220999Y26550D01*
X233499D01*
X234798Y27848D01*
X234997D01*
X237200Y30052D01*
Y30252D01*
X237500Y30551D01*
Y71352D01*
X240079Y73931D01*
X240211Y73856D01*
G03X240999Y73648I789J1394D01*
G01X243599D01*
G03X244923Y74348I0J1602D01*
G01X248526D01*
X252316Y78138D01*
Y89347D01*
X250999Y90663D01*
Y105550D01*
X237999Y118550D01*
X198499D01*
X195999Y121050D01*
X191293D01*
X191263Y121214D01*
G03X188353Y123010I-2265J-414D01*
G01X188326Y123002D01*
X186597D01*
X186574Y123007D01*
G03X186199Y123052I-377J-1557D01*
G01X184799D01*
G03X183198Y121452I0J-1601D01*
G01Y121050D01*
X121999D01*
X119499Y123550D01*
Y149450D01*
X113499Y155450D01*
Y163750D01*
X113549Y163800D01*
Y166700D01*
X113499Y166750D01*
Y196050D01*
X115999Y198550D01*
X153999D01*
X157999Y202550D01*
Y230050D01*
X156499Y231550D01*
X123499D01*
X121600Y233449D01*
Y246559D01*
G02X122118Y246941I400J0D01*
G03X124418Y247500I681J2209D01*
G01X125984D01*
G03X127399Y246648I1415J749D01*
G01X128999D01*
G03X129999Y246999I-1J1602D01*
G03X130999Y246648I1001J1251D01*
G01X132599D01*
G03X134014Y247500I0J1601D01*
G01X154103D01*
Y247365D01*
X164007D01*
Y254918D01*
X154103D01*
Y253880D01*
G03X153215Y253282I1098J-2588D01*
G01X153144Y253212D01*
X152840Y252909D01*
G02X152816Y252889I-99J94D01*
G02X152744Y252868I-73J116D01*
G01X134200D01*
Y253350D01*
G03X132599Y254952I-1602J0D01*
G01X130999D01*
G03X129999Y254601I1J-1602D01*
G03X128999Y254952I-1001J-1251D01*
G01X127399D01*
G03X125935Y254000I0J-1602D01*
G01X124300D01*
G03X122186Y254990I-1903J-1312D01*
G02X121750Y255388I-36J398D01*
G01Y412350D01*
X127800Y418400D01*
X133349D01*
X134749Y419800D01*
X142001D01*
G02X142400Y419420I0J-400D01*
G03X147552Y419046I2599J129D01*
G01X147563Y419106D01*
X149420Y420962D01*
Y421970D01*
X149999Y422550D01*
Y423262D01*
X150000D01*
Y428551D01*
X150499Y429050D01*
X153289D01*
X154718Y427622D01*
X154650Y427492D01*
G03X159188Y424949I2309J-1200D01*
G02X159859Y424970I342J-207D01*
G03X160699Y424196I2140J1480D01*
G02Y423503I-200J-346D01*
G03X163862Y419433I1300J-2254D01*
G02X164548Y419154I286J-279D01*
G01Y418662D01*
X164419Y418533D01*
X164394Y418519D01*
G03X167519Y415394I1106J-2019D01*
G01X167533Y415419D01*
X168952Y416838D01*
Y417614D01*
G02X169401Y418011I400J0D01*
G03X169600Y417998I204J1589D01*
G01X171000D01*
G03X172468Y418959I0J1602D01*
G01X172520Y419080D01*
X174170D01*
G03X174959Y418332I1431J719D01*
G01X175079Y418280D01*
Y416802D01*
X173298D01*
G02X172646Y416516I-399J24D01*
G03Y412484I-1646J-2016D01*
G02X173298Y412198I253J-310D01*
G01X179702D01*
Y416802D01*
X177920D01*
Y417918D01*
G02X178456Y418294I400J0D01*
G03X179000Y418198I546J1506D01*
G01X180400D01*
G03X181561Y418697I-1J1602D01*
G02X182121Y418717I290J-275D01*
G03X183200Y418298I1080J1183D01*
G01X184800D01*
G03X186003Y418843I-1J1602D01*
G01X186153Y418911D01*
X186280Y418865D01*
G03X186580Y418670I1017J1237D01*
G01Y417588D01*
X185793Y416802D01*
X182298D01*
Y412198D01*
X188702D01*
Y415693D01*
X189420Y416412D01*
Y418670D01*
G03X190302Y420100I-720J1431D01*
G01Y421500D01*
G03X189951Y422500I-1602J-1D01*
G03X190302Y423500I-1251J1001D01*
G01Y424900D01*
G03X190293Y425060I-1601J-10D01*
G02X190691Y425500I398J40D01*
G01X206000D01*
X211999Y431499D01*
Y475550D01*
X202999Y484550D01*
Y498050D01*
X199499Y501550D01*
X195704D01*
X195680Y501556D01*
G03X195300Y501602I-381J-1556D01*
G01X193700D01*
G03X193320Y501556I1J-1602D01*
G01X193296Y501550D01*
X188099D01*
X186499Y503150D01*
Y508050D01*
X187999Y509550D01*
X209000D01*
X210450Y511000D01*
X210638D01*
X210670Y510989D01*
G03X211200Y510898I532J1511D01*
G01X212800D01*
G03X214402Y512500I0J1602D01*
G01Y513393D01*
X214861Y513852D01*
X214963Y513835D01*
G03X217580Y514980I437J2565D01*
G01X218189D01*
G03Y517820I1811J1420D01*
G01X217580D01*
G03X212835Y515963I-2180J-1420D01*
G01X212852Y515861D01*
X212693Y515702D01*
X211200D01*
G03X210525Y515552I2J-1602D01*
G01X210485Y515534D01*
X210016D01*
X208999Y516550D01*
Y524550D01*
X209360Y524912D01*
X209497D01*
X211200Y526615D01*
Y540111D01*
X200186Y551126D01*
G02X200384Y551800I283J283D01*
G03X197650Y554534I-484J2250D01*
G02X196976Y554336I-391J85D01*
G01X196497Y554814D01*
X188001D01*
X185298Y552111D01*
Y537500D01*
G03X185297Y534726I2201J-1388D01*
G01Y533000D01*
G03X184992Y530917I2202J-1386D01*
G01X184999Y530891D01*
Y524550D01*
X183999Y523550D01*
X180999D01*
X180779Y523770D01*
X180790Y523866D01*
G03X180800Y524050I-1591J179D01*
G01Y525652D01*
G03X180667Y526290I-1601J-1D01*
G01X180650Y526328D01*
Y529912D01*
X178321Y532241D01*
G02X178657Y532921I282J283D01*
G03X179562Y538041I344J2579D01*
G01X179505Y538053D01*
X178587Y538970D01*
X178411D01*
G02X178270Y539312I0J200D01*
G01X178960Y540002D01*
X179062Y539985D01*
G03X176934Y542113I437J2565D01*
G01X176951Y542011D01*
X175836Y540896D01*
X171058D01*
G02X170775Y541578I0J400D01*
G01X172978Y543781D01*
Y545266D01*
X173459D01*
Y553670D01*
X167856D01*
Y554501D01*
X165273Y557085D01*
X165284Y557181D01*
G03X164392Y559567I-2784J319D01*
G02X164334Y560091I270J295D01*
G03X164372Y560158I-328J230D01*
G01X164555Y560277D01*
X164743Y560143D01*
G03X168705Y563123I2457J857D01*
G01X168620Y563182D01*
Y563557D01*
X173200D01*
Y564526D01*
X174265D01*
X174498Y564293D01*
Y563807D01*
X172580Y561889D01*
Y560110D01*
G02X172182Y559710I-400J0D01*
G03X174764Y557545I17J-2602D01*
G01X174747Y557647D01*
X175141Y558041D01*
G02X175767Y557963I283J-283D01*
G03X180179Y557880I2232J1337D01*
G01X181069D01*
G03X181544Y557315I1430J720D01*
G03X185761Y556525I1955J-1215D01*
G02X186153Y556998I393J73D01*
G01X186942D01*
X187311Y556630D01*
X191819D01*
G03X195920Y559806I2180J1421D01*
G01Y561824D01*
X197000D01*
Y565630D01*
X198003D01*
G02X198402Y565206I-1J-400D01*
G03X202298Y567305I2597J-156D01*
G02X202220Y567939I200J346D01*
G03X197939Y570609I-1803J1876D01*
G01X197895Y570470D01*
X189500D01*
Y571102D01*
X182500D01*
Y572750D01*
G03X180899Y574352I-1602J0D01*
G01X179499D01*
G03X179299Y574339I4J-1602D01*
G01X179202Y574327D01*
X179108Y574420D01*
Y574573D01*
X199476Y594940D01*
X350499D01*
G03Y599660I0J2360D01*
G01X197522D01*
X174390Y576527D01*
Y572050D01*
G03X174472Y571431I2359J-2D01*
G02X174156Y571388I-174J98D01*
G01X172046Y573498D01*
X159702D01*
G02X159302Y573891I0J400D01*
G03X159182Y574586I-2302J-40D01*
G01X159171Y574617D01*
Y574850D01*
X159588D01*
X159639Y574798D01*
X160151D01*
X160178Y574790D01*
G03X161496Y579202I646J2210D01*
G01X161448Y579216D01*
X161412Y579252D01*
X161299D01*
X161280Y579256D01*
G03X160368I-456J-2256D01*
G01X160349Y579252D01*
X154713D01*
X148848Y573387D01*
Y567811D01*
X152810Y563848D01*
X153041D01*
X153073Y563837D01*
G03X153599Y563748I527J1513D01*
G01X154999D01*
G03X155054Y563749I-2J1602D01*
G02X155425Y563170I14J-400D01*
G03X158618Y559547I2324J-1170D01*
G02X159143Y559251I133J-377D01*
G01X159236Y559185D01*
G02X159892Y558525I-1488J-2135D01*
G03X163355Y554832I2608J-1025D01*
G01X163471Y554869D01*
X164575Y553765D01*
X164535Y553670D01*
Y545266D01*
X166792D01*
G02X167074Y544583I-1J-400D01*
G01X166912Y544420D01*
X159800D01*
Y544951D01*
G03X158970Y546354I-1601J0D01*
G01Y547733D01*
X158979Y547762D01*
G03X154297Y547164I-2480J788D01*
G02X153958Y546552I-339J-212D01*
G01X153399D01*
G03X152596Y546336I0J-1601D01*
G02X152336Y546388I-101J173D01*
G03X149854Y547210I-1837J-1388D01*
G01X149827Y547202D01*
X148458D01*
X148426Y547213D01*
G03X148222Y547269I-525J-1513D01*
G01X148062Y547302D01*
Y548298D01*
X149629D01*
X153329Y551998D01*
X155363D01*
G03Y556002I1137J2002D01*
G01X151671D01*
X148745Y553075D01*
G02X148062Y553358I-283J283D01*
G01Y553502D01*
X144920D01*
Y554498D01*
X148062D01*
Y562769D01*
X142929Y567902D01*
X142438D01*
X142394Y567926D01*
G03X139661Y564284I-1094J-2026D01*
G02X139607Y563677I-285J-281D01*
G03X138938Y560664I1333J-1877D01*
G01Y556199D01*
G02X138520Y555800I-400J0D01*
G03X137976Y555759I-100J-2300D01*
G02X137499Y556151I-77J393D01*
G01Y614638D01*
G02X137942Y615035I400J-1D01*
G03X140496Y614896I2563J23552D01*
G01X143592D01*
X143605Y614711D01*
G03X144689Y613190I1785J125D01*
G01Y611947D01*
X156493D01*
Y621951D01*
X144689D01*
Y620418D01*
G03X143684Y619121I1111J-1899D01*
G01X143643Y618976D01*
X140493D01*
G02X137499Y619206I1J19611D01*
G01Y628608D01*
X137515Y628645D01*
G03X137640Y629265I-1477J620D01*
G01Y629870D01*
G02X137994Y629896I356J-2423D01*
G01X143591D01*
X143607Y629714D01*
G03X144117Y628618I1759J152D01*
G01X144118Y628617D01*
G03X144689Y628225I1346J1349D01*
G01Y626947D01*
X156493D01*
Y636951D01*
X144689D01*
Y635369D01*
G03X143858Y634336I1341J-1930D01*
G01X143709Y633976D01*
X137640D01*
Y634365D01*
G03X137515Y634985I-1602J0D01*
G01X137499Y635022D01*
Y653108D01*
X137515Y653145D01*
G03X137640Y653765I-1477J620D01*
G01Y654482D01*
G02X138768Y654660I1131J-3502D01*
G01X153334D01*
G03X154103Y653896I1649J890D01*
G01Y652877D01*
X164007D01*
Y660430D01*
X154103D01*
Y659441D01*
G03X153296Y658740I761J-1691D01*
G01X137646D01*
X137638Y658931D01*
G03X137515Y659485I-1600J-65D01*
G01X137499Y659522D01*
Y677050D01*
X141049Y680600D01*
X217000D01*
Y680500D01*
X220078Y677422D01*
Y667313D01*
X227312Y660080D01*
X235188D01*
X255407Y680298D01*
G02X256058Y679858I283J-283D01*
G03X279417Y688294I15599J-6635D01*
G02X279600Y689050I183J356D01*
G01X310499D01*
Y689130D01*
X326587D01*
X350221Y712763D01*
X350313Y712756D01*
G03X348205Y714864I186J2294D01*
G01X348212Y714772D01*
X325411Y691970D01*
X310499D01*
Y694437D01*
X327200Y711138D01*
Y725050D01*
X345499D01*
X464499Y606050D01*
X558499D01*
X563999Y611550D01*
Y626550D01*
X557999Y632550D01*
X481499D01*
X372999Y741050D01*
X337499D01*
X337000Y741548D01*
Y741750D01*
G03X336999Y741815I-1601J8D01*
G01Y744285D01*
G03X337000Y744350I-1600J57D01*
G01Y745750D01*
G03X336999Y745815I-1601J8D01*
G01Y747050D01*
X330999Y753050D01*
X328999D01*
X324060Y757988D01*
Y762552D01*
X323998D01*
X321500Y765048D01*
Y770048D01*
X321214Y770335D01*
X321331Y770475D01*
G03X321333Y770478I-1324J885D01*
G02X321631Y770490I154J-127D01*
G03X321669Y774148I1869J1810D01*
G02X321130Y774126I-282J284D01*
G03X320100Y774502I-1031J-1226D01*
G01X318998D01*
X318500Y775000D01*
Y778500D01*
X322500Y782500D01*
X323500D01*
X324068Y783068D01*
X324185Y783029D01*
G03Y787971I815J2471D01*
G01X324068Y787932D01*
X323500Y788500D01*
X306000D01*
X305274Y787774D01*
X305145Y787836D01*
G03X304087Y782899I-1145J-2336D01*
G02X304500Y782500I13J-400D01*
G01Y778500D01*
X303550Y777550D01*
X251050D01*
X242000Y768500D01*
Y758050D01*
X241000Y757050D01*
X183499D01*
X169499Y743050D01*
X162170D01*
G02X161858Y743700I0J400D01*
G03X153490Y745134I-3787J3032D01*
G02X152830Y744719I-377J-132D01*
G01X152499Y745050D01*
Y793550D01*
X158499Y799550D01*
X176999D01*
X181999Y804550D01*
Y819828D01*
X182006Y819854D01*
G03Y821246I-2507J696D01*
G01X181999Y821272D01*
Y824386D01*
G03Y827714I-2000J1664D01*
G01Y829551D01*
X185078D01*
Y813413D01*
X191412Y807080D01*
X219088D01*
X238920Y826911D01*
Y897870D01*
G03Y902230I-1421J2180D01*
G01Y907339D01*
X238402Y907857D01*
Y909000D01*
G03X236800Y910602I-1602J0D01*
G01X235657D01*
X232451Y913808D01*
Y917065D01*
X227500D01*
Y920500D01*
X225000Y923000D01*
X200500D01*
X193500Y916000D01*
X184999D01*
X182726Y918272D01*
Y919702D01*
G03X181999Y921244I-2001J-1D01*
G01Y922036D01*
G02X182532Y922413I400J0D01*
G03X183200Y922298I669J1887D01*
G01X184600D01*
G03X186565Y923918I0J2002D01*
G01X186596Y924080D01*
X192620D01*
G03Y926920I2180J1420D01*
G01X186602D01*
Y927200D01*
G03X185320Y929067I-2002J-1D01*
G01Y929525D01*
G03X186102Y930900I-819J1376D01*
G01Y932300D01*
G03X185783Y933259I-1601J0D01*
G02X186103Y933898I320J239D01*
G01X188462D01*
Y935098D01*
X210298D01*
Y925615D01*
X212001Y923912D01*
X232497D01*
X234700Y926115D01*
Y943611D01*
X226497Y951814D01*
X213001D01*
X210298Y949111D01*
Y939102D01*
X188462D01*
Y940302D01*
X185320D01*
Y941298D01*
X188462D01*
Y943671D01*
X188502Y943711D01*
Y949329D01*
X186329Y951502D01*
X181999D01*
Y960130D01*
X182687D01*
X183356Y960798D01*
X184399D01*
G03X185399Y961149I-1J1602D01*
G03X186399Y960798I1001J1251D01*
G01X187799D01*
G03X188774Y961130I-1J1602D01*
G01X191369D01*
G03X194970Y964730I2180J1420D01*
G01Y965524D01*
X197000D01*
Y969630D01*
X197819D01*
G03Y972470I2180J1420D01*
G01X190411D01*
X190183Y972243D01*
G02X189501Y972526I-282J283D01*
G01Y974802D01*
X189420D01*
Y979616D01*
G03X186578Y980294I-921J2434D01*
G01Y974802D01*
X182598D01*
Y973520D01*
X182235D01*
X182195Y973668D01*
G03X181999Y974112I-1546J-417D01*
G01Y974988D01*
G03X182250Y975847I-1350J861D01*
G01Y977253D01*
G03X181999Y978112I-1601J-2D01*
G01Y998052D01*
X255642Y1071696D01*
G02X256288Y1071581I283J-283D01*
G03X257346Y1087821I15369J7153D01*
G02X256608Y1088035I-338J214D01*
G01Y1089855D01*
X270800Y1104047D01*
Y1120046D01*
X284127Y1133373D01*
G03X280873Y1136627I-1627J1627D01*
G01X266984Y1122739D01*
G02X266302Y1123022I-282J283D01*
G01Y1126303D01*
X271502Y1131503D01*
Y1134363D01*
G03X267474Y1134406I-2002J1137D01*
G01X267498Y1134362D01*
Y1133161D01*
X262298Y1127961D01*
Y1108310D01*
X245490Y1091502D01*
X238957D01*
X238040Y1090584D01*
G02X237373Y1090756I-283J283D01*
G03X235450Y1092202I-1923J-556D01*
G01X232550D01*
G03X230548Y1090200I0J-2002D01*
G01Y1088800D01*
G03X230910Y1087653I2002J1D01*
G01X231006Y1087515D01*
X229784Y1086293D01*
G02X229102Y1086576I-282J283D01*
G01Y1087300D01*
G03X228751Y1088300I-1602J-1D01*
G03X229102Y1089300I-1251J1001D01*
G01Y1090700D01*
G03X229013Y1091226I-1602J-1D01*
G01X229001Y1091258D01*
Y1092727D01*
X229010Y1092754D01*
G03X224590I-2210J646D01*
G01X224598Y1092727D01*
Y1092361D01*
X224358D01*
X224321Y1092376D01*
G03X223700Y1092502I-623J-1476D01*
G01X222100D01*
G03X220834Y1091881I0J-1601D01*
G02X220175Y1091921I-316J245D01*
G03X218800Y1092702I-1375J-820D01*
G01X216200D01*
G03X214883Y1092012I0J-1602D01*
G02X214294Y1091936I-329J228D01*
G03X210420Y1091382I-1694J-1975D01*
G01X156492D01*
Y1092462D01*
X144690D01*
Y1087460D01*
X156492D01*
Y1088540D01*
X210420D01*
G03X214181Y1087894I2180J1421D01*
G02X214779Y1087761I243J-317D01*
G03X215140Y1087300I1420J740D01*
G02Y1086700I-265J-300D01*
G03X214598Y1085500I1060J-1201D01*
G01Y1082900D01*
G03X215915Y1081324I1601J0D01*
G01X216080Y1081294D01*
Y1070593D01*
X218793Y1067880D01*
X219989D01*
G03X220240Y1070993I1811J1421D01*
G02X219686Y1071004I-271J294D01*
G01X218920Y1071769D01*
Y1081294D01*
X219085Y1081324D01*
G03X220402Y1082900I-284J1576D01*
G01Y1085500D01*
G03X219860Y1086700I-1602J-1D01*
G02Y1087300I265J300D01*
G03X220320Y1087996I-1060J1200D01*
G02X220980Y1088156I380J-126D01*
G03X222100Y1087698I1121J1143D01*
G01X223243D01*
X224498Y1086443D01*
Y1086257D01*
X223880Y1085638D01*
Y1085493D01*
X223080Y1084693D01*
Y1084608D01*
X222987Y1084549D01*
G03X222248Y1083200I862J-1349D01*
G01Y1081800D01*
G03X222455Y1081014I1602J2D01*
G02X222382Y1080743I-174J-98D01*
G03X226272Y1078108I1318J-2243D01*
G01X226282Y1078173D01*
X228307Y1080198D01*
X228650D01*
G03X230252Y1081800I0J1602D01*
G01Y1082743D01*
X234307Y1086798D01*
X235450D01*
G03X235532Y1086800I-8J2002D01*
G02X235948Y1086401I16J-399D01*
G01Y1080221D01*
X239187Y1076983D01*
G02X238904Y1076300I-283J-283D01*
G01X229000D01*
X227400Y1074700D01*
Y1074150D01*
G02X227004Y1073750I-400J0D01*
G03X227790Y1068660I24J-2602D01*
G01X227905Y1068695D01*
X230900Y1065700D01*
X231228D01*
X231265Y1065548D01*
G03X235706Y1065441I2235J552D01*
G01X235720Y1065490D01*
X235931Y1065700D01*
X239712D01*
X239744Y1065540D01*
G03X240786Y1064044I2256J460D01*
G02X240858Y1063421I-211J-340D01*
G01X182682Y1005245D01*
G02X181999Y1005527I-283J283D01*
G01Y1006100D01*
X173100Y1014999D01*
Y1061000D01*
X168600Y1065500D01*
X164006D01*
Y1065942D01*
X155600D01*
Y1067459D01*
X156493D01*
Y1082463D01*
X144689D01*
Y1081700D01*
X140500D01*
X140000Y1082200D01*
Y1092500D01*
X136420Y1096080D01*
Y1100388D01*
X131300Y1105508D01*
Y1118500D01*
X131328Y1118528D01*
X144690D01*
Y1117460D01*
X156492D01*
Y1122462D01*
X144690D01*
Y1121368D01*
X135134D01*
G02X134851Y1122051I0J400D01*
G01X136116Y1123316D01*
G02X136725Y1123265I283J-283D01*
G03X140486Y1125921I1875J1335D01*
G02X140813Y1126550I328J229D01*
G01X155999D01*
X157499Y1128050D01*
Y1141550D01*
X141000Y1158049D01*
Y1175500D01*
X138950Y1177550D01*
X100999D01*
X96499Y1182050D01*
X81999D01*
X73499Y1190550D01*
Y1209550D01*
X85499Y1221550D01*
Y1225522D01*
X85528Y1225570D01*
G03X87995Y1231546I-18049J10948D01*
G01X87999Y1231550D01*
X92499D01*
Y1235050D01*
X93999Y1236550D01*
X132499D01*
X133499Y1235550D01*
Y1231550D01*
X132999Y1231050D01*
X126499D01*
X124999Y1229550D01*
Y1225050D01*
X125198Y1224852D01*
Y1224809D01*
X124248Y1223860D01*
X124156Y1223867D01*
G03X125426Y1219790I-186J-2294D01*
G02X126078Y1219480I252J-310D01*
G01Y1218115D01*
X120097D01*
Y1217534D01*
X118974D01*
X118602Y1217162D01*
G02X117919Y1217445I-283J283D01*
G01Y1221783D01*
G03X118800Y1223213I-720J1430D01*
G01Y1224615D01*
G03X118450Y1225613I-1601J-1D01*
G03X118800Y1226611I-1251J999D01*
G01Y1228013D01*
G03X117199Y1229614I-1601J0D01*
G01X115799D01*
G03X114450Y1228876I0J-1602D01*
G01X114391Y1228784D01*
X114107D01*
X114048Y1228876D01*
G03X112699Y1229614I-1349J-864D01*
G01X111298D01*
G03X109895Y1228784I0J-1601D01*
G01X109103D01*
G03X107700Y1229614I-1403J-771D01*
G01X106298D01*
G03X104895Y1228784I0J-1601D01*
G01X101224D01*
X101038Y1228598D01*
X100936Y1228615D01*
G03X101013Y1223499I-437J-2565D01*
G02X101476Y1223219I79J-392D01*
G03X104332Y1221653I2210J644D01*
G01X104359Y1221662D01*
X105901D01*
X105924Y1221656D01*
G03X106299Y1221612I373J1557D01*
G01X107699D01*
G03X109139Y1222513I0J1601D01*
G02X109859I360J-175D01*
G03X110578Y1221783I1440J700D01*
G01Y1220464D01*
X110058D01*
Y1215117D01*
X109911Y1214970D01*
X108940D01*
Y1215945D01*
X108957Y1215983D01*
G03X108940Y1217780I-2018J879D01*
G01Y1220464D01*
X104938D01*
Y1219064D01*
X104672D01*
X104645Y1219073D01*
G03X101714Y1216584I-646J-2210D01*
G02X101275Y1216137I-397J-49D01*
G03X103179Y1212130I-276J-2587D01*
G01X104937D01*
Y1207651D01*
G03X104241Y1206970I1225J-1949D01*
G01X100411D01*
X98578Y1205138D01*
Y1204730D01*
G03X101525Y1200442I1421J-2180D01*
G01X103345D01*
G03X103548Y1200113I1454J670D01*
G03X103203Y1199247I1251J-1000D01*
G01X103197Y1199174D01*
X102294Y1198271D01*
X102245Y1198257D01*
G03X103546Y1193840I655J-2207D01*
G01X103573Y1193848D01*
X104098D01*
X104172Y1193923D01*
G02X104832Y1193775I283J-283D01*
G03X104928Y1193545I2169J770D01*
G02X104568Y1192970I-360J-175D01*
G01X82587D01*
X79286Y1196272D01*
X79293Y1196364D01*
G03X77185Y1194256I-2294J186D01*
G01X77277Y1194263D01*
X81411Y1190130D01*
X115087D01*
X116920Y1191962D01*
Y1195370D01*
G03X117633Y1199039I-1421J2180D01*
G01X117597Y1199090D01*
Y1199469D01*
X116605Y1200462D01*
X116409D01*
X113587Y1203284D01*
X111603D01*
G03X110920Y1203943I-1404J-771D01*
G01Y1206761D01*
X111501D01*
Y1212543D01*
X112219Y1213262D01*
X114060D01*
Y1220464D01*
X113420D01*
Y1221783D01*
G03X113939Y1222200I-722J1430D01*
G02X114559I310J-253D01*
G03X115078Y1221783I1241J1013D01*
G01Y1215005D01*
X115066Y1214971D01*
G03X119404Y1212278I2433J-920D01*
G02X120097Y1212006I293J-272D01*
G01Y1211551D01*
X121878D01*
Y1209887D01*
X121539Y1209548D01*
X121437Y1209565D01*
G03X123565Y1207437I-437J-2565D01*
G01X123548Y1207539D01*
X124720Y1208711D01*
Y1211551D01*
X126080D01*
Y1209680D01*
G03X127937Y1204935I1420J-2180D01*
G01X128039Y1204952D01*
X128448Y1204543D01*
G02X128307Y1204202I-141J-141D01*
G01X127673D01*
X127646Y1204210D01*
G03X126000Y1199927I-646J-2210D01*
G01Y1198402D01*
G03X125886Y1193649I1000J-2402D01*
G01X126000Y1193595D01*
Y1193500D01*
X126500Y1193000D01*
X146500D01*
X147226Y1193726D01*
X147355Y1193664D01*
G03X149150Y1198519I1145J2336D01*
G01X149000Y1198558D01*
Y1200483D01*
X151098Y1202581D01*
Y1206559D01*
G02X150874Y1206654I903J2441D01*
G03X150593Y1206678I-172J-361D01*
G02X150116Y1206906I-109J385D01*
G03X147354Y1208210I-2116J-906D01*
G01X147327Y1208202D01*
X144875D01*
G03X144100Y1208402I-775J-1402D01*
G01X142500D01*
G03X142369Y1208396I8J-1602D01*
G02X141950Y1208896I-32J399D01*
G03X142002Y1209300I-1550J405D01*
G01Y1210700D01*
G03X141504Y1211860I-1602J-1D01*
G02X141779Y1212550I276J290D01*
G01X174999D01*
X178499Y1216050D01*
Y1268001D01*
X176000Y1270500D01*
Y1274000D01*
X176420Y1274420D01*
X176516Y1274409D01*
G03X176700Y1274398I187J1591D01*
G01X178300D01*
G03X179754Y1275330I-1J1601D01*
G01X180198D01*
X180223Y1275159D01*
G03X182314Y1277794I2277J341D01*
G01X182222Y1277787D01*
X181838Y1278170D01*
X179802D01*
X179748Y1278285D01*
G03X178655Y1279162I-1448J-685D01*
G01X178499Y1279197D01*
Y1283500D01*
X183499Y1288500D01*
Y1309050D01*
X181999Y1310550D01*
X152500D01*
X150750Y1308800D01*
X143907D01*
X143882Y1308807D01*
G03X143467Y1308862I-416J-1547D01*
G01X141867D01*
G03X141452Y1308807I1J-1602D01*
G01X141427Y1308800D01*
X134874D01*
G03X133800Y1309214I-1074J-1187D01*
G01X132198D01*
G03X131124Y1308800I0J-1601D01*
G01X125100D01*
X124500Y1309400D01*
Y1309450D01*
X123620Y1310330D01*
Y1314912D01*
X125970Y1317262D01*
Y1317746D01*
G03X126300Y1317949I-668J1455D01*
G03X126571Y1317774I1000J1251D01*
G01X126680Y1317719D01*
Y1316256D01*
X127105Y1315830D01*
X127101Y1315741D01*
G03X130451Y1318096I2598J-136D01*
G02X130194Y1318623I116J383D01*
G03X130302Y1319200I-1494J578D01*
G01Y1320600D01*
G03X128700Y1322202I-1602J0D01*
G01X127757D01*
X127146Y1322813D01*
Y1323433D01*
G03X128426Y1325300I-722J1867D01*
G01Y1328200D01*
G03X126425Y1330202I-2002J0D01*
G01X125025D01*
G03X123261Y1329146I0J-2001D01*
G02X122553Y1329151I-353J189D01*
G03X118768Y1329604I-2046J-1055D01*
G02X118174Y1329592I-302J262D01*
G03X117739Y1329952I-1674J-1580D01*
G02X117672Y1330572I216J337D01*
G01X125170Y1338070D01*
Y1339800D01*
X126695D01*
X126719Y1339794D01*
G03X127099Y1339748I381J1556D01*
G01X128499D01*
G03X128879Y1339794I-1J1602D01*
G01X128903Y1339800D01*
X130095D01*
X130119Y1339794D01*
G03X130499Y1339748I381J1556D01*
G01X131899D01*
G03X132279Y1339794I-1J1602D01*
G01X132303Y1339800D01*
X137100D01*
X141200Y1343900D01*
Y1350130D01*
X141862D01*
X145398Y1346593D01*
Y1346510D01*
G03X147191Y1348973I2602J-10D01*
G01X147074Y1348935D01*
X143038Y1352970D01*
X133200D01*
Y1354252D01*
X133183D01*
G02X133041Y1354593I0J200D01*
G01X134474Y1356026D01*
Y1361974D01*
X135000Y1362500D01*
X137849D01*
X211632Y1288717D01*
X215574Y1281879D01*
X215811Y1281437D01*
X340131Y1048815D01*
G02X339915Y1048250I-353J-189D01*
G03X342062Y1044231I784J-2164D01*
G02X342652Y1044098I237J-322D01*
G01X763300Y257000D01*
X834300Y222600D01*
X836659Y222259D01*
G02X836809Y221520I-57J-396D01*
G03X839595Y217891I1190J-1971D01*
G02X840155Y217885I277J-289D01*
G01X861411Y196630D01*
X883913D01*
G02X884103Y195878I-1J-400D01*
G03X888731I2314J-4264D01*
G02X888921Y196630I191J352D01*
G01X893911D01*
X910411Y180130D01*
X935911D01*
X939886Y176154D01*
X939956D01*
X946275Y169835D01*
G02X945993Y169152I-283J-283D01*
G03X945562Y169115I6J-2602D01*
G01X945460Y169098D01*
X945437Y169120D01*
X935500D01*
Y170402D01*
X928598D01*
Y170366D01*
G02X927884Y170118I-400J0D01*
G03X927701Y170312I-1252J-998D01*
G02X927656Y170857I269J297D01*
G03X928000Y171847I-1257J992D01*
G01Y173250D01*
G03X926399Y174852I-1602J0D01*
G01X924999D01*
G03X923999Y174501I1J-1602D01*
G03X922999Y174852I-1001J-1251D01*
G01X921599D01*
G03X921073Y174763I1J-1602D01*
G01X921041Y174752D01*
X917172D01*
X917145Y174760D01*
G03X915043Y170767I-646J-2210D01*
G02X915084Y170186I-253J-310D01*
G03X914819Y169844I1917J-1759D01*
G01X914285D01*
X909495Y165054D01*
X901546D01*
Y166049D01*
X889792D01*
Y165054D01*
X888108D01*
X888094Y165240D01*
G03X882938Y165509I-2595J-190D01*
G01X882908Y165344D01*
X877058D01*
G03X875628Y166226I-1431J-720D01*
G01X874228D01*
G03X873228Y165875I1J-1602D01*
G03X872228Y166226I-1001J-1251D01*
G01X870828D01*
G03X870302Y166137I1J-1602D01*
G01X870270Y166126D01*
X868173D01*
X868146Y166134D01*
G03X865985Y162191I-646J-2210D01*
G02X865996Y161599I-263J-301D01*
G03X868222Y157714I1579J-1675D01*
G01X868249Y157722D01*
X870270D01*
X870302Y157711D01*
G03X870828Y157622I527J1513D01*
G01X872228D01*
G03X873228Y157973I-1J1602D01*
G03X874228Y157622I1001J1251D01*
G01X875628D01*
G03X877187Y158859I0J1601D01*
G01X877224Y159014D01*
X880819D01*
G03X885179I2180J1420D01*
G01X889792D01*
Y158045D01*
X901546D01*
Y159014D01*
X905319D01*
G03X909622Y158929I2180J1420D01*
G01X909681Y159014D01*
X909971D01*
X913961Y163004D01*
X920398D01*
G03X921428Y162173I1431J719D01*
G01X921578Y162134D01*
Y160730D01*
G03X925122Y157045I1421J-2180D01*
G01X925181Y157130D01*
X925545D01*
G03X925952Y156588I1455J669D01*
G01X928161Y154380D01*
X940065D01*
X950420Y164734D01*
Y169708D01*
X941132Y178996D01*
X941062D01*
X937087Y182970D01*
X911587D01*
X895087Y199470D01*
X862587D01*
X843159Y218898D01*
G02X843616Y219541I283J283D01*
G01X870499Y206550D01*
X872499Y205550D01*
X885499D01*
X886999Y207050D01*
Y231050D01*
X885999Y232050D01*
X846499D01*
X774499Y266550D01*
X759255Y294831D01*
G02X759572Y295067I176J94D01*
G01X760332Y294308D01*
Y294280D01*
X762229Y292382D01*
X762256D01*
X770509Y284130D01*
X783819D01*
G03X788179I2180J1420D01*
G01X814871D01*
G03X815700Y283898I830J1370D01*
G01X817300D01*
G03X817940Y284032I-1J1602D01*
G02X818500Y283666I160J-367D01*
G01Y280500D01*
X807500Y269500D01*
Y264000D01*
X813500Y258000D01*
X840500D01*
X845000Y262500D01*
X853457D01*
G03X855343I943J2100D01*
G01X857000D01*
Y278200D01*
X857524Y278724D01*
X859324D01*
X861999Y276050D01*
X884999D01*
X885499Y276550D01*
Y281050D01*
X884999Y281550D01*
X871499D01*
X870499Y282550D01*
Y285050D01*
X871499Y286050D01*
X884999D01*
X885999Y287050D01*
Y301050D01*
X884999Y302050D01*
X873999D01*
X872999Y303050D01*
Y305050D01*
X873499Y305550D01*
X884499D01*
X885499Y306550D01*
Y311050D01*
X884499Y312050D01*
X873499D01*
X872999Y312550D01*
Y315050D01*
X873999Y316050D01*
X884499D01*
X884999Y316550D01*
Y331550D01*
X874499Y342050D01*
X866881D01*
X866843Y342067D01*
G03X866200Y342202I-644J-1467D01*
G01X863600D01*
G03X862957Y342067I1J-1602D01*
G01X862919Y342050D01*
X838450D01*
X837000Y343500D01*
Y363500D01*
X833450Y367050D01*
X789000D01*
X784550Y371500D01*
X754500D01*
X749000Y366000D01*
Y360441D01*
G02X748520Y360049I-400J0D01*
G03X747163Y355036I-520J-2550D01*
G01X747298Y354990D01*
Y352958D01*
X747287Y352926D01*
G03X747198Y352400I1513J-527D01*
G01Y351500D01*
X728708D01*
X225499Y1285050D01*
Y1285550D01*
X225706Y1285757D01*
G02X226281Y1285747I283J-283D01*
G01X237190Y1274060D01*
X249770Y1258800D01*
X385250Y1089610D01*
X542450Y894550D01*
X714810Y680530D01*
X766790Y615090D01*
X768490Y613320D01*
X869976Y613073D01*
X871999Y611050D01*
X884499D01*
X886499Y613050D01*
Y636050D01*
X884999Y637550D01*
X768999D01*
X375078Y1122555D01*
X375124Y1122665D01*
G03X372569Y1125811I-2125J885D01*
G01X372452Y1125789D01*
X262999Y1260550D01*
Y1261550D01*
X263999Y1262550D01*
X509760Y1159880D01*
X716970Y1074710D01*
X850880Y1019180D01*
X854640Y1017590D01*
X857260Y1017000D01*
X861499Y1017050D01*
X884999D01*
X885999Y1018050D01*
Y1042050D01*
X884999Y1043050D01*
X838999D01*
X260999Y1276550D01*
X181999Y1355550D01*
Y1363426D01*
G03X183019Y1364394I-999J2074D01*
G01X183033Y1364419D01*
X186802Y1368188D01*
Y1371842D01*
X186813Y1371874D01*
G03X186902Y1372400I-1513J527D01*
G01Y1373173D01*
G02X187584Y1373456I400J0D01*
G01X189034Y1372006D01*
X189047Y1371953D01*
G03X189828Y1370946I1552J397D01*
G01Y1370068D01*
X189691Y1370023D01*
G03X192670Y1368985I809J-2473D01*
G01Y1370896D01*
G03X192999Y1371099I-670J1454D01*
G03X193716Y1370774I999J1251D01*
G01X193777Y1370763D01*
X196898Y1367643D01*
Y1366699D01*
G03X197728Y1365296I1601J0D01*
G01Y1364714D01*
X197658Y1364654D01*
G03X197063Y1361926I1491J-1754D01*
G02X196874Y1361396I-362J-170D01*
G03X200564Y1359487I1125J-2346D01*
G01X200547Y1359589D01*
X200570Y1359612D01*
Y1361089D01*
G03X200640Y1364654I-1421J1811D01*
G01X200570Y1364714D01*
Y1365246D01*
G03X200899Y1365449I-670J1454D01*
G03X201899Y1365098I1001J1251D01*
G01X203299D01*
G03X203595Y1365126I-2J1602D01*
G01X203613Y1365130D01*
X206819D01*
G03X210420Y1368730I2180J1420D01*
G01Y1370224D01*
X211500D01*
Y1375380D01*
X215064D01*
G03X214026Y1378358I1435J2170D01*
G01X213981Y1378220D01*
X204000D01*
Y1379502D01*
X197349D01*
G02X196960Y1379991I1J400D01*
G03X197000Y1380350I-1561J356D01*
G01Y1381750D01*
G03X196129Y1383175I-1601J0D01*
G02X196073Y1383852I183J356D01*
G03X194054Y1387910I-1372J1848D01*
G01X194027Y1387902D01*
X193288D01*
X189048Y1383661D01*
Y1382710D01*
G02X188706Y1382569I-200J0D01*
G01X188587Y1382688D01*
X188578Y1382755D01*
G03X183820Y1383820I-2578J-355D01*
G01X181780D01*
X180500Y1385100D01*
X154948D01*
X116828Y1423221D01*
G02X117152Y1423902I283J283D01*
G03X119659Y1425759I238J2299D01*
G01X119690Y1425920D01*
X143151D01*
X143192Y1425773D01*
G03X144563Y1424236I2232J611D01*
G01X144689Y1424186D01*
Y1422971D01*
X156493D01*
Y1432975D01*
X144689D01*
Y1431365D01*
G03X143517Y1430518I2044J-4062D01*
G01X142997Y1430000D01*
X127170D01*
G03X125213Y1430915I-1936J-1590D01*
G01Y1430914D01*
X124102D01*
X124101Y1430915D01*
G03X122145Y1430000I-20J-2505D01*
G01X119709D01*
X119692Y1430182D01*
G03X115078Y1429976I-2302J-206D01*
G01Y1426201D01*
G03X115169Y1425561I2312J2D01*
G02X114785Y1425050I-384J-111D01*
G01X112400D01*
X104600Y1432850D01*
Y1437924D01*
G02X104990Y1438323I400J-1D01*
G03X107246Y1440601I-55J2311D01*
G01X107263Y1441722D01*
X124443D01*
G02X124591Y1441711I-1J-1010D01*
G01X124593D01*
G02X125188Y1441394I-150J-999D01*
G01Y1440441D01*
G03X126788Y1438840I1601J0D01*
G01X128392D01*
G03X129390Y1439190I-1J1601D01*
G03X130388Y1438840I999J1251D01*
G01X131990D01*
G03X133592Y1440441I0J1602D01*
G01Y1440920D01*
X143651D01*
X143692Y1440773D01*
G03X144689Y1439428I2232J612D01*
G01Y1437971D01*
X156493D01*
Y1447975D01*
X144689D01*
Y1446309D01*
G03X144361Y1446057I1810J-2695D01*
G03X144291Y1445991I918J-1043D01*
G01X144156Y1445855D01*
G03X143709Y1445135I1322J-1319D01*
G01X143663Y1445000D01*
X133592D01*
Y1445541D01*
G03X131992Y1447142I-1601J0D01*
G01X130906D01*
X129499Y1448550D01*
X125999D01*
X123999Y1446550D01*
Y1446050D01*
X123751Y1445802D01*
X107145D01*
G03X105000Y1447253I-2146J-861D01*
G02X104600Y1447653I0J400D01*
G01Y1452632D01*
G02X105296Y1452901I400J0D01*
G03X109018Y1453344I1703J1549D01*
G01X109032Y1453369D01*
X117800Y1462138D01*
Y1467292D01*
X117812Y1467324D01*
G03X117900Y1467850I-1513J524D01*
G01Y1468506D01*
G02X118593Y1468778I400J0D01*
G03X120498Y1467948I1905J1772D01*
G01X120499D01*
Y1465050D01*
X120599Y1464950D01*
Y1463750D01*
X121199Y1463150D01*
X122508D01*
G03X125108I1300J1900D01*
G01X139399D01*
X140499Y1462050D01*
Y1455550D01*
X142499Y1453550D01*
X143999D01*
X145499Y1455050D01*
X152499D01*
X152999Y1454550D01*
X154103D01*
Y1454452D01*
X164007D01*
Y1454558D01*
X165499Y1456050D01*
Y1470550D01*
X164499Y1471550D01*
X133499D01*
X129499Y1475550D01*
X122499D01*
X120499Y1473550D01*
Y1473152D01*
G03X120062Y1473115I0J-2602D01*
G01X119960Y1473098D01*
X119637Y1473420D01*
X117703D01*
G03X117461Y1473752I-1404J-770D01*
G02X117451Y1474292I290J275D01*
G03X117850Y1475350I-1203J1058D01*
G01Y1476750D01*
G03X116249Y1478352I-1602J0D01*
G01X115206D01*
X114904Y1478653D01*
Y1480779D01*
X117947D01*
Y1483066D01*
X119005D01*
X119037Y1483098D01*
X121321D01*
X121359Y1483082D01*
G03X121999Y1482948I641J1468D01*
G01X123599D01*
G03X125200Y1484548I0J1601D01*
G01Y1486150D01*
G03X125000Y1486925I-1602J0D01*
G01Y1490362D01*
X120111Y1495252D01*
X99387D01*
X97518Y1493383D01*
X97493Y1493369D01*
G03X97087Y1489614I1106J-2019D01*
G02X96981Y1488945I-263J-301D01*
G03X100564Y1486987I1018J-2395D01*
G01X100547Y1487089D01*
X101587Y1488130D01*
X106463D01*
Y1480523D01*
X104292Y1478352D01*
X103249D01*
G03X101648Y1476752I0J-1601D01*
G01Y1475350D01*
G03X101649Y1475287I1601J-6D01*
G02X101250Y1474872I-400J-15D01*
G01X98686D01*
X98487Y1475070D01*
X98494Y1475161D01*
G03X93384Y1476015I-2595J188D01*
G02X92714Y1475835I-387J103D01*
G01X52499Y1516050D01*
Y1545050D01*
X46602Y1550947D01*
X46600Y1551026D01*
G03X44375Y1553251I-2301J-76D01*
G01X44296Y1553253D01*
X39499Y1558050D01*
Y1565550D01*
X46448Y1572500D01*
X48500D01*
X59000Y1562000D01*
Y1561000D01*
X65300Y1554700D01*
X76841D01*
G03X77199Y1554066I2158J801D01*
G02X77169Y1553534I-313J-249D01*
G03X76698Y1552400I1130J-1134D01*
G01Y1551000D01*
G03X77049Y1550000I1602J1D01*
G03X76698Y1549000I1251J-1001D01*
G01Y1547600D01*
G03X77580Y1546170I1602J1D01*
G01Y1545112D01*
X77753Y1544939D01*
X77746Y1544848D01*
G03X81705Y1543099I2297J-157D01*
G02X82281Y1543101I289J-277D01*
G03X85200Y1546626I1651J1604D01*
G02X85132Y1546883I111J167D01*
G03X85302Y1547600I-1432J718D01*
G01Y1549000D01*
G03X84951Y1550000I-1602J-1D01*
G03X85302Y1551000I-1251J1001D01*
G01Y1552400D01*
G03X84420Y1553830I-1602J-1D01*
G01Y1554344D01*
X84445Y1554389D01*
G03X84588Y1554700I-2014J1115D01*
G01X86041D01*
X86998Y1553743D01*
Y1552800D01*
G03X88600Y1551198I1602J0D01*
G01X90000D01*
G03X91000Y1551549I-1J1602D01*
G03X92000Y1551198I1001J1251D01*
G01X93400D01*
G03X93554Y1551206I-6J1602D01*
G02X93978Y1550703I38J-398D01*
G03X97630Y1551904I2222J-603D01*
G02X97733Y1552260I124J157D01*
G03X97975Y1552298I-236J2290D01*
G01X98081Y1552320D01*
X100820Y1549581D01*
G02X100458Y1548906I-283J-283D01*
G03X102256Y1547108I-458J-2256D01*
G02X102931Y1547470I392J79D01*
G01X111178Y1539223D01*
Y1515680D01*
G03X110400Y1514813I721J-1430D01*
G01X110384Y1514772D01*
X110212Y1514600D01*
X109749Y1515064D01*
X109884Y1515205D01*
G03X106580Y1514820I-1884J1795D01*
G01Y1514216D01*
X106650Y1514145D01*
G02X106534Y1513498I-282J-283D01*
G03X108297Y1508213I1166J-2548D01*
G01X108404Y1508236D01*
X109504Y1507137D01*
Y1505363D01*
X109023D01*
Y1496959D01*
X117947D01*
Y1505363D01*
X117466D01*
Y1507839D01*
X117641Y1507860D01*
G03X118853Y1508680I-192J1590D01*
G01X120425D01*
X120463Y1508663D01*
G03X119406Y1512596I1036J2387D01*
G01X119245Y1512515D01*
G02X119045Y1512715I0J200D01*
G01X119046Y1512730D01*
G03X119050Y1512850I-1597J113D01*
G01Y1514250D01*
G03X117779Y1515817I-1601J0D01*
G01X117620Y1515851D01*
Y1522501D01*
G02X118143Y1522882I400J0D01*
G03X121359Y1524040I856J2668D01*
G01X143488D01*
X143501Y1524052D01*
X144690D01*
Y1522972D01*
X156492D01*
Y1527974D01*
X144690D01*
Y1526894D01*
X142325D01*
X142312Y1526880D01*
X121465D01*
G03X118143Y1528218I-2466J-1330D01*
G02X117620Y1528599I-123J381D01*
G01Y1539486D01*
G37*
G36*
G01X91532Y47950D02*
Y48642D01*
X81806D01*
X79999Y50450D01*
Y52450D01*
X81188Y53640D01*
X91532D01*
Y53950D01*
X99999D01*
X101999Y51950D01*
Y49450D01*
X100499Y47950D01*
X91532D01*
G37*
G36*
G01X85649Y34400D02*
X80999Y39050D01*
Y46550D01*
X81499Y47050D01*
X81700D01*
X82001Y46748D01*
X100452D01*
X101400Y45800D01*
Y36200D01*
X99600Y34400D01*
X85649D01*
G37*
G36*
G01X89499Y79550D02*
X71999D01*
X70999Y80550D01*
Y85550D01*
X71999Y86550D01*
X77499D01*
X77999Y86050D01*
Y83050D01*
X78499Y82550D01*
X88999D01*
X89999Y81550D01*
Y80050D01*
X89499Y79550D01*
G37*
G36*
G01X77499Y68050D02*
X72999D01*
X71499Y69550D01*
Y76050D01*
X72499Y77050D01*
X89499D01*
X89999Y76550D01*
Y70550D01*
X89499Y70050D01*
X79499D01*
X77499Y68050D01*
G37*
G36*
G01X81098Y455252D02*
X80900Y455449D01*
Y458551D01*
X81299Y458950D01*
X91899D01*
X93999Y461050D01*
X101999D01*
X102499Y460550D01*
Y455750D01*
X102000Y455252D01*
X81098D01*
G37*
G36*
G01X100499Y475550D02*
X81499D01*
X80999Y476050D01*
Y482550D01*
X81499Y483050D01*
X100499D01*
X100999Y482550D01*
Y476050D01*
X100499Y475550D01*
G37*
G36*
G01X101000Y443552D02*
X82698D01*
X80900Y445348D01*
Y453252D01*
X81699Y454050D01*
X101999D01*
X102499Y453550D01*
Y445050D01*
X101000Y443552D01*
G37*
G36*
G01X99999Y485050D02*
X81499D01*
X80999Y485550D01*
Y488050D01*
X81499Y488550D01*
X91999D01*
X93999Y490550D01*
X101499D01*
X102999Y489050D01*
Y488050D01*
X99999Y485050D01*
G37*
G36*
G01X60851Y611114D02*
X62354Y609611D01*
X62363Y609599D01*
G03X62500Y609441I1139J849D01*
G01X63337Y608604D01*
X63362D01*
X63513Y608452D01*
X69961D01*
X71050Y609541D01*
X74775D01*
Y610522D01*
X75508D01*
X75545Y610370D01*
G03X77101Y609148I1556J380D01*
G01X78501D01*
G03X78620Y609153I-8J1602D01*
G02X79050Y608754I30J-399D01*
G01Y607922D01*
X79041Y607895D01*
G03X81122Y604951I2210J-646D01*
G02X81499Y604551I-23J-399D01*
G01Y588321D01*
G02X80874Y587990I-400J0D01*
G03X75895Y579680I-2725J-4014D01*
G02X75992Y579043I-186J-354D01*
G01X70999Y574050D01*
X39999D01*
X37999Y576050D01*
Y583226D01*
X50635D01*
X58820Y591412D01*
Y608485D01*
G03X60186Y611203I-1420J2416D01*
G01X60175Y611299D01*
X60384Y611508D01*
X60632Y611260D01*
X60851Y611114D01*
G37*
G36*
G01X46473Y587280D02*
X55297Y596103D01*
G02X55979Y595820I282J-283D01*
G01Y592588D01*
X49459Y586068D01*
X37999D01*
Y587280D01*
X46473D01*
G37*
G36*
G01X91532Y569050D02*
Y569155D01*
X81070D01*
G02X80787Y569838I0J400D01*
G01X88999Y578050D01*
Y610050D01*
X87390Y611660D01*
Y615898D01*
G02X88166Y616032I400J-1D01*
G03X90847Y611787I10733J3810D01*
G01X94218Y608417D01*
X96367Y606268D01*
G02X96999Y605522I-4208J-4206D01*
G01Y571550D01*
X94499Y569050D01*
X91532D01*
G37*
G36*
G01X145999Y1133550D02*
X130198Y1149350D01*
X111050D01*
X107400Y1145700D01*
Y1142000D01*
X106200Y1140800D01*
X98300D01*
X94500Y1137000D01*
Y1133009D01*
X94480Y1132988D01*
Y1120508D01*
X92021Y1118050D01*
X80499D01*
X73499Y1125050D01*
Y1150700D01*
X73650Y1150850D01*
Y1177650D01*
X76500Y1180500D01*
X76949D01*
X76999Y1180550D01*
X95499D01*
X99499Y1176550D01*
X100300D01*
X100501Y1176348D01*
X138152D01*
X138800Y1175700D01*
Y1158249D01*
X155999Y1141050D01*
Y1134550D01*
X154999Y1133550D01*
X145999D01*
G37*
G36*
G01X93391Y1107000D02*
X93405Y1106814D01*
G03X96018Y1104398I2595J186D01*
G01X96101Y1104399D01*
X98000Y1102500D01*
X98310D01*
X98365Y1102389D01*
G03X99800Y1101498I1435J710D01*
G01X101200D01*
G03X102604Y1102330I0J1601D01*
G01X105719D01*
X106499Y1101550D01*
Y1101112D01*
X106148D01*
Y1097108D01*
X106499D01*
Y1096050D01*
X107499Y1095050D01*
X111578D01*
Y1093050D01*
X99999D01*
X98499Y1091550D01*
Y1089550D01*
X98100Y1089152D01*
X96799D01*
G03X96269Y1089061I2J-1602D01*
G01X96237Y1089050D01*
X88999D01*
X86999Y1091050D01*
Y1096135D01*
X87010Y1096167D01*
G03X87102Y1096700I-1510J535D01*
G01Y1098300D01*
G03X87010Y1098833I-1602J-2D01*
G01X86999Y1098865D01*
Y1103135D01*
X87010Y1103167D01*
G03X87102Y1103700I-1510J535D01*
G01Y1105300D01*
G03X87010Y1105833I-1602J-2D01*
G01X86999Y1105865D01*
Y1105999D01*
X88000Y1107000D01*
X93391D01*
G37*
G36*
G01X102499Y1249113D02*
X92999Y1258613D01*
Y1264613D01*
X91499Y1266113D01*
X80499D01*
X79999Y1266613D01*
Y1269613D01*
X80499Y1270113D01*
X95999D01*
X104499Y1261613D01*
X107999D01*
X108999Y1260613D01*
Y1250113D01*
X107999Y1249113D01*
X102499D01*
G37*
G36*
G01X155499Y1214550D02*
X154999Y1215050D01*
Y1233551D01*
X152000Y1236550D01*
X135999D01*
X134936Y1237613D01*
X133135D01*
X132997Y1237752D01*
X106358D01*
G03X105299Y1238152I-1059J-1202D01*
G01X102699D01*
G03X101640Y1237752I0J-1602D01*
G01X98860D01*
X79999Y1256613D01*
Y1263613D01*
X80999Y1264613D01*
X90499D01*
X91499Y1263613D01*
Y1257613D01*
X101999Y1247113D01*
X109999D01*
X111999Y1249113D01*
Y1260613D01*
X112999Y1261613D01*
X140499D01*
X146986Y1268100D01*
X171900D01*
X175499Y1264501D01*
Y1216050D01*
X173999Y1214550D01*
X155499D01*
G37*
G36*
G01X166499Y1271050D02*
X128999D01*
X127999Y1272050D01*
X99062D01*
X92499Y1278613D01*
Y1284613D01*
X91499Y1285613D01*
X80999D01*
X80499Y1286113D01*
Y1294113D01*
X80999Y1294613D01*
X93999D01*
X100499Y1288113D01*
Y1282613D01*
X101999Y1281113D01*
X109999D01*
X111499Y1282613D01*
Y1293613D01*
X112999Y1295113D01*
X146387D01*
X148500Y1293000D01*
Y1284900D01*
X149850Y1283550D01*
X166999D01*
X167999Y1282550D01*
Y1272550D01*
X166499Y1271050D01*
G37*
G36*
G01X108499Y1282613D02*
X102999D01*
X101999Y1283613D01*
Y1288613D01*
X94499Y1296113D01*
X80999D01*
X80499Y1296613D01*
Y1299113D01*
X80999Y1299613D01*
X97499D01*
X102999Y1294113D01*
X108499D01*
X108999Y1293613D01*
Y1283113D01*
X108499Y1282613D01*
G37*
G36*
G01X71500Y1576500D02*
X65000Y1583000D01*
Y1602000D01*
X66500Y1603500D01*
X103500D01*
X107000Y1600000D01*
Y1578500D01*
X105000Y1576500D01*
X76000D01*
G03X73400I-1300J-1900D01*
G01X71500D01*
G37*
G36*
G01X95578Y1634465D02*
G03X98420I1421J-2415D01*
G01Y1637988D01*
X96541Y1639867D01*
G02X96824Y1640550I283J283D01*
G01X129500D01*
X129850Y1640200D01*
X129900D01*
X130000Y1640100D01*
Y1635100D01*
X130050Y1635050D01*
Y1616600D01*
X126000Y1612550D01*
X45499D01*
X43499Y1614550D01*
Y1619990D01*
X72719D01*
G03X79182Y1622667I0J9140D01*
G03X80968Y1626979I-4312J4312D01*
G01Y1638551D01*
G03X78707Y1644006I-7714J-1D01*
G01X77312Y1645401D01*
G02X77637Y1646082I283J283D01*
G03X80286Y1646550I514J4824D01*
G01X85840D01*
X95578Y1636812D01*
Y1634465D01*
G37*
G36*
G01X43499Y1624070D02*
Y1629999D01*
X60050Y1646550D01*
X70566D01*
G03X71251Y1645731I13321J10445D01*
G03X71918Y1645025I12633J11267D01*
G01X75823Y1641120D01*
G02X76888Y1638551I-2570J-2570D01*
G01Y1626980D01*
G02X76297Y1625553I-2018J0D01*
G02X72718Y1624070I-3579J3577D01*
G01X43499D01*
G37*
G36*
G01X109999Y1653613D02*
X102999D01*
X92499Y1664113D01*
Y1670113D01*
X90999Y1671613D01*
X79999D01*
X79499Y1672113D01*
Y1675113D01*
X79999Y1675613D01*
X95499D01*
X105499Y1665613D01*
X109999D01*
X110999Y1664613D01*
Y1654613D01*
X109999Y1653613D01*
G37*
G36*
G01Y1687113D02*
X102999D01*
X101499Y1688613D01*
Y1694113D01*
X93999Y1701613D01*
X80499D01*
X79999Y1702113D01*
Y1704613D01*
X80499Y1705113D01*
X97999D01*
X103999Y1699113D01*
X109999D01*
X110999Y1698113D01*
Y1688113D01*
X109999Y1687113D01*
G37*
G36*
G01X158300Y1695613D02*
X148636Y1685948D01*
X148534Y1685966D01*
G03X145534Y1682966I-434J-2566D01*
G01X145552Y1682864D01*
X139494Y1676806D01*
X99306D01*
X91999Y1684113D01*
Y1690113D01*
X91532Y1690580D01*
Y1690690D01*
X91422D01*
X90999Y1691113D01*
X80499D01*
X79999Y1691613D01*
Y1699613D01*
X80499Y1700113D01*
X93499D01*
X99999Y1693613D01*
Y1688113D01*
X102499Y1685613D01*
X111999D01*
X112999Y1686613D01*
Y1698113D01*
X113999Y1699113D01*
X128999D01*
X130212Y1697900D01*
X132061D01*
G03X133736Y1697749I1030J2059D01*
G01X133763Y1697758D01*
X134145D01*
X138200Y1701813D01*
Y1701814D01*
X144499Y1708113D01*
X167999D01*
X168999Y1707113D01*
Y1696113D01*
X168499Y1695613D01*
X158300D01*
G37*
G36*
G01X134550Y1622050D02*
X131400Y1625200D01*
Y1640300D01*
X131500Y1640400D01*
Y1641613D01*
X130500Y1642613D01*
X93795D01*
X88520Y1647888D01*
Y1651838D01*
X79499Y1660859D01*
Y1669113D01*
X80499Y1670113D01*
X89999D01*
X90999Y1669113D01*
Y1663113D01*
X101999Y1652113D01*
X112999D01*
X114499Y1653613D01*
Y1664113D01*
X115734Y1665348D01*
X137497D01*
X137761Y1665613D01*
X161436D01*
X161999Y1665050D01*
Y1645500D01*
X164449Y1643050D01*
X172499D01*
X173999Y1641550D01*
Y1624050D01*
X171999Y1622050D01*
X134550D01*
G37*
G36*
G01X54999Y1878550D02*
Y1899223D01*
X55121Y1899274D01*
G03X56100Y1900750I-623J1476D01*
G01Y1902350D01*
Y1902390D01*
G02X56500Y1902800I400J10D01*
G01X57749D01*
X58974Y1904025D01*
X73525D01*
X77000Y1907500D01*
X86000D01*
X94000Y1915500D01*
X93974Y1915526D01*
Y1947526D01*
X100499Y1954050D01*
X133999D01*
X137499Y1950550D01*
Y1910550D01*
X131499Y1904550D01*
X118999D01*
X110950Y1896502D01*
X110198D01*
Y1895748D01*
X106999Y1892550D01*
Y1866550D01*
X104499Y1864050D01*
X80499D01*
X79499Y1865050D01*
Y1874550D01*
X76499Y1877550D01*
X55999D01*
X54999Y1878550D01*
G37*
G36*
G01X55475Y1941525D02*
X35024D01*
X31499Y1945050D01*
Y1951550D01*
X32499Y1952550D01*
X56950D01*
X59000Y1950500D01*
Y1945050D01*
X55475Y1941525D01*
G37*
G36*
G01X46400Y1965550D02*
G03X46379Y1965812I-1601J3D01*
G01X46362Y1965913D01*
X49398Y1968948D01*
X51299D01*
G03X52550Y1969550I0J1601D01*
G01X96999D01*
X99499Y1972050D01*
X108999D01*
X112499Y1968550D01*
Y1959050D01*
X110999Y1957550D01*
X94499D01*
X91499Y1954550D01*
X44200D01*
Y1956752D01*
X45999Y1958550D01*
Y1961049D01*
X46200Y1961250D01*
Y1963175D01*
G03X46400Y1963950I-1402J775D01*
G01Y1965550D01*
G37*
G36*
G01X45499Y1904550D02*
X38499Y1911550D01*
Y1912161D01*
G02X38840Y1912302I200J0D01*
G01X39185Y1911958D01*
X39200Y1911922D01*
G03X40729Y1915387I2397J1012D01*
G01X40610Y1915345D01*
X38600Y1917355D01*
Y1918850D01*
G03X38510Y1919380I-1601J1D01*
G01X38499Y1919412D01*
Y1920188D01*
X38510Y1920220D01*
G03X38600Y1920750I-1511J529D01*
G01Y1922148D01*
X42223D01*
G03X43592Y1926620I1776J1902D01*
G02X43247Y1927298I-62J395D01*
G01X43999Y1928050D01*
Y1929048D01*
X44000Y1929049D01*
Y1933668D01*
X44200D01*
Y1937200D01*
X45000Y1938000D01*
X56500D01*
Y1938051D01*
X69499Y1951050D01*
X84499D01*
X89499Y1946050D01*
Y1917050D01*
X84999Y1912550D01*
X72999D01*
X68474Y1908026D01*
X58026D01*
X58000Y1908000D01*
X52500D01*
X52000Y1907500D01*
Y1905500D01*
X51050Y1904550D01*
X45499D01*
G37*
G36*
G01X109999Y38550D02*
X107999Y40550D01*
Y69550D01*
X110999Y72550D01*
X173737D01*
X173769Y72539D01*
G03X174299Y72448I532J1511D01*
G01X175699D01*
G03X176229Y72539I-2J1602D01*
G01X176261Y72550D01*
X177637D01*
X177669Y72539D01*
G03X178199Y72448I532J1511D01*
G01X179799D01*
G03X180329Y72539I-2J1602D01*
G01X180361Y72550D01*
X181137D01*
X181169Y72539D01*
G03X181699Y72448I532J1511D01*
G01X183299D01*
G03X183829Y72539I-2J1602D01*
G01X183861Y72550D01*
X189773D01*
G03X193225I1726J1947D01*
G01X201999D01*
X202924Y71624D01*
Y60376D01*
X202999D01*
Y59050D01*
X182499Y38550D01*
X109999D01*
G37*
G36*
G01X108499Y74550D02*
X107499Y75550D01*
Y114550D01*
X111499Y118550D01*
X184237D01*
X184269Y118539D01*
G03X184799Y118448I532J1511D01*
G01X186199D01*
G03X186729Y118539I-2J1602D01*
G01X186761Y118550D01*
X186999D01*
X187499Y118050D01*
Y108050D01*
X180999Y101550D01*
Y100412D01*
X180988Y100380D01*
G03X180898Y99850I1511J-529D01*
G01Y98448D01*
X180499Y98050D01*
X174499D01*
X170999Y94550D01*
Y77050D01*
X168499Y74550D01*
X108499D01*
G37*
G36*
G01X135898Y442550D02*
G03X138738Y442311I1603J2050D01*
G01X139499Y441550D01*
X140449D01*
X140470Y441546D01*
G03X140799Y441512I328J1567D01*
G01X142037D01*
X142499Y441050D01*
Y438550D01*
X144999Y436050D01*
X145999D01*
X146499Y435550D01*
Y431050D01*
X145914Y430464D01*
X143438D01*
Y430050D01*
X136499D01*
X135400Y428951D01*
Y427897D01*
G03X135398Y427813I1599J-80D01*
G01Y426413D01*
G03X135400Y426329I1601J-4D01*
G01Y423897D01*
G03X135398Y423813I1599J-80D01*
G01Y422413D01*
G03X135400Y422329I1601J-4D01*
G01Y421002D01*
X134251D01*
X132851Y419602D01*
X131758D01*
X131726Y419613D01*
G03X131200Y419702I-527J-1513D01*
G01X129600D01*
G03X129074Y419613I1J-1602D01*
G01X129042Y419602D01*
X127302D01*
X127251Y419550D01*
X126999D01*
X125999Y420550D01*
Y435799D01*
X127700Y437500D01*
X129599D01*
X130999Y438900D01*
Y442050D01*
X131499Y442550D01*
X132777D01*
X132803Y442543D01*
G03X134195I696J2507D01*
G01X134221Y442550D01*
X135898D01*
G37*
G36*
G01X132300Y469000D02*
X130999Y470301D01*
Y480050D01*
X132999Y482050D01*
X137893D01*
G03X140507I1307J2250D01*
G01X142499D01*
X143499Y481050D01*
Y469749D01*
X142750Y469000D01*
X132300D01*
G37*
G36*
G01X170800Y433400D02*
X170456Y433744D01*
Y439074D01*
X169530Y440000D01*
Y441019D01*
X169467Y441082D01*
X169499Y441113D01*
Y445050D01*
X168499Y446050D01*
X164407D01*
X164368Y446068D01*
G03X163699Y446214I-668J-1455D01*
G01X162335D01*
X161999Y446550D01*
Y448050D01*
X162298Y448348D01*
X170748D01*
X171798Y449398D01*
X172352D01*
Y449952D01*
X172512Y450113D01*
X184999D01*
X185999Y449113D01*
Y435113D01*
X184286Y433400D01*
X170800D01*
G37*
G36*
G01X177044Y427598D02*
X178450D01*
Y429050D01*
X181798D01*
Y425875D01*
G03X181598Y425100I1402J-775D01*
G01Y423500D01*
G03X181949Y422500I1602J1D01*
G03X181849Y422360I1251J-1000D01*
G02X181538Y422327I-169J107D01*
G03X180400Y422802I-1138J-1126D01*
G01X179207D01*
X177548Y424461D01*
X177565Y424563D01*
G03X176772Y426906I-2565J438D01*
G02X177044Y427598I272J292D01*
G37*
G36*
G01X153600Y444450D02*
X153281Y444769D01*
X153269Y444828D01*
G03X151699Y446114I-1570J-315D01*
G01X150299D01*
G03X149079Y445550I0J-1602D01*
G01X148419D01*
G03X147199Y446114I-1220J-1038D01*
G01X145799D01*
G03X144579Y445550I0J-1602D01*
G01X143419D01*
G03X142199Y446114I-1220J-1038D01*
G01X140799D01*
G03X139989Y445894I0J-1601D01*
G02X139717Y445962I-101J173D01*
G03X134901Y444470I-2217J-1362D01*
G02X134502Y444050I-399J-20D01*
G01X126999D01*
X125999Y445050D01*
Y454799D01*
X127900Y456700D01*
X170300D01*
X171300Y455700D01*
Y450600D01*
X170250Y449550D01*
X164150D01*
X164124Y449557D01*
G03X163699Y449614I-423J-1544D01*
G01X162299D01*
G03X161874Y449557I-2J-1601D01*
G01X161848Y449550D01*
X159300D01*
X157499Y447749D01*
Y447341D01*
X157483Y447303D01*
G03Y445495I2117J-904D01*
G01X157499Y445457D01*
Y444599D01*
X156900Y444000D01*
X154000D01*
X153600Y444400D01*
Y444450D01*
G37*
G36*
G01X189200Y428100D02*
X187999Y429301D01*
Y452551D01*
X187000Y453550D01*
X175499D01*
X172352Y456698D01*
Y456802D01*
X172248D01*
X170999Y458050D01*
X128999D01*
X128949Y458000D01*
X123400D01*
X123100Y458300D01*
Y464800D01*
X125350Y467050D01*
X142499D01*
X143298Y467848D01*
X144200D01*
Y468751D01*
X155999Y480550D01*
X174300D01*
X175750Y482000D01*
X203850D01*
X210798Y475052D01*
Y433698D01*
X205200Y428100D01*
X189200D01*
G37*
G36*
G01X145700Y535598D02*
G03X146960Y536045I-1J2002D01*
G02X147239Y536018I126J-156D01*
G03X150811Y536080I1761J1482D01*
G01X152087D01*
X152807Y536799D01*
G02X153478Y536418I283J-282D01*
G03X158349Y536891I2521J-643D01*
G01X158970Y537512D01*
Y537946D01*
G03X159800Y539350I-771J1403D01*
G01Y539679D01*
X166705D01*
G02X166988Y538997I0J-400D01*
G01X165481Y537490D01*
X161975D01*
Y529385D01*
X159742Y527152D01*
X158699D01*
G03X157098Y525550I0J-1601D01*
G01Y524150D01*
G03X157521Y523066I1600J0D01*
G02X157481Y522486I-295J-271D01*
G03X157095Y522020I1018J-1236D01*
G01X156537D01*
X154277Y524281D01*
X154287Y524376D01*
G03X150440Y526927I-2588J274D01*
G02X149853Y527200I-194J350D01*
G03X145583Y528655I-2553J-500D01*
G02X144920Y528956I-263J301D01*
G01Y535188D01*
X144851Y535257D01*
G02X144992Y535598I141J141D01*
G01X145700D01*
G37*
G36*
G01X140770Y519837D02*
G02X140291Y519637I-357J181D01*
G03X139799Y519714I-491J-1524D01*
G01X138199D01*
G03X137959Y519696I-1J-1601D01*
G02X137499Y520092I-60J396D01*
G01Y522938D01*
G03X137528Y525673I-2199J1391D01*
G01X137499Y525721D01*
Y526712D01*
G03X138302Y528100I-798J1388D01*
G01Y528428D01*
G02X138989Y528706I400J0D01*
G03X140425Y528098I1437J1394D01*
G01X141825D01*
G03X141874Y528099I-16J2002D01*
G02X142078Y527899I4J-200D01*
G01Y526319D01*
X141914Y526289D01*
G03X140598Y524713I286J-1576D01*
G01Y522113D01*
G03X141139Y520913I1601J0D01*
G02Y520313I-265J-300D01*
G03X140770Y519837I1059J-1202D01*
G37*
G36*
G01X143198Y483050D02*
X142997Y483252D01*
X134298D01*
X132999Y484550D01*
Y488550D01*
X134999Y490550D01*
X149000D01*
X150300Y489250D01*
Y484250D01*
X149100Y483050D01*
X143198D01*
G37*
G36*
G01X143999Y502050D02*
X136499D01*
X134499Y504050D01*
Y513550D01*
X135499Y514550D01*
X147499D01*
X147999Y514050D01*
Y506050D01*
X143999Y502050D01*
G37*
G36*
G01X170900Y489397D02*
Y483778D01*
X170892Y483751D01*
G03X170798Y483082I2208J-651D01*
G01X170799Y482999D01*
X169900Y482100D01*
X152500D01*
X151800Y482800D01*
Y489350D01*
X151502Y489649D01*
Y489748D01*
X150950Y490299D01*
Y490314D01*
X150935D01*
X149498Y491752D01*
X149398D01*
X149100Y492050D01*
X136499D01*
X133999Y494550D01*
Y499050D01*
X135899Y500950D01*
X136001Y500848D01*
X144497D01*
X149200Y505552D01*
Y505751D01*
X157499Y514050D01*
X161499D01*
X161549Y514000D01*
X167000D01*
X169500Y511500D01*
X172649D01*
X173299Y512150D01*
X173301Y512152D01*
G03X173387Y512237I-1575J1679D01*
G03X173421Y512270I-1516J1596D01*
G01X175200Y514050D01*
Y514051D01*
X176048Y514898D01*
X176049D01*
X180650Y519500D01*
Y519501D01*
X183498Y522348D01*
X184497D01*
X184761Y522613D01*
X201999D01*
X202999Y521613D01*
Y510752D01*
X187501D01*
X185298Y508548D01*
Y507412D01*
X170900Y493014D01*
Y492711D01*
X170844Y492653D01*
G03X170900Y489397I1655J-1600D01*
G37*
G36*
G01X188999Y722550D02*
X145499D01*
X144999Y723050D01*
Y725550D01*
X145999Y726550D01*
X181499D01*
X197499Y742550D01*
X221999D01*
X222499Y742050D01*
Y732050D01*
X221999Y731550D01*
X197999D01*
X188999Y722550D01*
G37*
G36*
G01X237364Y695752D02*
X237362Y695754D01*
X232946D01*
X226999Y701701D01*
Y709050D01*
X224999Y711050D01*
X204999D01*
X191499Y697550D01*
X145499D01*
X144999Y698050D01*
Y705050D01*
X145999Y706050D01*
X155200D01*
X156098Y706948D01*
X156492D01*
Y707342D01*
X161050Y711900D01*
X183000D01*
X192650Y721550D01*
X236990D01*
X238411Y720130D01*
X252188D01*
X256059Y724000D01*
X259600D01*
X260999Y722601D01*
Y706050D01*
X259499Y704550D01*
X250500D01*
X249600Y703650D01*
Y696500D01*
X248852Y695752D01*
X237364D01*
G37*
G36*
G01X247964Y772364D02*
X251150Y775550D01*
X283999D01*
X285999Y773550D01*
Y757050D01*
X284499Y755550D01*
X276050D01*
X274500Y754000D01*
Y750500D01*
X274499Y750499D01*
Y731050D01*
X273999Y730550D01*
X231999D01*
X230999Y731550D01*
Y741050D01*
X227999Y744050D01*
X195499D01*
X179499Y728050D01*
X146000D01*
X145800Y728250D01*
Y735650D01*
X146200Y736050D01*
X155500D01*
X160475Y741025D01*
X171974D01*
X184999Y754050D01*
X241500D01*
X243900Y756450D01*
Y765608D01*
G03Y765792I-2300J92D01*
G01Y768300D01*
X246685Y771085D01*
X246717Y771100D01*
G03X247949Y772332I-1118J2350D01*
G01X247964Y772364D01*
G37*
G36*
G01X196499Y693050D02*
X145999D01*
X144999Y694050D01*
Y695050D01*
X145999Y696050D01*
X191999D01*
X204999Y709050D01*
X221999D01*
X222999Y708050D01*
Y698550D01*
X222499Y698050D01*
X201499D01*
X196499Y693050D01*
G37*
G36*
G01X168199Y834512D02*
G03X169063Y834764I2J1601D01*
G01X169198Y834851D01*
X169499Y834550D01*
Y824550D01*
X168999Y824050D01*
X166999D01*
X166914Y823964D01*
X165438D01*
Y821488D01*
X164499Y820550D01*
X160704D01*
X160680Y820556D01*
G03X160300Y820602I-381J-1556D01*
G01X158700D01*
G03X158320Y820556I1J-1602D01*
G01X158296Y820550D01*
X157400D01*
X156300Y819450D01*
Y811900D01*
X158200Y810000D01*
X173899D01*
X175499Y808400D01*
Y804050D01*
X173499Y802050D01*
X155499D01*
X150499Y807050D01*
Y830550D01*
X151208Y831259D01*
G02X151848Y831157I283J-283D01*
G03X155842Y833435I2052J1043D01*
G02X156180Y834050I338J215D01*
G01X164499D01*
X165499Y835050D01*
X165601D01*
G03X166799Y834512I1197J1063D01*
G01X168199D01*
G37*
G36*
G01X155499Y866550D02*
X154499Y867550D01*
Y877550D01*
X155999Y879050D01*
X168499D01*
X169499Y878050D01*
Y877548D01*
G03Y877352I2600J-98D01*
G01Y868050D01*
X167999Y866550D01*
X155499D01*
G37*
G36*
G01X183498Y844602D02*
X184016Y844085D01*
X183934Y843950D01*
G03X183698Y843113I1366J-837D01*
G01Y842070D01*
X183082Y841454D01*
Y837199D01*
X183098Y837183D01*
Y836115D01*
X178934D01*
X178800Y836249D01*
Y837513D01*
G03X177199Y839114I-1601J0D01*
G01X175934D01*
X173499Y841550D01*
X169108D01*
X169094Y841736D01*
G03X163904I-2595J-186D01*
G01X163890Y841550D01*
X155499D01*
X153499Y843550D01*
Y850550D01*
X157499Y854550D01*
X191499D01*
X191999Y854050D01*
Y849501D01*
X192000Y849500D01*
Y849300D01*
X191452Y848752D01*
X185001D01*
X183498Y847249D01*
Y844602D01*
G37*
G36*
G01X155607Y881970D02*
X154499Y883079D01*
Y887050D01*
X155499Y888050D01*
X193050D01*
X199618Y894618D01*
X199748Y894552D01*
G03X202610Y895180I1051J2048D01*
G01X203225D01*
X203315Y895269D01*
G02X203997Y894986I282J-283D01*
G01Y888902D01*
X201438D01*
Y883807D01*
X199601Y881970D01*
X155607D01*
G37*
G36*
G01X203707Y900821D02*
X201635Y898749D01*
X201518Y898787D01*
G03X198612Y895881I-719J-2187D01*
G01X198650Y895764D01*
X192436Y889550D01*
X156597D01*
G03X156401I-98J-2600D01*
G01X154499D01*
X153999Y890050D01*
Y897050D01*
X155298Y898348D01*
X166497D01*
X166698Y898550D01*
X168499D01*
X170999Y901050D01*
Y908050D01*
X175499Y912550D01*
X175500D01*
X176975Y914025D01*
X193911D01*
X201499Y921613D01*
X224688D01*
X225999Y920302D01*
Y909698D01*
X225414Y909113D01*
X211999D01*
X206891Y904005D01*
X206801Y904011D01*
G03X206699Y904014I-98J-1598D01*
G01X205299D01*
G03X203698Y902413I0J-1601D01*
G01Y901013D01*
G03X203701Y900911I1601J-4D01*
G01X203707Y900821D01*
G37*
G36*
G01X232650Y879050D02*
X234999Y876701D01*
Y833199D01*
X228000Y826200D01*
X214200D01*
X212999Y827401D01*
Y850675D01*
X210000Y853674D01*
X194374D01*
X191499Y856550D01*
X154999D01*
X153999Y857550D01*
Y864550D01*
X154499Y865050D01*
X171499D01*
X173499Y867050D01*
Y874550D01*
X177999Y879050D01*
X232650D01*
G37*
G36*
G01X154999Y899550D02*
X153999Y900550D01*
Y911050D01*
X155499Y912550D01*
X166499D01*
X167499Y911550D01*
Y901050D01*
X166264Y899814D01*
X165048D01*
Y899550D01*
X154999D01*
G37*
G36*
G01X155499Y1128550D02*
X141499D01*
X128999Y1141050D01*
X112499D01*
X111499Y1142050D01*
Y1145050D01*
X112999Y1146550D01*
X128999D01*
X143999Y1131550D01*
X155499D01*
X155999Y1131050D01*
Y1129050D01*
X155499Y1128550D01*
G37*
G36*
G01X100499Y1119600D02*
Y1131961D01*
X100617Y1132080D01*
X112545D01*
X112579Y1132067D01*
G03X115223Y1132550I922J2433D01*
G01X116690D01*
X116714Y1132378D01*
G03X118300Y1130998I1586J221D01*
G01X119700D01*
G03X121302Y1132600I0J1602D01*
G01Y1133302D01*
X122000Y1134000D01*
Y1134398D01*
X123800D01*
G03X124330Y1134489I-2J1602D01*
G01X124362Y1134500D01*
X125738D01*
X125770Y1134489D01*
G03X126300Y1134398I532J1511D01*
G01X127700D01*
G03X127962Y1134420I-3J1602D01*
G01X128063Y1134437D01*
X128500Y1134000D01*
Y1129000D01*
X127500Y1128000D01*
X121000D01*
X119499Y1126499D01*
Y1122682D01*
G03X119438Y1118881I1746J-1929D01*
G01X119499Y1118822D01*
Y1118079D01*
X118470Y1117050D01*
X108549D01*
G03X104625Y1116025I-1550J-2090D01*
G01X102900Y1114300D01*
X100400D01*
X99200Y1115500D01*
Y1118191D01*
X99220Y1118212D01*
Y1118520D01*
X100300Y1119600D01*
X100499D01*
G37*
G36*
G01X126799Y1226714D02*
G03X126490Y1226684I-1J-1601D01*
G01X126385Y1226664D01*
X126200Y1226849D01*
Y1229052D01*
X126698Y1229550D01*
X133499D01*
X133860Y1229912D01*
X133950D01*
Y1230002D01*
X134999Y1231050D01*
Y1233050D01*
X135999Y1234050D01*
X149499D01*
X150499Y1233050D01*
Y1220050D01*
X149499Y1219050D01*
X135499D01*
X134499Y1220050D01*
Y1225550D01*
X133499Y1226550D01*
X128907D01*
X128868Y1226568D01*
G03X128199Y1226714I-668J-1455D01*
G01X126799D01*
G37*
G36*
G01X133330Y1208154D02*
G03X133000Y1207951I668J-1455D01*
G03X132000Y1208302I-1001J-1251D01*
G01X130600D01*
G03X130190Y1208248I2J-1602D01*
G02X129951Y1208374I-51J193D01*
G03X128920Y1209680I-2451J-875D01*
G01Y1213592D01*
X129076Y1213748D01*
Y1214111D01*
X133080D01*
Y1213912D01*
X134532Y1212459D01*
G02X134519Y1211882I-283J-282D01*
G03X133998Y1210700I1080J-1182D01*
G01Y1209757D01*
X133330Y1209088D01*
Y1208154D01*
G37*
G36*
G01X116499Y1296550D02*
X115499Y1297550D01*
Y1299521D01*
X118820Y1302843D01*
Y1302872D01*
X119499Y1303550D01*
Y1306050D01*
X120710Y1307260D01*
X121745D01*
X122035Y1307550D01*
X149999D01*
X150999Y1306550D01*
Y1298050D01*
X149499Y1296550D01*
X116499D01*
G37*
G36*
G01X109261Y1262050D02*
X108497Y1262814D01*
X106234D01*
X102499Y1266550D01*
Y1268550D01*
X103128Y1269180D01*
X125870D01*
X126124Y1268925D01*
X127064D01*
X127809Y1268180D01*
X135721D01*
X135999Y1267901D01*
Y1262814D01*
X112501D01*
X111737Y1262050D01*
X109261D01*
G37*
G36*
G01X180999Y1288550D02*
X153999D01*
X152999Y1289550D01*
Y1306550D01*
X155499Y1309050D01*
X179999D01*
X181999Y1307050D01*
Y1289550D01*
X180999Y1288550D01*
G37*
G36*
G01X111999Y1310550D02*
X109999Y1312550D01*
Y1319942D01*
X114395D01*
G03X115799Y1319112I1403J771D01*
G01X116066D01*
Y1315402D01*
X115497D01*
Y1310550D01*
X111999D01*
G37*
G36*
G01X104600Y1456268D02*
Y1463949D01*
X102542Y1466007D01*
G02X102683Y1466349I141J142D01*
G01X102901D01*
X102924Y1466343D01*
G03X103299Y1466298I377J1557D01*
G01X104699D01*
G03X106300Y1467900I0J1601D01*
G01Y1469300D01*
G03X105950Y1470300I-1601J1D01*
G03X106300Y1471300I-1251J999D01*
G01Y1472700D01*
G03X105879Y1473783I-1601J1D01*
G02X105869Y1474312I295J270D01*
G03X106250Y1475350I-1220J1037D01*
G01Y1476293D01*
X108821Y1478863D01*
G02X109503Y1478580I282J-283D01*
G01Y1477757D01*
G03X109148Y1476750I1247J-1006D01*
G01Y1475350D01*
G03X109569Y1474267I1601J-1D01*
G02X109579Y1473738I-295J-270D01*
G03X109198Y1472700I1220J-1037D01*
G01Y1471300D01*
G03X109548Y1470300I1601J-1D01*
G03X109198Y1469300I1251J-999D01*
G01Y1467900D01*
G03X110799Y1466298I1602J0D01*
G01X112199D01*
G03X112574Y1466343I-2J1602D01*
G01X112597Y1466348D01*
X113398D01*
Y1463962D01*
X105918Y1456483D01*
X105893Y1456469D01*
G03X105296Y1455999I1106J-2019D01*
G02X104600Y1456268I-296J269D01*
G37*
G36*
G01X203700Y1638898D02*
G03X203962Y1638920I-3J1602D01*
G01X204063Y1638937D01*
X204500Y1638500D01*
Y1635500D01*
X204000Y1635000D01*
X198499D01*
X196499Y1633000D01*
Y1631717D01*
X196493Y1631693D01*
G03X196448Y1631313I1556J-377D01*
G01Y1629913D01*
G03X196493Y1629533I1601J-3D01*
G01X196499Y1629509D01*
Y1626200D01*
X198200Y1624499D01*
Y1618000D01*
X195700Y1615500D01*
X178000D01*
X176500Y1617000D01*
Y1635800D01*
X178313Y1637613D01*
X196113D01*
X197500Y1639000D01*
X197638D01*
X197670Y1638989D01*
G03X198200Y1638898I532J1511D01*
G01X199800D01*
G03X200330Y1638989I-2J1602D01*
G01X200362Y1639000D01*
X201738D01*
X201770Y1638989D01*
G03X202300Y1638898I532J1511D01*
G01X203700D01*
G37*
G36*
G01X122499Y1718550D02*
X120999Y1720050D01*
Y1723050D01*
X113499Y1730550D01*
Y1735050D01*
X115298Y1736848D01*
X121792D01*
G03X123199Y1736012I1407J766D01*
G01X124799D01*
G03X126206Y1736848I0J1602D01*
G01X136078D01*
X136113Y1736834D01*
G03X136704Y1736722I588J1489D01*
G01X138304D01*
G03X138895Y1736834I3J1601D01*
G01X138930Y1736848D01*
X146001D01*
X146501Y1736348D01*
X146700D01*
X148499Y1734550D01*
Y1728050D01*
X145499Y1725050D01*
Y1723812D01*
X145488Y1723780D01*
G03X145398Y1723250I1511J-529D01*
G01Y1721948D01*
X144999Y1721550D01*
X143258D01*
X142499Y1722309D01*
Y1725050D01*
X141999Y1725550D01*
X135999D01*
X134999Y1724550D01*
Y1720550D01*
X132999Y1718550D01*
X122499D01*
G37*
G36*
G01X181452Y1695539D02*
X181435Y1695437D01*
G03X184437Y1692435I2565J-437D01*
G01X184539Y1692452D01*
X215180Y1661812D01*
Y1660500D01*
X194770D01*
G03X193914Y1661151I-1969J-1701D01*
G01X193883Y1661166D01*
X179362Y1675688D01*
Y1676398D01*
X180229D01*
X183102Y1679271D01*
Y1681563D01*
G03X179960Y1684700I-2002J1137D01*
G02X179362Y1685047I-198J347D01*
G01Y1688621D01*
G03X177473Y1692662I-1461J1779D01*
G02X176999Y1693055I-74J393D01*
G01Y1694921D01*
G02X177459Y1695317I400J0D01*
G03X177700Y1695298I246J1583D01*
G01X179300D01*
G03X180519Y1695861I0J1601D01*
G02X181106Y1695885I305J-259D01*
G01X181452Y1695539D01*
G37*
G36*
G01X110761Y1666550D02*
X110497Y1666814D01*
X106234D01*
X101999Y1671050D01*
Y1674550D01*
X102499Y1675050D01*
X135499D01*
X137499Y1673050D01*
Y1667050D01*
X136999Y1666550D01*
X110761D01*
G37*
G36*
G01X154999Y1712113D02*
X153999Y1713113D01*
Y1732113D01*
X155499Y1733613D01*
X174499D01*
X175798Y1732314D01*
Y1713412D01*
X174499Y1712113D01*
X154999D01*
G37*
G36*
G01X161909Y1810695D02*
G03X161698Y1816884I-3838J2967D01*
G02X161997Y1817550I299J266D01*
G01X259499D01*
X260499Y1816550D01*
Y1812050D01*
X258499Y1810050D01*
X162226D01*
G02X161909Y1810695I-1J400D01*
G37*
G36*
G01X241501Y1938752D02*
X239799Y1937050D01*
X232499D01*
X231499Y1938050D01*
Y1945050D01*
X225499Y1951050D01*
X209999D01*
X203499Y1944550D01*
X146499D01*
X145499Y1945550D01*
Y1951550D01*
X146499Y1952550D01*
X155600D01*
X158822Y1955772D01*
X196921D01*
X199748Y1958600D01*
X203449D01*
X203499Y1958550D01*
X216800D01*
X217001Y1958348D01*
X239998D01*
X240199Y1958550D01*
X240500D01*
X243100Y1961150D01*
Y1974000D01*
X247150Y1978050D01*
X282499D01*
X283499Y1977050D01*
Y1961050D01*
X282999Y1960550D01*
X275550D01*
X275000Y1960000D01*
Y1956500D01*
X274999Y1956499D01*
Y1941550D01*
X273499Y1940050D01*
X243499D01*
X242200Y1938752D01*
X241501D01*
G37*
G36*
G01X250050Y1900050D02*
X249031Y1899031D01*
X248981Y1899017D01*
G03X248949Y1899008I607J-2220D01*
G01X248922Y1899000D01*
X239200D01*
X237650Y1900550D01*
X229999D01*
X225999Y1904550D01*
Y1912550D01*
X223999Y1914550D01*
X213300D01*
X208752Y1910002D01*
X161798D01*
X161300Y1910500D01*
Y1910550D01*
X157300Y1914550D01*
X145999D01*
X145499Y1915050D01*
Y1922050D01*
X145999Y1922550D01*
X164490D01*
X164511Y1922530D01*
X211212D01*
X211651Y1922090D01*
X211701D01*
X212081Y1921710D01*
X221037D01*
X221856Y1922530D01*
X228005D01*
X231476Y1926000D01*
X242449D01*
X245499Y1929050D01*
X249999D01*
X251499Y1930550D01*
Y1931851D01*
X251700Y1932052D01*
Y1932752D01*
X252999Y1934050D01*
X258999D01*
X259999Y1933050D01*
Y1922050D01*
X258999Y1921050D01*
X252499D01*
X251200Y1919751D01*
Y1912662D01*
X251189Y1912630D01*
G03X251098Y1912100I1511J-532D01*
G01Y1910500D01*
G03X251189Y1909970I1602J2D01*
G01X251200Y1909938D01*
Y1909399D01*
X250798Y1908998D01*
Y1908298D01*
X250050Y1907550D01*
Y1900050D01*
G37*
G36*
G01X219499Y1937050D02*
X204999D01*
X202499Y1939550D01*
X145999D01*
X145499Y1940050D01*
Y1941550D01*
X146499Y1942550D01*
X204999D01*
X211499Y1949050D01*
X220499D01*
X221499Y1948050D01*
Y1939050D01*
X219499Y1937050D01*
G37*
G36*
G01X138499Y1957550D02*
X116999D01*
X115999Y1958550D01*
Y1979499D01*
X118000Y1981500D01*
X137500D01*
X139499Y1979501D01*
Y1958550D01*
X138499Y1957550D01*
G37*
G36*
G01X235641Y1928619D02*
G03X230393Y1929076I-2541J1181D01*
G01X230423Y1928965D01*
X229508Y1928050D01*
X227499D01*
X224820Y1925370D01*
X220680D01*
X219861Y1924552D01*
X213257D01*
X212877Y1924932D01*
X212827D01*
X212388Y1925370D01*
X166178D01*
X163999Y1927550D01*
Y1936050D01*
X164999Y1937050D01*
X202499D01*
X204073Y1935476D01*
X239924D01*
X241999Y1937550D01*
X248999D01*
X250499Y1936050D01*
Y1932550D01*
X248499Y1930550D01*
X244499D01*
X241999Y1928050D01*
X236003D01*
G02X235641Y1928619I0J400D01*
G37*
G36*
G01X217499Y1901050D02*
X215024Y1903524D01*
X161326D01*
X156492Y1908358D01*
Y1908486D01*
X156364D01*
X155300Y1909550D01*
X146499D01*
X145499Y1910550D01*
Y1912050D01*
X145999Y1912550D01*
X157200D01*
X160950Y1908800D01*
X209350D01*
X213100Y1912550D01*
X221499D01*
X222499Y1911550D01*
Y1902050D01*
X221499Y1901050D01*
X217499D01*
G37*
G36*
G01X209999Y18550D02*
X187499D01*
X183999Y22050D01*
Y37050D01*
X195499Y48550D01*
X208999D01*
X211999Y45550D01*
Y20550D01*
X209999Y18550D01*
G37*
G36*
G01X205100Y52300D02*
X204200Y53200D01*
Y60883D01*
X204435D01*
Y83435D01*
X205314Y84314D01*
X207670D01*
X207855Y84500D01*
X215800D01*
X216917Y83383D01*
Y60883D01*
X217000D01*
Y56000D01*
X213300Y52300D01*
X205100D01*
G37*
G36*
G01X229651Y72796D02*
X230855Y73999D01*
X230928Y74005D01*
G03X233044Y76121I-179J2295D01*
G01X233050Y76194D01*
X233700Y76845D01*
Y77752D01*
X234499Y78550D01*
X238499D01*
X238999Y78050D01*
Y74550D01*
X237950Y73502D01*
X236348D01*
Y71898D01*
X235999Y71550D01*
Y30550D01*
X234499Y29050D01*
X215999D01*
X214499Y30550D01*
Y51050D01*
X218999Y55550D01*
Y72050D01*
X219499Y72550D01*
X225499D01*
X225744Y72796D01*
X229651D01*
G37*
G36*
G01X182987Y492430D02*
X184786Y494228D01*
X184897Y494200D01*
G03X185299Y494148I405J1550D01*
G01X186699D01*
G03X188300Y495750I0J1601D01*
G01Y497150D01*
G03X186699Y498752I-1602J0D01*
G01X185299D01*
G03X185234Y498750I17J-1601D01*
G01X182664D01*
G03X182599Y498752I-82J-1599D01*
G01X181199D01*
G03X181134Y498750I17J-1601D01*
G01X180999D01*
X180399Y499350D01*
Y500550D01*
X180799Y500950D01*
X187000D01*
X187601Y500348D01*
X199001D01*
X201798Y497552D01*
Y487349D01*
X200499Y486050D01*
X189702D01*
G03X188327Y486779I-1702J-1550D01*
G01X188261Y486788D01*
X187199Y487850D01*
X182099D01*
X180999Y488950D01*
Y491750D01*
X181678Y492430D01*
X182987D01*
G37*
G36*
G01X208999Y526113D02*
X187499D01*
X186499Y527113D01*
Y551613D01*
X188499Y553613D01*
X195999D01*
X209999Y539613D01*
Y527113D01*
X208999Y526113D01*
G37*
G36*
G01X237913Y666822D02*
X234012Y662920D01*
X228488D01*
X222920Y668489D01*
Y673615D01*
G02X223602Y673898I400J0D01*
G01X226500Y671000D01*
X236469D01*
G02X236847Y670467I1J-400D01*
G03X237853Y667437I2453J-868D01*
G02X237913Y666822I-223J-332D01*
G37*
G36*
G01X197367Y820623D02*
G03X199587Y816531I2133J-1491D01*
G02X200000Y816132I13J-400D01*
G01Y810500D01*
X199420Y809920D01*
X192588D01*
X187920Y814589D01*
Y830788D01*
X187520Y831187D01*
Y832111D01*
X190748D01*
X190764Y832096D01*
Y827507D01*
G03X192373Y822619I1172J-2323D01*
G01X192475Y822636D01*
X193129Y821982D01*
X193143Y821927D01*
G03X194700Y820698I1557J372D01*
G01X196100D01*
G03X197100Y821049I-1J1602D01*
G03X197303Y820911I999J1252D01*
G02X197367Y820623I-100J-173D01*
G37*
G36*
G01X207900Y881100D02*
X207300Y881700D01*
Y887300D01*
X207900Y887900D01*
X210900D01*
X213400Y890400D01*
Y892995D01*
G03X213452Y896150I-1650J1605D01*
G01X213400Y896207D01*
Y896900D01*
X213798Y897298D01*
X222202D01*
X222798Y896702D01*
Y883898D01*
X220102Y881202D01*
X213001D01*
X212900Y881100D01*
X207900D01*
G37*
G36*
G01X185299Y844714D02*
G03X185187Y844711I-13J-1601D01*
G01X185096Y844704D01*
X184700Y845100D01*
Y846751D01*
X185499Y847550D01*
X192999D01*
X193449Y848000D01*
X210500D01*
X211500Y847000D01*
Y834500D01*
X209000Y832000D01*
X195500D01*
X195420Y832080D01*
Y835698D01*
X193531Y837588D01*
Y841082D01*
X193499Y841113D01*
Y844050D01*
X192949Y844600D01*
X191795D01*
X191761Y844613D01*
G03X191199Y844714I-560J-1500D01*
G01X189799D01*
G03X189237Y844613I-2J-1601D01*
G01X189203Y844600D01*
X187295D01*
X187261Y844613D01*
G03X186699Y844714I-560J-1500D01*
G01X185299D01*
G37*
G36*
G01X228498Y824998D02*
X235396Y831897D01*
G02X236079Y831614I283J-283D01*
G01Y828087D01*
X220738Y812747D01*
G02X220061Y812959I-283J282D01*
G03X217056Y815064I-2561J-459D01*
G01X216954Y815046D01*
X213763Y818237D01*
X213780Y818338D01*
G03X213802Y818600I-1580J265D01*
G01Y820000D01*
G03X213451Y821000I-1602J-1D01*
G03X213802Y822000I-1251J1001D01*
G01Y823400D01*
G03X212200Y825002I-1602J0D01*
G01X210800D01*
G03X210425Y824957I2J-1602D01*
G01X210402Y824952D01*
X209702D01*
Y831002D01*
X211115Y832416D01*
G02X211798Y832133I283J-283D01*
G01Y826903D01*
X213702Y824998D01*
X228498D01*
G37*
G36*
G01X215812Y899302D02*
X214800Y900313D01*
Y900947D01*
X211783Y903964D01*
X211097D01*
X211074Y903970D01*
G03X210699Y904014I-373J-1557D01*
G01X209980D01*
G02X209697Y904697I0J400D01*
G01X212500Y907500D01*
X225500D01*
X226161Y908161D01*
X232451D01*
Y908824D01*
G02X233134Y909107I400J0D01*
G01X233598Y908643D01*
Y907400D01*
G03X235200Y905798I1602J0D01*
G01X236078D01*
Y902230D01*
G03Y897870I1421J-2180D01*
G01Y878286D01*
G02X235396Y878003I-400J0D01*
G01X233148Y880252D01*
X225600D01*
X225498Y880498D01*
X225500Y880500D01*
X224000Y882000D01*
Y897500D01*
X223000Y898500D01*
X218087D01*
G03X216700Y899302I-1388J-800D01*
G01X215812D01*
G37*
G36*
G01X231999Y925113D02*
X212499D01*
X211499Y926113D01*
Y948613D01*
X213499Y950613D01*
X225999D01*
X233499Y943113D01*
Y926613D01*
X231999Y925113D01*
G37*
G36*
G01X373396Y699653D02*
X346797Y726252D01*
X311238D01*
G03X309799Y727152I-1440J-702D01*
G01X308199D01*
G03X306760Y726252I1J-1602D01*
G01X289741D01*
X289716Y726259D01*
G03X288401Y726287I-715J-2709D01*
G01X288294Y726264D01*
X287637Y726920D01*
X287628D01*
X283499Y731050D01*
Y736050D01*
X283999Y736550D01*
X305499D01*
X308999Y740050D01*
Y740788D01*
X309010Y740820D01*
G03X309100Y741350I-1511J529D01*
G01Y742750D01*
G03X309079Y743012I-1601J3D01*
G01X309062Y743113D01*
X309499Y743550D01*
X318999D01*
X319648Y742902D01*
Y738988D01*
X320660D01*
X321399Y738250D01*
X327907D01*
G03X328091I92J2300D01*
G01X336583D01*
X337999Y739666D01*
X370883D01*
X480499Y630050D01*
X557999D01*
X562499Y625550D01*
Y612550D01*
X557999Y608050D01*
X464999D01*
X377102Y695947D01*
G02X377179Y696574I282J284D01*
G03X374023Y699730I-1180J1976D01*
G02X373396Y699653I-343J205D01*
G37*
G36*
G01X292999Y697550D02*
X289499Y701050D01*
Y716550D01*
X297999Y725050D01*
X322798D01*
Y712962D01*
X307386Y697550D01*
X292999D01*
G37*
G36*
G01X284999Y699050D02*
X267499D01*
X266499Y700050D01*
Y723050D01*
X267499Y724050D01*
X283999D01*
X285499Y722550D01*
Y699550D01*
X284999Y699050D01*
G37*
G36*
G01X308598Y757657D02*
X306778Y755837D01*
X306686Y755844D01*
G03X304754Y755050I-186J-2294D01*
G01X290999D01*
X289499Y756550D01*
Y768050D01*
X290499Y769050D01*
X303050D01*
X304098Y770098D01*
X305450D01*
Y771422D01*
X306427Y772398D01*
X307800D01*
G03X308330Y772489I-2J1602D01*
G01X308362Y772500D01*
X309738D01*
X309770Y772489D01*
G03X310300Y772398I532J1511D01*
G01X311700D01*
G03X311962Y772420I-3J1602D01*
G01X312063Y772437D01*
X312500Y772000D01*
Y770500D01*
X311500Y769500D01*
X309000D01*
X308749Y769249D01*
Y759779D01*
X308732Y759741D01*
G03X308598Y759100I1468J-641D01*
G01Y757657D01*
G37*
G36*
G01X322999Y1936148D02*
Y1931550D01*
X322200Y1930752D01*
X288298D01*
X287499Y1931550D01*
Y1937550D01*
X288499Y1938550D01*
X290999D01*
X291499Y1939050D01*
Y1946050D01*
X291999Y1946550D01*
X294473D01*
X294514Y1946403D01*
G03X296058Y1945226I1544J424D01*
G01X297658D01*
G03X298972Y1945912I0J1601D01*
G02X299583Y1945966I328J-229D01*
G01X301499Y1944050D01*
X304999D01*
X306499Y1942550D01*
X306524D01*
G02X306807Y1941867I0J-400D01*
G01X306578Y1941638D01*
Y1940638D01*
X305439Y1939499D01*
X305394Y1939484D01*
G03X308461Y1938296I805J-2474D01*
G01X308386Y1938428D01*
X309420Y1939462D01*
Y1940462D01*
X311508Y1942550D01*
X311999D01*
X312999Y1943550D01*
Y1945050D01*
X313999Y1946050D01*
X321999D01*
X322280Y1945770D01*
Y1940503D01*
G03X322999Y1936148I1719J-1953D01*
G37*
G36*
G01X311176Y1961491D02*
G03X311183Y1961337I1601J-4D01*
G01X311192Y1961243D01*
X308499Y1958550D01*
X298032D01*
G03X295684I-1174J-2322D01*
G01X288499D01*
X285999Y1961050D01*
Y1972050D01*
X286999Y1973050D01*
X305999D01*
X306024Y1973024D01*
X306890D01*
X306914Y1972852D01*
G03X308500Y1971474I1586J224D01*
G01X310100D01*
G03X310369Y1971497I-1J1602D01*
G01X310385Y1971500D01*
X310500D01*
X311198Y1970802D01*
Y1969600D01*
G03X311499Y1968666I1602J1D01*
G01Y1967856D01*
G03X311176Y1966891I1278J-964D01*
G01Y1965491D01*
G03X311463Y1964575I1601J-1D01*
G01X311499Y1964524D01*
Y1963858D01*
X311463Y1963807D01*
G03X311176Y1962891I1314J-915D01*
G01Y1961491D01*
G37*
G36*
G01X264999Y1913550D02*
X263999Y1914550D01*
Y1933050D01*
X266499Y1935550D01*
X277999D01*
X282168Y1931381D01*
Y1931372D01*
X283212Y1930328D01*
X283205Y1930236D01*
G03X283499Y1928910I2294J-187D01*
G01Y1917550D01*
X279499Y1913550D01*
X264999D01*
G37*
G36*
G01X752496Y309550D02*
X749499Y314819D01*
Y319050D01*
X752073Y321624D01*
X752143Y321631D01*
G03X753580Y323224I-164J1593D01*
G01Y324624D01*
G03X753523Y325045I-1602J-2D01*
G02X753909Y325550I386J105D01*
G01X762499D01*
X763499Y324550D01*
Y321050D01*
X764499Y320050D01*
X777999D01*
X778499Y320550D01*
Y321288D01*
X778510Y321320D01*
G03X778600Y321850I-1511J529D01*
G01Y323250D01*
G03X778510Y323780I-1601J1D01*
G01X778499Y323812D01*
Y325288D01*
X778510Y325320D01*
G03X778600Y325850I-1511J529D01*
G01Y327152D01*
X778999Y327550D01*
X780499D01*
X780999Y327050D01*
Y323550D01*
X781499Y323050D01*
Y319550D01*
X783999Y317050D01*
X793999D01*
X794499Y316550D01*
Y310050D01*
X791499Y307050D01*
X765704D01*
X765680Y307056D01*
G03X765300Y307102I-381J-1556D01*
G01X763700D01*
G03X763320Y307056I1J-1602D01*
G01X763296Y307050D01*
X761198D01*
X760997Y307252D01*
X755798D01*
X753499Y309550D01*
X752496D01*
G37*
G36*
G01X763172Y295484D02*
X756965Y301692D01*
X754826Y305452D01*
G02X755174Y306050I348J198D01*
G01X760499D01*
X761499Y305050D01*
X792499D01*
X793499Y304050D01*
Y287550D01*
X792920Y286970D01*
X788179D01*
G03X783819I-2180J-1420D01*
G01X771685D01*
X763432Y295224D01*
X763405D01*
X763172Y295456D01*
Y295484D01*
G37*
G36*
G01X867499Y311550D02*
X866294Y310344D01*
X847564D01*
X846414Y311495D01*
X846437Y311602D01*
G03X841120Y311106I-2737J598D01*
G02X840752Y310550I-368J-156D01*
G01X819999D01*
X819499Y311050D01*
Y316050D01*
X819999Y316550D01*
X865499D01*
X867499Y314550D01*
Y311550D01*
G37*
G36*
G01X826499Y304050D02*
X829499Y307050D01*
X829500D01*
X830374Y307924D01*
X846051D01*
G03X847478Y307504I1426J2212D01*
G01X865898D01*
X872478Y300924D01*
X873426D01*
X873501Y300848D01*
X883554D01*
X884478Y299924D01*
Y293924D01*
X883478Y292924D01*
X867478D01*
X863478Y296924D01*
X852278D01*
X850778Y295424D01*
Y284924D01*
X849778Y283924D01*
X841600D01*
X839576Y281900D01*
X820199D01*
X819702Y282398D01*
Y285998D01*
X818999Y286700D01*
Y303050D01*
X819999Y304050D01*
X826499D01*
G37*
G36*
G01X812373Y310071D02*
X813873Y308571D01*
Y289071D01*
X812873Y288071D01*
X796373D01*
X794873Y289571D01*
Y308725D01*
X795700Y309552D01*
Y309898D01*
X795873Y310071D01*
X812373D01*
G37*
G36*
G01X774000Y345424D02*
Y345500D01*
X773500Y346000D01*
Y354000D01*
X773000Y354500D01*
X770362D01*
X770330Y354511D01*
G03X769800Y354602I-532J-1511D01*
G01X768200D01*
G03X767670Y354511I2J-1602D01*
G01X767638Y354500D01*
X766262D01*
X766230Y354511D01*
G03X765700Y354602I-532J-1511D01*
G01X764300D01*
G03X764038Y354580I3J-1602D01*
G01X763937Y354563D01*
X763500Y355000D01*
Y357000D01*
X766000Y359500D01*
X769500D01*
X770500Y360500D01*
Y370000D01*
X770798Y370298D01*
X784052D01*
X787000Y367351D01*
Y364446D01*
X786978Y364424D01*
Y346924D01*
X785478Y345424D01*
X774000D01*
G37*
G36*
G01X791999Y363050D02*
X794499Y365550D01*
X833251D01*
X835700Y363101D01*
Y342100D01*
X836750Y341050D01*
X837751D01*
X837952Y340848D01*
X873200D01*
X883499Y330550D01*
Y323050D01*
X882999Y322550D01*
X874499D01*
X864999Y332050D01*
X853999D01*
X851999Y330050D01*
Y321550D01*
X849499Y319050D01*
X806999D01*
X804499Y321550D01*
Y337100D01*
X801549Y340050D01*
X793999D01*
X791999Y342050D01*
Y363050D01*
G37*
G36*
G01X853278Y294924D02*
X854076Y295722D01*
X862180D01*
X866478Y291424D01*
X883978D01*
X884478Y290924D01*
Y287924D01*
X883978Y287424D01*
X870478D01*
X866978Y283924D01*
X854278D01*
X853278Y284924D01*
Y294924D01*
G37*
G36*
G01X866198Y317550D02*
X865997Y317752D01*
X857798D01*
X856499Y319050D01*
Y329550D01*
X857499Y330550D01*
X862499D01*
X872499Y320550D01*
X882999D01*
X883798Y319752D01*
Y317848D01*
X883499Y317550D01*
X866198D01*
G37*
G36*
G01X1014700Y1431300D02*
X952200D01*
X948000Y1435500D01*
Y1509100D01*
X949900Y1511000D01*
X1014500D01*
X1016200Y1509300D01*
Y1432800D01*
X1014700Y1431300D01*
G37*
%LPC*%
G75*
G36*
G01X63681Y452907D02*
G02X62186Y454764I-2281J-306D01*
G03X62719Y455193I137J376D01*
G02X64214Y453336I2281J306D01*
G03X63681Y452907I-137J-376D01*
G37*
G36*
G01X70932Y546685D02*
G02X70234Y544593I1568J-1686D01*
G03X69568Y544815I-394J-71D01*
G02X70266Y546907I-1568J1686D01*
G03X70932Y546685I394J71D01*
G37*
G36*
G01X34702Y105702D02*
Y98798D01*
X21298D01*
Y100048D01*
X16423D01*
X16396Y100040D01*
G02Y104460I-646J2210D01*
G01X16423Y104452D01*
X21298D01*
Y105702D01*
X34702D01*
G37*
G36*
G01X83081Y522367D02*
G02X82118Y521717I-2162J2165D01*
G01Y520672D01*
X72214D01*
Y528225D01*
X82118D01*
Y526920D01*
G02X82428Y526740I-1931J-3683D01*
G01X95240D01*
X96500Y528000D01*
X99298D01*
G02X100345Y528390I1048J-1212D01*
G01X101945D01*
G02X102945Y528039I-1J-1602D01*
G02X103945Y528390I1001J-1251D01*
G01X105545D01*
G02X107146Y526788I-1J-1602D01*
G01Y526500D01*
X110500D01*
X113000Y524000D01*
Y517500D01*
X111500Y516000D01*
X101500D01*
X101000Y515500D01*
Y514367D01*
X101017Y514328D01*
G02X99787Y511265I-2117J-928D01*
G01X99750Y511250D01*
X99500Y511000D01*
X94500D01*
X93500Y512000D01*
Y512240D01*
X93475Y512285D01*
G02X93500Y514559I2025J1115D01*
G01Y522660D01*
X83790D01*
G03X83659Y522652I-5J-1000D01*
G01X83657D01*
G03X83081Y522367I132J-992D01*
G37*
G36*
G01X82696Y531760D02*
G02X82118Y531313I-2019J2013D01*
G01Y530121D01*
X72214D01*
Y537674D01*
X82118D01*
Y536337D01*
G02X82660Y535901I-1744J-2723D01*
G03X82809Y535840I149J150D01*
G01X83886D01*
X83888Y536038D01*
G02X88510Y536025I2311J-13D01*
G01Y532249D01*
G02X83976Y531615I-2311J1D01*
G01X83935Y531760D01*
X82696D01*
G37*
G36*
G01X25302Y110298D02*
X23198Y112402D01*
Y138598D01*
X25302Y140702D01*
X37998D01*
X40202Y138498D01*
Y114002D01*
X36498Y110298D01*
X25302D01*
G37*
G36*
G01X56702Y711502D02*
X50498Y705298D01*
X32002D01*
X26298Y711002D01*
Y742498D01*
X31002Y747202D01*
X53498D01*
X56702Y743998D01*
Y711502D01*
G37*
G36*
G01X91532Y903606D02*
X93963D01*
G02X92835Y900764I1036J-2056D01*
G01X91532D01*
Y899664D01*
X79728D01*
Y904666D01*
X91532D01*
Y903606D01*
G37*
G36*
G01X29702Y899298D02*
Y898912D01*
X30081Y898533D01*
X30106Y898519D01*
G02X26981Y895394I-1106J-2019D01*
G01X26967Y895419D01*
X25298Y897088D01*
Y899298D01*
X20798D01*
Y906202D01*
X34202D01*
Y899298D01*
X29702D01*
G37*
G36*
G01X93001Y896252D02*
X98497D01*
X100200Y894548D01*
Y890052D01*
X99467Y889319D01*
X99600Y889178D01*
G02X99757Y888993I-1903J-1774D01*
G01X99765Y888983D01*
X100200Y888548D01*
Y888120D01*
X100208Y888094D01*
G02Y886706I-2508J-694D01*
G01X100200Y886680D01*
Y883616D01*
G02X100222Y881226I-2300J-1216D01*
G01X100200Y881183D01*
Y881052D01*
X99965Y880817D01*
X99957Y880807D01*
G02X99493Y880343I-2057J1593D01*
G01X99483Y880335D01*
X97997Y878848D01*
X81001D01*
X80187Y879663D01*
X79728D01*
Y880122D01*
X79298Y880552D01*
Y889548D01*
X79728Y889978D01*
Y894667D01*
X81417D01*
X81501Y894752D01*
X91501D01*
X93001Y896252D01*
G37*
G36*
G01X91532Y870764D02*
Y869664D01*
X79728D01*
Y874666D01*
X91532D01*
Y873606D01*
X107403D01*
G02X107840Y870764I2596J-1055D01*
G01X91532D01*
G37*
G36*
G01X98497Y848348D02*
X81501D01*
X80187Y849663D01*
X79728D01*
Y864667D01*
X81417D01*
X81501Y864752D01*
X91501D01*
X93001Y866252D01*
X98497D01*
X100200Y864548D01*
Y860052D01*
X99448Y859300D01*
X100700Y858048D01*
Y850552D01*
X98497Y848348D01*
G37*
G36*
G01X19578Y1317696D02*
Y1318739D01*
G02X22420I1421J1811D01*
G01Y1317090D01*
G02X19578Y1317696I-1921J-2040D01*
G37*
G36*
G01X49302Y1864098D02*
X44712D01*
X42533Y1861919D01*
X42519Y1861894D01*
G02X38276Y1863595I-2019J1106D01*
G03X37890Y1864098I-386J103D01*
G01X35898D01*
Y1871002D01*
X49302D01*
Y1864098D01*
G37*
G36*
G01X712850Y1797703D02*
Y1797234D01*
G02X712762Y1796708I-1601J-2D01*
G01X712750Y1796676D01*
Y1784537D01*
X706412Y1778198D01*
X536776D01*
X522406Y1763828D01*
X350823D01*
G03X350479Y1763224I0J-400D01*
G02X346519I-1980J-1174D01*
G03X346175Y1763828I-344J204D01*
G01X327688D01*
G02Y1768232I-1387J2202D01*
G01X520582D01*
X534952Y1782602D01*
X541784D01*
G03X542119Y1783220I0J400D01*
G02X545687Y1786840I2181J1418D01*
G01X638887D01*
X641848Y1789800D01*
Y1791676D01*
X641836Y1791708D01*
G02X641748Y1792234I1513J524D01*
G01Y1793637D01*
G02X641778Y1793944I1601J-1D01*
G01X641782Y1793963D01*
Y1794182D01*
X641427D01*
X641389Y1794166D01*
G02X640749Y1794032I-641J1468D01*
G01X639349D01*
G02X638709Y1794166I1J1602D01*
G01X638671Y1794182D01*
X636195D01*
G02X633302Y1797990I-2264J1283D01*
G01X633356Y1798003D01*
X633938Y1798586D01*
X638951D01*
X638974Y1798591D01*
G02X639349Y1798636I377J-1557D01*
G01X640749D01*
G02X641124Y1798591I-2J-1602D01*
G01X641147Y1798586D01*
X642951D01*
X642974Y1798591D01*
G02X643349Y1798636I377J-1557D01*
G01X644749D01*
G02X645682Y1798336I0J-1601D01*
G01X647091D01*
X647123Y1798347D01*
G02X647649Y1798436I527J-1513D01*
G01X649049D01*
G02X650049Y1798085I-1J-1602D01*
G02X651049Y1798436I1001J-1251D01*
G01X652449D01*
G02X652975Y1798347I-1J-1602D01*
G01X653007Y1798336D01*
X653586D01*
G02X654749Y1798836I1163J-1103D01*
G01X656349D01*
G02X657208Y1798586I0J-1601D01*
G01X662215D01*
G02X663920Y1799961I2334J-1150D01*
G01X663974Y1799974D01*
X667444Y1803445D01*
G02X668564Y1804046I1557J-1557D01*
G01X668623Y1804058D01*
X668780Y1804214D01*
G03X668497Y1804897I-283J283D01*
G01X662834D01*
G03X662450Y1804387I1J-400D01*
G02X658562Y1801468I-2501J-717D01*
G01X656247D01*
X656211Y1801432D01*
X653007D01*
X652975Y1801421D01*
G02X652449Y1801332I-527J1513D01*
G01X651049D01*
G02X650049Y1801683I1J1602D01*
G02X649049Y1801332I-1001J1251D01*
G01X647649D01*
G02X646650Y1801682I0J1601D01*
G01X645147D01*
X645124Y1801677D01*
G02X644749Y1801632I-377J1557D01*
G01X643349D01*
G02X642974Y1801677I2J1602D01*
G01X642951Y1801682D01*
X641147D01*
X641124Y1801677D01*
G02X640749Y1801632I-377J1557D01*
G01X639661D01*
X638877Y1800848D01*
X636386D01*
G02X632826Y1804481I-1387J2202D01*
G03X632671Y1805058I-334J219D01*
G02X635224Y1809586I1167J2326D01*
G01X638951D01*
X638974Y1809591D01*
G02X639349Y1809636I377J-1557D01*
G01X640749D01*
G02X642350Y1808034I-1J-1602D01*
G01Y1806631D01*
G02X642320Y1806324I-1601J1D01*
G01X642316Y1806305D01*
Y1806086D01*
X642671D01*
X642709Y1806102D01*
G02X643349Y1806236I641J-1468D01*
G01X644749D01*
G02X645389Y1806102I-1J-1602D01*
G01X645427Y1806086D01*
X648961D01*
X649110Y1805936D01*
X649183Y1805930D01*
G02X650049Y1805585I-134J-1596D01*
G02X651049Y1805936I1001J-1251D01*
G01X652449D01*
G02X652975Y1805847I-1J-1602D01*
G01X653007Y1805836D01*
X653586D01*
G02X654749Y1806336I1163J-1103D01*
G01X656349D01*
G02X657148Y1806122I-1J-1602D01*
G03X657748Y1806468I200J347D01*
G01Y1807229D01*
X658962Y1808444D01*
G02X660082Y1809045I1557J-1557D01*
G01X660141Y1809057D01*
X661550Y1810466D01*
X662197D01*
Y1811214D01*
X658246D01*
G03X657847Y1810791I0J-400D01*
G02X652503Y1809464I-2798J-157D01*
G01X651153D01*
G02X649749Y1808632I-1404J769D01*
G01X648349D01*
G02X646748Y1810234I1J1602D01*
G01Y1811634D01*
G02X646752Y1811753I1601J6D01*
G03X646353Y1812182I-399J29D01*
G01X645887D01*
X645214Y1812856D01*
X645152Y1812867D01*
G02X643642Y1816423I397J2267D01*
G03X643466Y1817016I-331J224D01*
G02X645006Y1821347I894J2122D01*
G01X645033Y1821338D01*
X648208D01*
X648610Y1820936D01*
X648683Y1820930D01*
G02X649549Y1820585I-134J-1596D01*
G02X650549Y1820936I1001J-1251D01*
G01X651949D01*
G02X653166Y1820375I0J-1601D01*
G01X653226Y1820304D01*
X653441D01*
X653500Y1820397D01*
G02X654849Y1821136I1349J-862D01*
G01X655792D01*
X658711Y1824054D01*
X659369D01*
G02X663729I2180J-1420D01*
G01X665137D01*
X667820Y1821372D01*
Y1816371D01*
X670601D01*
Y1808500D01*
X670730D01*
X672852Y1806379D01*
Y1803191D01*
X671171Y1801510D01*
X671159Y1801451D01*
G02X670558Y1800331I-2158J437D01*
G01X667087Y1796861D01*
X667074Y1796807D01*
G02X665178Y1794911I-2525J629D01*
G01X665124Y1794898D01*
X664409Y1794182D01*
X657027D01*
X656989Y1794166D01*
G02X656389Y1794033I-640J1468D01*
G01X656309Y1794031D01*
X656211Y1793932D01*
X653007D01*
X652975Y1793921D01*
G02X652449Y1793832I-527J1513D01*
G01X651049D01*
G02X650049Y1794183I1J1602D01*
G02X649049Y1793832I-1001J1251D01*
G01X647649D01*
G02X647123Y1793921I1J1602D01*
G01X647091Y1793932D01*
X646348D01*
Y1793722D01*
G02X646350Y1793634I-1599J-80D01*
G01Y1792234D01*
G02X646262Y1791708I-1601J-2D01*
G01X646250Y1791676D01*
Y1787976D01*
X641559Y1783284D01*
G03X641842Y1782602I283J-282D01*
G01X704588D01*
X708348Y1786361D01*
Y1796676D01*
X708336Y1796708D01*
G02X708248Y1797234I1513J524D01*
G01Y1798637D01*
G02X708278Y1798944I1601J-1D01*
G01X708282Y1798963D01*
Y1799182D01*
X707927D01*
X707889Y1799166D01*
G02X707249Y1799032I-641J1468D01*
G01X705849D01*
G02X704790Y1799432I0J1602D01*
G01X702007D01*
X701975Y1799421D01*
G02X701449Y1799332I-527J1513D01*
G01X700049D01*
G02X699049Y1799683I1J1602D01*
G02X698049Y1799332I-1001J1251D01*
G01X696649D01*
G02X695700Y1799644I1J1602D01*
G01X695648Y1799682D01*
X695027D01*
X694989Y1799666D01*
G02X694389Y1799533I-640J1468D01*
G01X694309Y1799531D01*
X694161Y1799382D01*
X693134D01*
X690684Y1796932D01*
X686936D01*
G02X683024Y1798505I-1387J2202D01*
G01X683011Y1798559D01*
X680348Y1801222D01*
Y1803637D01*
G02X680472Y1804364I2201J-1D01*
G03X680095Y1804897I-377J133D01*
G01X678497D01*
Y1811184D01*
X674152D01*
X671828Y1813507D01*
Y1821261D01*
X677222Y1826654D01*
X679369D01*
G02X683729I2180J-1420D01*
G01X691573D01*
X691616Y1826797D01*
G02X693149Y1827936I1533J-462D01*
G01X694549D01*
G02X695549Y1827585I-1J-1602D01*
G02X696549Y1827936I1001J-1251D01*
G01X697949D01*
G02X699542Y1826501I0J-1602D01*
G01X699561Y1826322D01*
X709696D01*
G02X713444Y1823845I2152J-818D01*
G03X713428Y1823573I138J-145D01*
G02X709450Y1821438I-1776J-1464D01*
G01X709407Y1821580D01*
X699550D01*
Y1820932D01*
G02X697949Y1819332I-1601J1D01*
G01X696549D01*
G02X695549Y1819683I1J1602D01*
G02X694549Y1819332I-1001J1251D01*
G01X693149D01*
G02X691560Y1820738I0J1601D01*
G01X691538Y1820914D01*
X689229D01*
G02X684869I-2180J1420D01*
G01X678186D01*
X676570Y1819297D01*
Y1816088D01*
X676668Y1815990D01*
X678498D01*
Y1816370D01*
X686900D01*
Y1815090D01*
G03X687583Y1814808I400J1D01*
G01X687620Y1814844D01*
X687646D01*
X688387Y1815586D01*
X692071D01*
X692109Y1815602D01*
G02X692749Y1815736I641J-1468D01*
G01X694349D01*
G02X694989Y1815602I-1J-1602D01*
G01X695027Y1815586D01*
X695556D01*
Y1815628D01*
X698371Y1818444D01*
X705329D01*
X705929Y1817844D01*
X707082D01*
G02Y1813356I518J-2244D01*
G01X704071D01*
X703471Y1813956D01*
X700229D01*
X700150Y1813877D01*
Y1812332D01*
G02X699739Y1811262I-1601J1D01*
G03X699905Y1810929I149J-134D01*
G02X700049Y1810936I150J-1595D01*
G01X701449D01*
G02X701975Y1810847I-1J-1602D01*
G01X702007Y1810836D01*
X707291D01*
X707323Y1810847D01*
G02X707849Y1810936I527J-1513D01*
G01X709249D01*
G02X709889Y1810802I-1J-1602D01*
G01X709927Y1810786D01*
X710282D01*
Y1811005D01*
X710278Y1811024D01*
G02X710248Y1811331I1571J308D01*
G01Y1812736D01*
G02X711849Y1814336I1601J-1D01*
G01X713249D01*
G02X713624Y1814291I-2J-1602D01*
G01X713647Y1814286D01*
X715224D01*
G02X719563Y1811935I1776J-1902D01*
G03X720003Y1811469I394J-69D01*
G02X719609Y1806375I297J-2585D01*
G01X719583Y1806382D01*
X719176D01*
Y1806090D01*
X719246Y1806030D01*
G02X718086Y1801496I-1682J-1985D01*
G03X717818Y1800908I80J-392D01*
G02X713557Y1797960I-2269J-1274D01*
G03X712850Y1797703I-307J-257D01*
G37*
G36*
G01X811498Y1485162D02*
X812101D01*
G03X812486Y1485671I0J400D01*
G02X813151Y1488003I2214J629D01*
G03X812882Y1488698I-270J295D01*
G01X810312D01*
X803462Y1481848D01*
X758672D01*
X758645Y1481840D01*
G02Y1486260I-646J2210D01*
G01X758672Y1486252D01*
X801638D01*
X805833Y1490447D01*
G03X805551Y1491130I-283J283D01*
G01X793679D01*
G02X789319I-2180J1420D01*
G01X757411D01*
X739578Y1508962D01*
Y1551087D01*
X743662Y1555170D01*
X748846D01*
G02X749049Y1555500I1455J-668D01*
G02X748698Y1556500I1251J1001D01*
G01Y1557900D01*
G02X748774Y1558387I1602J-1D01*
G01Y1558551D01*
G02X749000Y1562573I1226J1948D01*
G01Y1568000D01*
X752500Y1571500D01*
X770000D01*
X771298Y1572798D01*
Y1574998D01*
X773002Y1576702D01*
X785498D01*
X789528Y1572671D01*
Y1552298D01*
X787325Y1550094D01*
X783779D01*
Y1546344D01*
X774875D01*
Y1547616D01*
X774714Y1547778D01*
G03X774085Y1547696I-283J-283D01*
G02X773951Y1547500I-1385J803D01*
G02X774302Y1546500I-1251J-1001D01*
G01Y1545100D01*
G02X774256Y1544721I-1602J2D01*
G03X774587Y1544231I389J-94D01*
G02X771649Y1542093I-373J-2575D01*
G01X771666Y1542195D01*
X770579Y1543282D01*
Y1543670D01*
G02X769763Y1544650I721J1430D01*
G01X769721Y1544794D01*
X763940D01*
Y1544648D01*
X762329Y1543036D01*
Y1542234D01*
X755985D01*
G02X755419Y1541566I-1458J662D01*
G03X755358Y1540951I222J-333D01*
G01X757710Y1538599D01*
X757788Y1538596D01*
G02X759125Y1537776I-61J-1600D01*
G01X759976D01*
Y1538358D01*
X767178D01*
Y1535798D01*
X773440D01*
G02X776812Y1534347I1137J-2002D01*
G01X776850Y1534194D01*
X778181D01*
G02X779003Y1533967I0J-1602D01*
G01X779137Y1533887D01*
X779501Y1534252D01*
X781497D01*
X781552Y1534196D01*
X781631Y1534194D01*
G02X783182Y1532593I-51J-1601D01*
G01Y1532483D01*
X783200Y1532465D01*
Y1531598D01*
G03X783733Y1531221I400J0D01*
G02X785174Y1531251I766J-2171D01*
G03X785692Y1531633I118J382D01*
G01Y1532730D01*
X788251D01*
Y1539230D01*
X788832D01*
Y1542892D01*
X789212Y1543272D01*
X789205Y1543364D01*
G02X793310Y1544970I2294J185D01*
G01X794500D01*
Y1546300D01*
X794567D01*
G03X794708Y1546641I0J200D01*
G01X793798Y1547552D01*
Y1567548D01*
X796001Y1569752D01*
X834448D01*
X837502Y1566698D01*
Y1549752D01*
X882497D01*
X884273Y1547975D01*
X884839D01*
Y1547409D01*
X885200Y1547048D01*
Y1538552D01*
X884839Y1538191D01*
Y1537409D01*
X885200Y1537048D01*
Y1533552D01*
X884839Y1533191D01*
Y1532971D01*
X884619D01*
X883997Y1532348D01*
X870497D01*
X865704Y1527556D01*
G03X865987Y1526874I283J-282D01*
G01X873036D01*
Y1527974D01*
X884838D01*
Y1522972D01*
X873036D01*
Y1524032D01*
X863988D01*
X862793Y1525228D01*
X857333D01*
X856031Y1526530D01*
X820987D01*
X818400Y1523942D01*
Y1521174D01*
X826697D01*
Y1519252D01*
X833511D01*
X833536Y1519226D01*
X838057D01*
X839329Y1520498D01*
X869325D01*
X871325Y1518498D01*
X884825D01*
X886528Y1516794D01*
Y1508798D01*
X885526Y1507796D01*
X886528Y1506794D01*
Y1503798D01*
X884825Y1502094D01*
X871325D01*
X863879Y1494649D01*
G03X864162Y1493966I283J-283D01*
G01X866907D01*
X869834Y1496894D01*
X873036D01*
Y1497974D01*
X884838D01*
Y1492972D01*
X873036D01*
Y1494052D01*
X871010D01*
X868083Y1491126D01*
X861081D01*
G02X859627Y1490194I-1455J669D01*
G01X858027D01*
G02X857535Y1490272I2J1602D01*
G03X857056Y1490072I-122J-381D01*
G02X856687Y1489596I-1428J726D01*
G03Y1488996I265J-300D01*
G02X857228Y1487796I-1060J-1200D01*
G01Y1485196D01*
G02X856455Y1483825I-1602J0D01*
G03X856351Y1483231I207J-342D01*
G02X856065Y1479659I-2024J-1635D01*
G03X856035Y1479093I267J-298D01*
G02X852619I-1708J-1543D01*
G03X852589Y1479659I-297J268D01*
G02X852053Y1480332I1739J1935D01*
G03X851420Y1480420I-350J-194D01*
G01X850600Y1479600D01*
X847845D01*
G03X847559Y1478920I0J-400D01*
G02X843135Y1477537I-1859J-1820D01*
G01X843152Y1477639D01*
X841191Y1479600D01*
X839602D01*
Y1477600D01*
G02X838320Y1475733I-2002J1D01*
G01Y1473052D01*
G02X835480Y1473448I-1720J-1952D01*
G01Y1475733D01*
G02X834205Y1477445I720J1867D01*
G01X834190Y1477630D01*
X828712D01*
X827943Y1478398D01*
X827000D01*
G02X825680Y1479093I0J1601D01*
G01X825621Y1479180D01*
X825302D01*
Y1476038D01*
X824102D01*
Y1472363D01*
G02Y1469037I-2002J-1663D01*
G01Y1467938D01*
X824126Y1467894D01*
G02X820074I-2026J-1094D01*
G01X820098Y1467938D01*
Y1469037D01*
G02Y1472363I2002J1663D01*
G01Y1476038D01*
X818898D01*
Y1479180D01*
X817902D01*
Y1476038D01*
X811098D01*
X811054Y1476014D01*
G02Y1480066I-1094J2026D01*
G01X811098Y1480042D01*
X811498D01*
Y1485162D01*
G37*
G36*
G01X880897Y1054440D02*
X881923D01*
X882167Y1054683D01*
X882367Y1054883D01*
G02X882449Y1054962I1900J-1891D01*
G01Y1056493D01*
X892353D01*
Y1048940D01*
X882449D01*
Y1050360D01*
X880429D01*
X880401Y1050290D01*
G02X875928Y1050912I-2168J806D01*
G01X875659Y1054302D01*
G02X880269Y1054668I2305J183D01*
G01X880281Y1054527D01*
G03X880897Y1054440I617J2144D01*
G37*
G36*
G01X880882Y976990D02*
Y977458D01*
G03X880199Y977741I-400J0D01*
G01X880047Y977589D01*
X880064Y977487D01*
G02X877936Y979615I-2565J-437D01*
G01X878038Y979598D01*
X880911Y982470D01*
X885587D01*
X888004Y980054D01*
Y977996D01*
G02X888663Y977312I-772J-1403D01*
G01X892161D01*
X892401Y977073D01*
X898805D01*
G03X899130Y977706I0J400D01*
G02X903018Y980156I1869J1344D01*
G01X903032Y980131D01*
X906748Y976415D01*
G02X906833Y976352I-915J-1323D01*
G01X906956Y976432D01*
G02X907833Y976694I878J-1340D01*
G01X909233D01*
G02X910834Y975092I-1J-1602D01*
G01Y973802D01*
X918000D01*
Y972520D01*
X927319D01*
G02Y969680I2180J-1420D01*
G01X925500D01*
Y964524D01*
X923470D01*
Y963230D01*
G02X919869Y959630I-1421J-2180D01*
G01X917111D01*
X916942Y959798D01*
X915899D01*
G02X914899Y960149I1J1602D01*
G02X913899Y959798I-1001J1251D01*
G01X912856D01*
X910687Y957630D01*
X902961D01*
X900777Y959813D01*
X900685Y959806D01*
G02X902793Y961914I-186J2294D01*
G01X902786Y961822D01*
X903223Y961385D01*
X903435Y961596D01*
X903421Y961695D01*
G02X903644Y963156I2578J354D01*
G01X903662Y963196D01*
Y964288D01*
G02X902832Y965691I771J1403D01*
G01Y966635D01*
X900397Y969069D01*
X896920D01*
Y964806D01*
G02X894078Y965484I-1921J-1756D01*
G01Y969069D01*
X889792D01*
Y970038D01*
X888343D01*
G02X888224Y969934I-1112J1152D01*
G03X888222Y969621I123J-157D01*
G02X884382Y968988I-1639J-2021D01*
G03X884002Y969599I-338J213D01*
G02X883833Y969590I-170J1593D01*
G01X882433D01*
G02X881907Y969679I1J1602D01*
G01X881875Y969690D01*
X880381D01*
X880354Y969682D01*
G02Y974102I-646J2210D01*
G01X880381Y974094D01*
X880558D01*
G03X880932Y974633I-1J400D01*
G02X880832Y975192I1501J557D01*
G01Y976592D01*
G02X880876Y976967I1601J2D01*
G01X880882Y976990D01*
G37*
G36*
G01X147688Y239729D02*
Y243504D01*
G02X152279Y243886I2311J0D01*
G01X152307Y243720D01*
X153220D01*
X153474Y243974D01*
G02X154103Y244419I1617J-1619D01*
G01Y245469D01*
X164007D01*
Y237916D01*
X154103D01*
Y238945D01*
G02X153453Y239405I1020J2130D01*
G01X153234Y239624D01*
G03X153199Y239638I-34J-35D01*
G01X152316D01*
X152295Y239463D01*
G02X147688Y239729I-2296J266D01*
G37*
G36*
G01X385700Y23551D02*
Y14552D01*
X382997Y11848D01*
X368501D01*
X366298Y14052D01*
Y32089D01*
X364798Y33588D01*
Y40548D01*
X364098D01*
X364075Y40543D01*
G02X363700Y40498I-377J1557D01*
G01X362300D01*
G02X362231Y40500I12J1602D01*
G03X361931Y39818I-17J-399D01*
G01X364200Y37548D01*
Y12001D01*
X361498Y9298D01*
X320502D01*
X318398Y11402D01*
Y25898D01*
X310499D01*
Y25050D01*
X288999D01*
X288150Y25898D01*
X287202D01*
X285898Y27202D01*
Y28150D01*
X282499Y31550D01*
Y34851D01*
X282298Y35052D01*
Y46548D01*
X286501Y50752D01*
X296997D01*
X297198Y50550D01*
X310499D01*
Y50314D01*
X317200D01*
Y50252D01*
X326497D01*
X326547Y50202D01*
X329998D01*
X335998Y44202D01*
X357547D01*
X360018Y41731D01*
G03X360700Y42031I283J283D01*
G02X360698Y42100I1600J81D01*
G01Y43500D01*
G02X361049Y44500I1602J-1D01*
G02X360846Y44830I1252J998D01*
G01X359662D01*
X359539Y44952D01*
X359437Y44935D01*
G02X358304Y44993I-437J2565D01*
G01X358278Y45000D01*
X358000D01*
X357818Y45182D01*
X357791Y45196D01*
G02X356696Y46291I1209J2304D01*
G01X356682Y46318D01*
X355500Y47500D01*
Y59000D01*
X355806Y59306D01*
G03X355523Y59988I-283J282D01*
G01X350648D01*
Y62548D01*
X344006D01*
X343625Y62167D01*
G02X340065Y61249I-2126J883D01*
G03X339533Y61219I-249J-313D01*
G02X338399Y60748I-1134J1130D01*
G01X336999D01*
G02X335999Y61099I1J1602D01*
G02X334999Y60748I-1001J1251D01*
G01X333599D01*
G02X331998Y62350I1J1602D01*
G01Y63750D01*
G02X332042Y64125I1601J2D01*
G01X332048Y64148D01*
Y65952D01*
X332042Y65975D01*
G02X331998Y66350I1557J373D01*
G01Y66447D01*
G03X331315Y66730I-400J0D01*
G01X323934Y59348D01*
X296282D01*
G02X295302Y59012I-981J1266D01*
G01X292696D01*
G02X291716Y59348I1J1602D01*
G01X290501D01*
X287298Y62552D01*
Y67548D01*
X288916Y69166D01*
G03X288633Y69849I-283J283D01*
G01X287501D01*
X285798Y71552D01*
Y82048D01*
X286872Y83122D01*
G03X286657Y83799I-283J283D01*
G02X284920Y84942I443J2564D01*
G01X283349D01*
X283078Y85213D01*
X282986Y85206D01*
G02X284861Y88525I-186J2294D01*
G03X285470Y88391I358J178D01*
G02X289280Y87784I1630J-2028D01*
G01X290745D01*
G02X292199Y88714I1454J-672D01*
G01X293802D01*
G02X294291Y88637I-2J-1601D01*
G03X294770Y88837I122J381D01*
G02X295139Y89313I1428J-726D01*
G03Y89913I-265J300D01*
G02X294598Y91113I1060J1200D01*
G01Y93713D01*
G02X295914Y95289I1602J0D01*
G01X296078Y95319D01*
Y95736D01*
X296008Y95796D01*
G02X295513Y98714I1491J1754D01*
G03X295212Y99314I-345J202D01*
G02X297680Y103320I288J2586D01*
G01X300188D01*
X302407Y101102D01*
X303825D01*
G02X305826Y99100I-1J-2002D01*
G01Y96200D01*
G02X304546Y94333I-2002J0D01*
G01Y93913D01*
X305457Y93002D01*
X306400D01*
G02X308002Y91400I0J-1602D01*
G01Y90000D01*
G02X307925Y89512I-1602J3D01*
G01X307916Y89483D01*
Y89252D01*
X308291D01*
G02X308403Y89285I710J-2202D01*
G01X313605Y94486D01*
X312180Y95912D01*
Y103238D01*
X312379Y103438D01*
G03X312238Y103779I-141J141D01*
G01X309709D01*
X309699Y103590D01*
G02X307700Y101698I-1999J110D01*
G01X306300D01*
G02X304298Y103700I0J2002D01*
G01Y106600D01*
G02X305736Y108520I2001J0D01*
G01X305880Y108563D01*
Y111120D01*
G02X308720I1420J2180D01*
G01Y108322D01*
G02X309691Y106800I-1020J-1722D01*
G01X309710Y106620D01*
X314070D01*
G02X315500Y107502I1431J-720D01*
G01X316900D01*
G02X317900Y107151I-1J-1602D01*
G02X318900Y107502I1001J-1251D01*
G01X320300D01*
G02X320826Y107413I-1J-1602D01*
G01X320858Y107402D01*
X322727D01*
X322754Y107410D01*
G02Y102990I646J-2210D01*
G01X322727Y102998D01*
X320858D01*
X320826Y102987D01*
G02X320300Y102898I-527J1513D01*
G01X318900D01*
G02X317900Y103249I1J1602D01*
G02X317387Y102974I-1001J1251D01*
G03X317256Y102283I122J-381D01*
G02X318006Y101159I-1456J-1783D01*
G01X318020Y101110D01*
X319402Y99729D01*
Y99462D01*
X320602D01*
Y96320D01*
X321598D01*
Y99462D01*
X340531D01*
X341298Y100228D01*
Y118997D01*
X344002Y121702D01*
X372498D01*
X375702Y118498D01*
Y100002D01*
X372998Y97298D01*
X362551D01*
X362501Y97348D01*
X344079D01*
X342189Y95458D01*
X328002D01*
Y90338D01*
X327448D01*
G03X327056Y89858I0J-400D01*
G02X327048Y88903I-2256J-459D01*
G03X327721Y88534I391J-86D01*
G01X332001Y92814D01*
X357334D01*
X358800Y91348D01*
Y91002D01*
X363451D01*
Y87970D01*
X364356D01*
G02X365700Y88702I1345J-870D01*
G01X367300D01*
G02X368748Y87785I0J-1602D01*
G01X368802Y87670D01*
X370932D01*
X370964Y87681D01*
G02X369542Y84699I736J-2181D01*
G01X369493Y84830D01*
X368754D01*
G02X367300Y83898I-1455J669D01*
G01X365700D01*
G02X364181Y84993I0J1601D01*
G01X364135Y85130D01*
X363451D01*
Y82098D01*
X358800D01*
Y79715D01*
X356997Y77912D01*
X342497D01*
X337519Y72934D01*
G03X337802Y72252I283J-282D01*
G01X350298D01*
Y72548D01*
X352501Y74752D01*
X400997D01*
X403200Y72548D01*
Y58549D01*
G03X403411Y58349I200J0D01*
G02X403499Y58352I99J-1599D01*
G01X404899D01*
G02X406329Y57470I-1J-1602D01*
G01X408587D01*
X409460Y56598D01*
X409562Y56615D01*
G02Y51485I437J-2565D01*
G01X409460Y51502D01*
X407587Y49630D01*
X407411D01*
G03X407270Y49288I0J-200D01*
G01X407920Y48638D01*
Y43462D01*
X406249Y41791D01*
G03X406261Y41214I283J-283D01*
G02X402523Y37608I-1762J-1914D01*
G03X401915I-304J-260D01*
G02X400699Y37048I-1217J1042D01*
G01X399299D01*
G02X398065Y37630I1J1601D01*
G01X397401D01*
Y37048D01*
X391920D01*
Y26462D01*
X390087Y24630D01*
X388829D01*
G02X387399Y23748I-1431J720D01*
G01X385999D01*
G02X385911Y23751I11J1602D01*
G03X385700Y23551I-11J-200D01*
G37*
G36*
G01X222501Y1172252D02*
X270497D01*
X276200Y1166548D01*
Y1148552D01*
X271497Y1143848D01*
X220501D01*
X217798Y1146552D01*
Y1167548D01*
X222501Y1172252D01*
G37*
G36*
G01X861812Y1877014D02*
X863415D01*
G02X864542Y1876550I0J-1601D01*
G01X864999D01*
X865999Y1875550D01*
X881937D01*
G02X882125Y1875682I1744J-2285D01*
G01X882143Y1875694D01*
X882449Y1876000D01*
Y1876966D01*
X892353D01*
Y1875196D01*
X892499Y1875050D01*
Y1872050D01*
X892353Y1871904D01*
Y1869413D01*
X882449D01*
Y1870466D01*
G02X882332Y1870526I1133J2353D01*
G01X882287Y1870550D01*
X880999D01*
X880499Y1870050D01*
X865999D01*
X864499Y1868550D01*
X848499D01*
X846999Y1870050D01*
Y1872550D01*
X850999Y1876550D01*
X857086D01*
G02X858213Y1877014I1127J-1137D01*
G01X859816D01*
G02X860814Y1876664I-1J-1601D01*
G02X861812Y1877014I999J-1251D01*
G37*
G36*
G01X882449Y1866477D02*
Y1867517D01*
X892353D01*
Y1859964D01*
X882449D01*
Y1861000D01*
G02X881780Y1861468I1050J2213D01*
G03X881637Y1861544I-775J-1285D01*
G02X881635Y1861545I621J1244D01*
G03X880999Y1861688I-639J-1357D01*
G01X869227D01*
X869203Y1861516D01*
G02X864602Y1861840I-2289J324D01*
G01Y1865615D01*
G02X869203Y1865938I2312J0D01*
G01X869227Y1865766D01*
X881000D01*
G03X881676Y1865876I-2J2143D01*
G01X881732Y1865932D01*
X881736Y1865937D01*
G02X882449Y1866477I1663J-1455D01*
G37*
G36*
G01X154085Y1859964D02*
X152499Y1861550D01*
X141499D01*
X138999Y1859050D01*
X135499D01*
X133999Y1860550D01*
Y1865550D01*
X132499Y1867050D01*
X122499D01*
X120999Y1868550D01*
Y1875550D01*
X122499Y1877050D01*
X164499D01*
X165499Y1876050D01*
Y1861550D01*
X164007Y1860058D01*
Y1859964D01*
X154085D01*
G37*
G36*
G01X825991Y1819379D02*
X826906D01*
G03X827188Y1820062I-1J400D01*
G01X826371Y1820880D01*
X819511D01*
X819493Y1820698D01*
G02X818670Y1819446I-1594J152D01*
G01Y1818212D01*
X818047Y1817589D01*
X818064Y1817487D01*
G02X813675Y1818906I-2565J-437D01*
G01X813735Y1818965D01*
Y1819248D01*
X813099D01*
G02X811669Y1820130I1J1602D01*
G01X807768D01*
X807736Y1820119D01*
G02X805201Y1820864I-736J2181D01*
G03X804921Y1820897I-157J-124D01*
G02X803686Y1825002I-1421J1811D01*
G01X803778Y1824995D01*
X805754Y1826970D01*
X811669D01*
G02X813099Y1827852I1431J-720D01*
G01X814499D01*
G02X815499Y1827501I-1J-1602D01*
G02X816499Y1827852I1001J-1251D01*
G01X817899D01*
G02X819456Y1826624I0J-1601D01*
G01X819493Y1826470D01*
X821319D01*
G02X825679I2180J-1420D01*
G01X827485D01*
X834434Y1819522D01*
Y1819379D01*
X834915D01*
Y1810975D01*
X829312D01*
Y1809855D01*
X827587Y1808130D01*
X817145D01*
G02X816539Y1810970I-2646J920D01*
G01X825991D01*
Y1819379D01*
G37*
G36*
G01X916078Y1794423D02*
Y1794736D01*
X916008Y1794796D01*
G02X918920Y1794739I1491J1754D01*
G01Y1779826D01*
X925000D01*
Y1774424D01*
X922920D01*
Y1772230D01*
G02X919319Y1768630I-1421J-2180D01*
G01X917211D01*
X916442Y1769398D01*
X915848D01*
X915499Y1769050D01*
X898116D01*
X898084Y1769039D01*
G02X896394I-845J2461D01*
G01X896362Y1769050D01*
X886499D01*
X882999Y1772550D01*
Y1779912D01*
X882164D01*
G02X881638Y1780000I-2J1601D01*
G01X881606Y1780012D01*
X880337D01*
X880310Y1780003D01*
G02X878173Y1783967I-646J2210D01*
G03X878179Y1784572I-259J305D01*
G02X880346Y1788510I1521J1728D01*
G01X880373Y1788502D01*
X881642D01*
X881674Y1788513D01*
G02X882200Y1788602I527J-1513D01*
G01X883600D01*
G02X884600Y1788251I-1J-1602D01*
G02X885600Y1788602I1001J-1251D01*
G01X887000D01*
G02X887380Y1788556I-1J-1602D01*
G01X887404Y1788550D01*
X901499D01*
X902216Y1789267D01*
X902222Y1789339D01*
G02X907393Y1788767I2592J-226D01*
G01X907380Y1788669D01*
X908134Y1787914D01*
X908966D01*
G02X910566Y1786313I-1J-1601D01*
G01Y1785483D01*
X910999Y1785050D01*
X912999D01*
X913578Y1785629D01*
Y1789320D01*
G02X915588Y1794034I1421J2180D01*
G03X916078Y1794423I90J390D01*
G37*
G36*
G01X98309Y1536605D02*
G03X98521Y1536776I14J199D01*
G02X98803Y1537595I2279J-327D01*
G03X98731Y1537866I-174J99D01*
G02X101896Y1538705I1168J1984D01*
G03X101968Y1538434I174J-99D01*
G02X100635Y1534154I-1168J-1984D01*
G03X100423Y1533983I-14J-199D01*
G02X98309Y1536605I-2279J326D01*
G37*
G36*
G01X852797Y1469610D02*
X854599D01*
G03X854626Y1469611I-60J1996D01*
G01Y1470098D01*
G02X856227Y1471698I1601J-1D01*
G01X857827D01*
G02X858827Y1471347I-1J-1602D01*
G02X859827Y1471698I1001J-1251D01*
G01X861427D01*
G02X863028Y1470096I-1J-1602D01*
G01Y1469704D01*
X881567D01*
G02X882449Y1470322I2249J-2271D01*
G01Y1471454D01*
X892353D01*
Y1463901D01*
X882449D01*
Y1464941D01*
G02X881770Y1465421I1061J2221D01*
G03X881281Y1465624I-490J-490D01*
G01X863399D01*
G03X863028Y1465597I-6J-2483D01*
G01Y1464994D01*
G02X861427Y1463394I-1601J1D01*
G01X859827D01*
G02X858827Y1463745I1J1602D01*
G02X857827Y1463394I-1001J1251D01*
G01X856227D01*
G02X854626Y1464996I1J1602D01*
G01Y1465227D01*
X854314D01*
X854255Y1465132D01*
G02X852250Y1464035I-1967J1214D01*
G01X848851Y1464091D01*
G02X848926Y1468713I38J2311D01*
G01X849503Y1468704D01*
X849551Y1468732D01*
G02X852797Y1469610I3246J-5563D01*
G37*
G36*
G01X876787Y1454517D02*
X876737Y1454550D01*
X876499D01*
X875499Y1455550D01*
Y1461050D01*
X876499Y1462050D01*
X876802D01*
X876844Y1462070D01*
G02X878903Y1462050I1009J-2079D01*
G01X892499D01*
X892999Y1461550D01*
Y1455050D01*
X892499Y1454550D01*
X892353D01*
Y1454452D01*
X882449D01*
Y1454550D01*
X879370D01*
G02X876787Y1454517I-1316J1900D01*
G37*
G36*
G01X867498Y1358849D02*
Y1360098D01*
X860498D01*
Y1363100D01*
X850100D01*
Y1365254D01*
X849432D01*
X849373Y1365193D01*
G02X849407Y1368770I-1873J1806D01*
G03X850100Y1369042I293J272D01*
G01Y1372200D01*
X856098D01*
Y1372902D01*
G02X857699Y1374502I1601J-1D01*
G01X859099D01*
G02X859352Y1374481I-6J-1602D01*
G03X859776Y1375050I63J395D01*
G02X863930Y1377035I2073J1000D01*
G03X864632Y1376997I361J171D01*
G02X865094Y1377540I1963J-1202D01*
G03X865109Y1378132I-261J303D01*
G02X867346Y1382006I1591J1664D01*
G01X867373Y1381998D01*
X868869D01*
X868901Y1382009D01*
G02X869427Y1382098I527J-1513D01*
G01X870827D01*
G02X871827Y1381747I-1J-1602D01*
G02X872827Y1382098I1001J-1251D01*
G01X874227D01*
G02X875396Y1381590I-1J-1602D01*
G01X877819D01*
G02X882171Y1381604I2181J-1420D01*
G01X889792D01*
Y1382585D01*
X901546D01*
Y1381604D01*
X901834D01*
X905420Y1378018D01*
Y1366462D01*
X901087Y1362130D01*
X894179D01*
G02X889819I-2180J1420D01*
G01X875329D01*
G02X875117Y1361810I-1431J718D01*
G03Y1361290I304J-260D01*
G02X875500Y1360252I-1218J-1039D01*
G01Y1358850D01*
G02X875456Y1358475I-1601J-2D01*
G01X875450Y1358452D01*
Y1357773D01*
X875497Y1357717D01*
G02X875643Y1357524I-2000J-1665D01*
G01X875654Y1357509D01*
X875700Y1357462D01*
Y1357438D01*
X875729Y1357391D01*
G02X872611Y1353604I-2230J-1341D01*
G03X872090Y1353338I-137J-376D01*
G02X868328Y1356327I-2503J712D01*
G01Y1357446D01*
G02X867498Y1358849I771J1403D01*
G37*
G36*
G01X150295Y1331662D02*
X150602D01*
Y1328520D01*
X151641D01*
G02X151106Y1325680I1859J-1821D01*
G01X150602D01*
Y1322538D01*
X150048D01*
G03X149656Y1322058I0J-400D01*
G02X145144I-2256J-458D01*
G03X144752Y1322538I-392J80D01*
G01X144198D01*
Y1325680D01*
X143202D01*
Y1322538D01*
X138969D01*
X138070Y1321640D01*
X138056Y1321591D01*
G02X135191Y1324456I-2206J659D01*
G01X135240Y1324470D01*
X136680Y1325911D01*
X135380Y1327212D01*
Y1333188D01*
X135888Y1333697D01*
G03X135605Y1334379I-283J282D01*
G01X132302D01*
Y1332800D01*
G02X130300Y1330798I-2002J0D01*
G01X128900D01*
G02X126898Y1332800I0J2002D01*
G01Y1335700D01*
G02X128900Y1337702I2002J0D01*
G01X130300D01*
G02X131602Y1337220I-1J-2002D01*
G01X136570D01*
G02X138000Y1338102I1431J-720D01*
G01X139400D01*
G02X140400Y1337751I-1J-1602D01*
G02X141400Y1338102I1001J-1251D01*
G01X142800D01*
G02X144384Y1336735I0J-1601D01*
G01X144394Y1336670D01*
X145902Y1335162D01*
Y1334926D01*
X146195D01*
X146255Y1334998D01*
G02X149959Y1332279I1769J-1473D01*
G03X150295Y1331662I336J-217D01*
G37*
G36*
G01X226442Y1111257D02*
X226602Y1111098D01*
Y1098202D01*
X223898Y1095498D01*
X215202D01*
X213402Y1097298D01*
X145702D01*
X145542Y1097459D01*
X144689D01*
Y1112463D01*
X156493D01*
Y1112402D01*
X158502D01*
X162102Y1116002D01*
X184902D01*
X194302Y1125402D01*
X228448D01*
Y1140898D01*
X230802Y1143252D01*
X243348D01*
X245202Y1141398D01*
Y1141102D01*
X249751D01*
Y1139041D01*
G03X250351Y1138695I400J0D01*
G02Y1134705I1149J-1995D01*
G03X249751Y1134359I-200J-346D01*
G01Y1133302D01*
X251198D01*
X253002Y1131498D01*
Y1125902D01*
X251598Y1124498D01*
X247998D01*
X247902Y1124402D01*
Y1097302D01*
X245298Y1094698D01*
X234002D01*
X232698Y1096002D01*
Y1106202D01*
X227302Y1111598D01*
X226583D01*
G03X226442Y1111257I1J-200D01*
G37*
G36*
G01X882449Y1059051D02*
X881500Y1060000D01*
X878500D01*
X876500Y1058000D01*
X852500D01*
X851500Y1059000D01*
X845000D01*
X844000Y1060000D01*
Y1064500D01*
X846500Y1067000D01*
X861000D01*
X862500Y1065500D01*
X882449D01*
Y1065942D01*
X892353D01*
Y1065147D01*
X893000Y1064500D01*
Y1059500D01*
X892500Y1059000D01*
X892353D01*
Y1058389D01*
X882449D01*
Y1059051D01*
G37*
G36*
G01X809998Y670074D02*
Y674662D01*
X810632D01*
G03X811012Y675186I0J400D01*
G02X815388I2188J714D01*
G03X815768Y674662I380J-124D01*
G01X816402D01*
Y671520D01*
X817398D01*
Y674662D01*
X818598D01*
Y679848D01*
X755313D01*
X754037Y678573D01*
X754024Y678519D01*
G02X750870Y681673I-2525J629D01*
G01X750924Y681686D01*
X753489Y684252D01*
X813284D01*
G03X813567Y684934I0J400D01*
G01X812198Y686302D01*
Y688266D01*
G03X811599Y688612I-400J-1D01*
G02X810800Y688398I-800J1388D01*
G01X809200D01*
G02X808371Y688630I1J1602D01*
G01X779179D01*
G02X774819I-2180J1420D01*
G01X751411D01*
X740580Y699461D01*
Y743588D01*
X746162Y749170D01*
X748346D01*
G02X748549Y749500I1455J-668D01*
G02X748198Y750500I1251J1001D01*
G01Y751900D01*
G02X748287Y752426I1602J-1D01*
G01X748298Y752458D01*
Y753531D01*
G02X751387Y757702I1702J1969D01*
G03X752000Y758040I213J338D01*
G01Y763500D01*
X753000Y764500D01*
X767449D01*
X767798Y764850D01*
Y766498D01*
X770002Y768702D01*
X783998D01*
X786898Y765802D01*
Y765652D01*
X786999Y765550D01*
Y745550D01*
X780463Y739014D01*
G03X780580Y738367I283J-283D01*
G02X778979Y733451I-1081J-2367D01*
G03X778499Y733059I-80J-392D01*
G01Y732050D01*
X779298Y731252D01*
X780497D01*
X781700Y730048D01*
Y728848D01*
X782867Y727682D01*
G02X784072Y726550I-868J-2132D01*
G01X785497D01*
Y732402D01*
X786078D01*
Y735138D01*
X786712Y735772D01*
X786705Y735864D01*
G02X789585Y738276I2294J186D01*
G01X789696Y738247D01*
X790499Y739050D01*
Y741351D01*
X790298Y741552D01*
Y760548D01*
X793501Y763752D01*
X798198D01*
G02X800572I1187J-2316D01*
G01X832348D01*
X835002Y761098D01*
Y744050D01*
X878499D01*
X885499Y737050D01*
Y722050D01*
X884499Y721050D01*
X869499D01*
X868999Y720550D01*
Y718050D01*
X869499Y717550D01*
X884999D01*
X885499Y717050D01*
Y712050D01*
X884999Y711550D01*
X869499D01*
X868999Y711050D01*
Y708778D01*
X869694Y708084D01*
X883194D01*
X883227Y708050D01*
X884499D01*
X885499Y707050D01*
Y692550D01*
X884499Y691550D01*
X869999D01*
X868999Y690550D01*
Y688050D01*
X869999Y687050D01*
X884999D01*
X885999Y686050D01*
Y682050D01*
X884999Y681050D01*
X863508D01*
X863169Y680712D01*
X859450D01*
G02X857996Y679780I-1455J669D01*
G01X856396D01*
G02X855904Y679858I2J1602D01*
G03X855425Y679658I-122J-381D01*
G02X855056Y679182I-1428J726D01*
G03Y678582I265J-300D01*
G02X855598Y677382I-1060J-1201D01*
G01Y674782D01*
G02X854612Y673304I-1601J0D01*
G03X854459Y672677I153J-370D01*
G02X854441Y669696I-1763J-1480D01*
G03X854458Y669418I152J-130D01*
G02X850941Y669411I-1755J-1921D01*
G03X850956Y669689I-136J147D01*
G02X850933Y672677I1740J1507D01*
G03X850780Y673304I-306J257D01*
G02X849794Y674782I615J1478D01*
G01Y675498D01*
G03X849484Y675665I-200J0D01*
G02X849320Y675570I-883J1336D01*
G01Y673508D01*
G02X846611Y669466I-2120J-1508D01*
G03X846120Y669076I-91J-390D01*
G01Y668500D01*
G03X846504Y668100I400J0D01*
G02X843835Y665937I-104J-2600D01*
G01X843852Y666039D01*
X843280Y666612D01*
Y675480D01*
X843159Y675532D01*
G02X842396Y676230I642J1467D01*
G01X841885D01*
X841870Y676045D01*
G02X839875Y674198I-1995J154D01*
G01X838475D01*
G02X836474Y676200I1J2002D01*
G01Y679102D01*
G02X836495Y679390I2001J-1D01*
G03X836100Y679848I-396J58D01*
G01X822602D01*
Y674662D01*
X823802D01*
Y672403D01*
G03X824441Y672083I400J0D01*
G02X825400Y672402I959J-1282D01*
G01X826800D01*
G02X828204Y671570I0J-1601D01*
G01X832590D01*
X832605Y671755D01*
G02X834600Y673602I1995J-154D01*
G01X836000D01*
G02X838002Y671600I0J-2002D01*
G01Y668700D01*
G02X836720Y666833I-2002J1D01*
G01Y665380D01*
G02X833879I-1420J-2180D01*
G01Y666833D01*
G02X832605Y668545I721J1867D01*
G01X832590Y668730D01*
X831916D01*
G03X831603Y668081I0J-400D01*
G02X829154Y664440I-1803J-1431D01*
G01X829127Y664448D01*
X827198D01*
X827175Y664443D01*
G02X826800Y664398I-377J1557D01*
G01X825400D01*
G02X823911Y665412I1J1601D01*
G01X823861Y665538D01*
X823168D01*
G03X822788Y665014I0J-400D01*
G02X818412I-2188J-714D01*
G03X818032Y665538I-380J124D01*
G01X817398D01*
Y668680D01*
X816402D01*
Y665538D01*
X809796D01*
G02X809459Y669699I-1136J2002D01*
G03X809998Y670074I139J375D01*
G37*
G36*
G01X850675Y658696D02*
X853494D01*
Y659182D01*
G02X855096Y660784I1602J0D01*
G01X856696D01*
G02X857696Y660433I-1J-1602D01*
G02X858696Y660784I1001J-1251D01*
G01X860296D01*
G02X861898Y659182I0J-1602D01*
G01Y658740D01*
X881969D01*
G02X882449Y659112I2184J-2323D01*
G01Y660430D01*
X892353D01*
Y652877D01*
X882449D01*
Y654456D01*
G02X882223Y654660I2152J2611D01*
G01X861899D01*
X861898D01*
Y654082D01*
G02X860296Y652480I-1602J0D01*
G01X858696D01*
G02X857696Y652831I1J1602D01*
G02X856696Y652480I-1001J1251D01*
G01X855096D01*
G02X853494Y654082I0J1602D01*
G01Y654289D01*
X853184D01*
X853126Y654196D01*
G02X851214Y653121I-1953J1236D01*
G01X847814Y653059D01*
G02X847730Y657681I-42J2311D01*
G01X848127Y657689D01*
X848183Y657739D01*
G02X850675Y658696I2492J-2767D01*
G37*
G36*
G01X876284Y645573D02*
Y649348D01*
G02X880892Y649616I2312J0D01*
G01X880913Y649440D01*
X881928D01*
X881984Y649487D01*
G02X882449Y649808I1821J-2140D01*
G01Y650981D01*
X892353D01*
Y643428D01*
X882449D01*
Y644868D01*
G02X882166Y645117I1862J2402D01*
G01X881923Y645360D01*
X880904D01*
X880876Y645193D01*
G02X876284Y645573I-2280J380D01*
G37*
G36*
G01X154103Y649630D02*
Y650981D01*
X164007D01*
Y643428D01*
X154103D01*
Y644597D01*
G02X153581Y645002I1346J2274D01*
G03X153199Y645160I-382J-383D01*
G01X146548D01*
X146521Y644992D01*
G02X141926Y645356I-2283J364D01*
G01Y649131D01*
G02X146532Y649415I2312J0D01*
G01X146554Y649240D01*
X153623D01*
G02X154103Y649630I2218J-2239D01*
G37*
G36*
G01X925600Y558400D02*
X924846D01*
G03X924467Y557873I0J-400D01*
G02X921038Y554632I-2468J-823D01*
G03X920542Y554456I-147J-372D01*
G02X920194Y554252I-349J196D01*
G01X908804D01*
G02X908456Y554456I1J400D01*
G03X907960Y554632I-349J-196D01*
G02X906078Y554617I-960J2418D01*
G01X906044Y554630D01*
X904810D01*
G02X901464Y554334I-1812J1420D01*
G03X900942Y554344I-267J-298D01*
G02X900687Y554252I-255J308D01*
G01X888411D01*
X887951Y554712D01*
Y557854D01*
G02Y557874I400J10D01*
G03X887680Y558070I-200J9D01*
G02X885235Y562616I-931J2430D01*
G03X885216Y562953I-117J162D01*
G02X884999Y563099I783J1397D01*
G02X883999Y562748I-1001J1251D01*
G01X882599D01*
G02X882073Y562837I1J1602D01*
G01X882041Y562848D01*
X880623D01*
X880596Y562840D01*
G02X877660Y564819I-646J2210D01*
G03X877198Y565174I-398J-40D01*
G02X877019Y570335I-411J2569D01*
G03X877453Y570706I35J398D01*
G02X880396Y572760I2297J-156D01*
G01X880423Y572752D01*
X882041D01*
X882073Y572763D01*
G02X882599Y572852I527J-1513D01*
G01X883999D01*
G02X884999Y572501I-1J-1602D01*
G02X885999Y572852I1001J-1251D01*
G01X887399D01*
G02X888085Y572697I-1J-1602D01*
G01X888125Y572678D01*
X901798D01*
Y572990D01*
X901769Y573037D01*
G02X906574Y574005I2230J1341D01*
G01X906560Y573906D01*
X907380Y573085D01*
X907494Y573118D01*
G02X907946Y573184I455J-1536D01*
G01X909346D01*
G02X910948Y571582I0J-1602D01*
G01Y570182D01*
G02X910941Y570038I-1602J6D01*
G03X911339Y569602I398J-36D01*
G01X918000D01*
Y568970D01*
X925426D01*
X925462Y569126D01*
G02X927078Y566117I2537J-576D01*
G01X927044Y566130D01*
X925600D01*
Y558400D01*
G37*
G36*
G01X875766Y240103D02*
Y243878D01*
G02X875999Y244888I2312J-1D01*
G01Y247050D01*
X875049Y248000D01*
X861558D01*
X861502Y247891D01*
G02X860078Y247022I-1424J732D01*
G01X858478D01*
G02X857478Y247373I1J1602D01*
G02X856478Y247022I-1001J1251D01*
G01X854878D01*
G02X853454Y247891I0J1601D01*
G01X853398Y248000D01*
X852482D01*
X852436Y247973D01*
G02X851233Y247663I-1157J2001D01*
G01X847834Y247729D01*
G02X846832Y247978I42J2312D01*
G01X846790Y248000D01*
X846500D01*
X845000Y249500D01*
Y250049D01*
X844999Y250050D01*
Y253050D01*
X847499Y255550D01*
X891999D01*
X893499Y254050D01*
Y254001D01*
X893500Y254000D01*
Y249500D01*
X893499Y249499D01*
Y239050D01*
X891999Y237550D01*
X880999D01*
X880499Y238050D01*
X879140D01*
G02X875766Y240103I-1062J2053D01*
G37*
G36*
G01X827198Y208952D02*
G02X827565Y209971I1601J-1D01*
G03X827326Y210620I-308J255D01*
G02X827411Y215760I448J2563D01*
G01X827477Y215769D01*
X827630Y215922D01*
X827623Y216014D01*
G02X831817Y217500I2294J186D01*
G03X832359Y217386I330J225D01*
G02X835833Y215885I1217J-1954D01*
G03X836063Y215727I196J39D01*
G02X836062Y210597I436J-2565D01*
G01X835960Y210614D01*
X835628Y210283D01*
X835773Y210138D01*
X835777Y210135D01*
G02X836300Y208952I-1078J-1184D01*
G01Y207550D01*
G02X836291Y207377I-1601J-3D01*
G03X836903Y206996I398J-43D01*
G02X836408Y203013I1396J-2196D01*
G03X835834Y203020I-290J-275D01*
G02X834699Y202548I-1135J1129D01*
G01X834434D01*
Y197331D01*
X834915D01*
Y188927D01*
X825991D01*
Y197049D01*
X824078Y198962D01*
Y202275D01*
X823920Y202309D01*
G02X827015Y206282I579J2741D01*
G03X827373Y206279I180J88D01*
G02X827548Y206550I1426J-729D01*
G02X827198Y207548I1251J999D01*
G01Y208952D01*
G37*
G36*
G01X226276Y184500D02*
G03Y185100I-264J300D01*
G02X226365Y189075I1723J1950D01*
G03X226299Y189741I-251J311D01*
G02X229449Y193773I1200J2309D01*
G03X230049I300J264D01*
G02X233439Y189883I1950J-1723D01*
G03Y189217I222J-333D01*
G02X233722Y185100I-1440J-2167D01*
G03Y184500I264J-300D01*
G02Y180600I-1723J-1950D01*
G03Y180000I264J-300D01*
G02X230265Y176110I-1723J-1950D01*
G03X229733I-266J-299D01*
G02X226276Y180000I-1734J1940D01*
G03Y180600I-264J300D01*
G02Y184500I1723J1950D01*
G37*
G36*
G01X156402Y167827D02*
Y167626D01*
G03X156941Y167251I400J0D01*
G02X157499Y167352I558J-1491D01*
G01X158899D01*
G02X160500Y165750I-1J-1602D01*
G01Y165068D01*
X161446D01*
Y166049D01*
X170802D01*
G03X171201Y166429I-1J400D01*
G02X174663Y168302I2299J-114D01*
G01X176861D01*
X177849Y167314D01*
X177901Y167300D01*
G02X178499Y167001I-401J-1550D01*
G02X179499Y167352I1001J-1251D01*
G01X180899D01*
G02X182500Y165750I-1J-1602D01*
G01Y164311D01*
G03X182899Y163902I400J-9D01*
G01X189500D01*
Y162920D01*
X197861D01*
X199002Y164061D01*
X198987Y164161D01*
G02X202336Y162057I2574J380D01*
G03X202261Y161325I119J-382D01*
G02X199243Y157130I-1262J-2276D01*
G01X197000D01*
Y154624D01*
X194970D01*
Y153512D01*
X193997Y152539D01*
X194014Y152437D01*
G02X193962Y151324I-2565J-438D01*
G03X194348Y150820I386J-104D01*
G01X210761D01*
X217078Y157138D01*
Y180870D01*
G02Y185230I1421J2180D01*
G01Y188739D01*
G02X219920I1421J1811D01*
G01Y185230D01*
G02Y180870I-1421J-2180D01*
G01Y155962D01*
X211937Y147980D01*
X184061D01*
X182335Y149706D01*
X182269Y149715D01*
G02X180898Y151300I231J1585D01*
G01Y152700D01*
G02X181181Y153609I1601J0D01*
G01X180542Y154248D01*
X179499D01*
G02X178499Y154599I1J1602D01*
G02X177499Y154248I-1001J1251D01*
G01X176456D01*
X173837Y151630D01*
X173256D01*
X173200Y151581D01*
G02X168944Y153057I-1701J1969D01*
G03X168345Y153323I-393J-76D01*
G02X165211Y153659I-1346J2227D01*
G03X164569Y153526I-275J-291D01*
G02X159612Y154987I-2392J1024D01*
G01X159629Y155089D01*
X159578Y155140D01*
Y157712D01*
X158542Y158748D01*
X157499D01*
G02X156499Y159099I1J1602D01*
G02X155499Y158748I-1001J1251D01*
G01X154099D01*
G02X153573Y158837I1J1602D01*
G01X153541Y158848D01*
X150538D01*
X147198Y162188D01*
Y165727D01*
X147190Y165754D01*
G02X151607Y167055I2210J646D01*
G01X151649Y166912D01*
X151998D01*
Y167827D01*
X151990Y167854D01*
G02X156410I2210J646D01*
G01X156402Y167827D01*
G37*
G36*
G01X352068Y1582709D02*
G02X351080Y1584795I-2294J191D01*
G03X351706Y1585091I227J329D01*
G02X352694Y1583005I2294J-191D01*
G03X352068Y1582709I-227J-329D01*
G37*
G36*
G01X172565Y1788096D02*
X173200D01*
Y1787102D01*
X175062D01*
Y1787313D01*
G02X175107Y1787688I1602J-2D01*
G01X175112Y1787711D01*
Y1788777D01*
X185587Y1799252D01*
X296112D01*
G02X298886I1387J-2202D01*
G01X333612D01*
G02Y1794848I1387J-2202D01*
G01X298886D01*
G02X296112I-1387J2202D01*
G01X187411D01*
X181989Y1789427D01*
G03X182111Y1788778I283J-283D01*
G02X183066Y1787313I-646J-1465D01*
G01Y1785913D01*
G02X183046Y1785664I-1602J3D01*
G03X183441Y1785202I395J-62D01*
G01X190000D01*
Y1783920D01*
X198361D01*
X198910Y1784470D01*
X198904Y1784562D01*
G02X203258Y1782832I2595J188D01*
G03X203242Y1782554I135J-147D01*
G02X202070Y1778820I-1743J-1504D01*
G01X201920Y1778781D01*
Y1772962D01*
X195587Y1766630D01*
X184411D01*
X181228Y1769812D01*
Y1771096D01*
G02X180398Y1772499I771J1403D01*
G01Y1773443D01*
X179394Y1774447D01*
Y1776459D01*
G02X179064Y1776662I668J1455D01*
G02X178734Y1776459I-998J1252D01*
G01Y1774230D01*
G02X175134Y1770630I-1420J-2180D01*
G01X171411D01*
X169367Y1772673D01*
G03X168806Y1772678I-283J-283D01*
G02X165578Y1776730I-1807J1872D01*
G01Y1780092D01*
X161446D01*
Y1781488D01*
X160301D01*
G02X159778Y1780889I-1430J721D01*
G03X159741Y1780258I226J-330D01*
G02X156522Y1780423I-1714J-1958D01*
G01X156606Y1780482D01*
Y1780669D01*
G03X156303Y1780840I-200J0D01*
G02X155475Y1780608I-830J1369D01*
G01X154071D01*
G02X153545Y1780696I-2J1601D01*
G01X153513Y1780708D01*
X152279D01*
X149320Y1783667D01*
Y1790135D01*
X154786Y1795602D01*
X161227D01*
X161254Y1795610D01*
G02X164145Y1792890I646J-2210D01*
G03X164535Y1792402I390J-88D01*
G01X164601D01*
X164651Y1792434D01*
G02X168202Y1790544I1249J-1934D01*
G01X168205Y1790348D01*
X170465D01*
X172048Y1788766D01*
G02X172165Y1788490I-283J-283D01*
G03X172565Y1788096I400J6D01*
G37*
G36*
G01X811264Y1889562D02*
X818142D01*
G03X818425Y1890245I0J400D01*
G01X815871Y1892798D01*
X760861D01*
X760532Y1892469D01*
X760518Y1892444D01*
G02X757393Y1895569I-2019J1106D01*
G01X757418Y1895583D01*
X759037Y1897202D01*
X788216D01*
G03X788520Y1897861I-1J400D01*
G02X788319Y1898130I1979J1689D01*
G01X766892D01*
X754061Y1910960D01*
X754034D01*
X751960Y1913034D01*
Y1913061D01*
X740480Y1924542D01*
Y1955835D01*
X744315Y1959670D01*
X747346D01*
G02X747549Y1960000I1455J-668D01*
G02X747198Y1961000I1251J1001D01*
G01Y1962400D01*
G02X747287Y1962926I1602J-1D01*
G01X747298Y1962958D01*
Y1965912D01*
X747462Y1966075D01*
X747475Y1966129D01*
G02X748500Y1967626I2525J-629D01*
G01Y1971000D01*
X753000Y1975500D01*
X767000D01*
X770500Y1979000D01*
X771000D01*
X771086Y1978914D01*
X784812D01*
X787016Y1976711D01*
Y1958215D01*
X784812Y1956012D01*
X781266D01*
Y1952261D01*
X779704D01*
G03X779422Y1951578I1J-400D01*
G01X781500Y1949500D01*
Y1942000D01*
X784098Y1939402D01*
X786497D01*
Y1945902D01*
X787078D01*
Y1949138D01*
X788411Y1950470D01*
X790688D01*
G02X792131Y1951322I1811J-1420D01*
G03X792350Y1952000I-64J395D01*
G01X791298Y1953052D01*
Y1973048D01*
X794001Y1975752D01*
X833948D01*
X836102Y1973598D01*
Y1961598D01*
X837098Y1960602D01*
X865647D01*
X865648Y1960600D01*
X865900D01*
X866500Y1960000D01*
Y1959748D01*
X872497Y1953752D01*
X883497D01*
X883761Y1953487D01*
X884839D01*
Y1952409D01*
X885200Y1952048D01*
Y1944552D01*
X884839Y1944191D01*
Y1942409D01*
X885200Y1942048D01*
Y1939552D01*
X884839Y1939191D01*
Y1938483D01*
X884131D01*
X883997Y1938348D01*
X867997D01*
X865301Y1935653D01*
G03X865584Y1934970I283J-283D01*
G01X866587D01*
X869172Y1932386D01*
X873036D01*
Y1933486D01*
X884838D01*
Y1928484D01*
X873036D01*
Y1929544D01*
X867996D01*
X865411Y1932130D01*
X821087D01*
X817458Y1928500D01*
G03X817740Y1927817I283J-283D01*
G01X825888D01*
Y1924214D01*
X832489D01*
X832502Y1924228D01*
X837915D01*
X840002Y1926314D01*
X869312D01*
X871312Y1924314D01*
X884812D01*
X886516Y1922611D01*
Y1914615D01*
X885513Y1913613D01*
X886516Y1912611D01*
Y1909615D01*
X884812Y1907912D01*
X871312D01*
X865216Y1901816D01*
G03X865499Y1901134I283J-282D01*
G01X866652D01*
X867924Y1902406D01*
X873036D01*
Y1903486D01*
X884838D01*
Y1898484D01*
X873036D01*
Y1899564D01*
X869100D01*
X867828Y1898292D01*
X861716D01*
Y1897613D01*
G02X860114Y1896012I-1602J1D01*
G01X858511D01*
G02X858022Y1896089I2J1601D01*
G03X857543Y1895889I-122J-381D01*
G02X857174Y1895413I-1428J726D01*
G03Y1894813I265J-300D01*
G02X857716Y1893613I-1060J-1201D01*
G01Y1891013D01*
G02X856867Y1889600I-1602J1D01*
G03X856757Y1888981I189J-353D01*
G02X856573Y1885332I-1943J-1731D01*
G03X856557Y1885054I135J-147D01*
G02X853071I-1743J-1504D01*
G03X853055Y1885332I-151J131D01*
G02X852363Y1886377I1760J1917D01*
G03X851695Y1886517I-377J-134D01*
G02X849558Y1885709I-1895J1783D01*
G03X849120Y1885311I-38J-398D01*
G01Y1884080D01*
G02X846195Y1884023I-1421J-2180D01*
G01X846280Y1884082D01*
Y1884312D01*
X841743Y1888848D01*
X840674D01*
G02X838672Y1890850I0J2002D01*
G01Y1893750D01*
G02X838772Y1894374I2002J-1D01*
G03X838392Y1894898I-380J124D01*
G01X820398D01*
X819915Y1894416D01*
X824769Y1889562D01*
X825902D01*
Y1887135D01*
G03X826501Y1886788I400J0D01*
G02X827300Y1887002I800J-1388D01*
G01X828700D01*
G02X830104Y1886170I0J-1601D01*
G01X834790D01*
X834800Y1886360D01*
G02X836799Y1888252I1999J-110D01*
G01X838199D01*
G02X840200Y1886250I-1J-2002D01*
G01Y1883350D01*
G02X838920Y1881483I-2002J0D01*
G01Y1879080D01*
G02X836078I-1421J-2180D01*
G01Y1881483D01*
G02X834808Y1883150I721J1867D01*
G01X834789Y1883330D01*
X830154D01*
G02X829951Y1883000I-1455J668D01*
G02X830296Y1882134I-1251J-1000D01*
G01X830302Y1882061D01*
X830702Y1881662D01*
Y1878473D01*
X830710Y1878446D01*
G02X826290I-2210J-646D01*
G01X826298Y1878473D01*
Y1879350D01*
G02X825731Y1880278I1002J1250D01*
G01X825698Y1880438D01*
X824702D01*
Y1876763D01*
G02Y1873437I-2002J-1663D01*
G01Y1872238D01*
X824726Y1872194D01*
G02X820674I-2026J-1094D01*
G01X820698Y1872238D01*
Y1873437D01*
G02Y1876763I2002J1663D01*
G01Y1880438D01*
X819498D01*
Y1883580D01*
X818502D01*
Y1880438D01*
X812036D01*
G02X809493Y1884262I-1136J2002D01*
G03X809296Y1884976I-244J317D01*
G02X807990Y1885516I304J2584D01*
G01X807936Y1885558D01*
X807038D01*
X806994Y1885534D01*
G02Y1889586I-1094J2026D01*
G01X807038Y1889562D01*
X807936D01*
X807990Y1889604D01*
G02X811210I1610J-2044D01*
G01X811264Y1889562D01*
G37*
G36*
G01X736147Y1795660D02*
G03X735855Y1796332I-293J272D01*
G01X735649D01*
G02X735123Y1796421I1J1602D01*
G01X735091Y1796432D01*
X733822D01*
X733795Y1796424D01*
G02X731360Y1800082I-646J2210D01*
G03X731249Y1800680I-311J252D01*
G02X730790Y1804852I1300J2254D01*
G03X730806Y1805130I-135J147D01*
G02X733195Y1808844I1743J1504D01*
G01X733222Y1808836D01*
X735091D01*
X735123Y1808847D01*
G02X735649Y1808936I527J-1513D01*
G01X737049D01*
G02X738049Y1808585I-1J-1602D01*
G02X739049Y1808936I1001J-1251D01*
G01X740449D01*
G02X741722Y1808306I0J-1601D01*
G03X742302Y1808246I318J242D01*
G02X743349Y1808636I1048J-1212D01*
G01X744749D01*
G02X746136Y1807834I-1J-1602D01*
G01X749747D01*
Y1809427D01*
X747961Y1811214D01*
X744711D01*
X744392Y1811532D01*
X743349D01*
G02X742076Y1812162I0J1601D01*
G03X741496Y1812222I-318J-242D01*
G02X740449Y1811832I-1048J1212D01*
G01X739049D01*
G02X738049Y1812183I1J1602D01*
G02X737049Y1811832I-1001J1251D01*
G01X735649D01*
G02X735123Y1811921I1J1602D01*
G01X735091Y1811932D01*
X733722D01*
X733695Y1811924D01*
G02Y1816344I-646J2210D01*
G01X733722Y1816336D01*
X735091D01*
X735123Y1816347D01*
G02X735649Y1816436I527J-1513D01*
G01X737049D01*
G02X738049Y1816085I-1J-1602D01*
G02X738378Y1816288I999J-1251D01*
G01Y1817222D01*
X739001Y1817845D01*
X738984Y1817947D01*
G02X744141Y1818617I2565J437D01*
G01X744147Y1818545D01*
X745470Y1817222D01*
Y1815964D01*
G02X746350Y1814534I-722J-1430D01*
G01Y1814054D01*
X749137D01*
X752316Y1810876D01*
X758151D01*
Y1801952D01*
X749470D01*
Y1799546D01*
X747387Y1797464D01*
X746203D01*
G02X744749Y1796532I-1455J669D01*
G01X743706D01*
X740613Y1793440D01*
X740602Y1793380D01*
G02X736147Y1795660I-2553J504D01*
G37*
G36*
G01X771947Y1808710D02*
Y1810876D01*
X773948D01*
Y1811546D01*
X778237Y1815836D01*
X780309D01*
G02X781749Y1816736I1440J-702D01*
G01X782255D01*
X782278Y1816741D01*
G02X783049Y1816836I774J-3107D01*
G01X800641D01*
X807278Y1810199D01*
Y1782752D01*
X812700D01*
Y1782962D01*
G02X812698Y1783050I1599J80D01*
G01Y1784452D01*
G02X814299Y1786052I1601J-1D01*
G01X814711D01*
G03X815068Y1786631I0J400D01*
G02X814898Y1787348I1431J718D01*
G01Y1788750D01*
G02X815828Y1790204I1602J0D01*
G01Y1790870D01*
G02Y1795230I1421J2180D01*
G01Y1797388D01*
X817819Y1799380D01*
X818857Y1800418D01*
X823431D01*
Y1803199D01*
X834915D01*
Y1794795D01*
X834914D01*
Y1793375D01*
X838150Y1790138D01*
Y1789966D01*
X838200Y1789909D01*
G02X838600Y1788850I-1202J-1059D01*
G01Y1787785D01*
X839700Y1786685D01*
Y1781899D01*
X840702Y1780898D01*
Y1773802D01*
X833902Y1767002D01*
Y1739566D01*
G03X834584Y1739283I400J0D01*
G01X834702Y1739402D01*
X862302D01*
G02X862443Y1739557I1697J-1402D01*
G01X875088Y1752202D01*
X894412D01*
X906202Y1740412D01*
Y1717588D01*
X904038Y1715425D01*
X904025Y1715371D01*
G02X900113Y1713798I-2525J629D01*
G01X898663D01*
G02X898124Y1713425I-1162J1103D01*
G01X898002Y1713373D01*
Y1710088D01*
X897702Y1709788D01*
Y1708500D01*
G02X897210Y1707346I-1602J1D01*
G01X897149Y1707287D01*
Y1707002D01*
X897398D01*
X898502Y1705898D01*
Y1691902D01*
X896598Y1689998D01*
X882402D01*
X881098Y1691302D01*
Y1705598D01*
X881148Y1705648D01*
Y1707100D01*
X885852D01*
Y1707002D01*
X887409D01*
Y1707213D01*
X887408Y1707224D01*
G02X887398Y1707400I1592J179D01*
G01Y1708800D01*
G02X887598Y1709575I1602J0D01*
G01Y1710827D01*
X887548Y1711000D01*
X886699D01*
X886498Y1710798D01*
X882002D01*
X881801Y1711000D01*
X881199D01*
X880998Y1710798D01*
X878502D01*
X878004Y1711297D01*
X877696D01*
X877198Y1710798D01*
X872602D01*
Y1709048D01*
G02X872425Y1708317I-1601J1D01*
G01X872402Y1708274D01*
Y1707811D01*
X873307Y1706906D01*
G03X873648Y1707047I141J142D01*
G01Y1707100D01*
X878352D01*
Y1700698D01*
X878202D01*
Y1696088D01*
X873478Y1691364D01*
X873525Y1691243D01*
G02X868898Y1691687I-2425J-943D01*
G01Y1693012D01*
X873798Y1697912D01*
Y1700698D01*
X873648D01*
Y1701698D01*
X872289D01*
X869343Y1704643D01*
X868500Y1703800D01*
X841600D01*
X836500Y1708900D01*
Y1719098D01*
X831802D01*
X829698Y1721202D01*
Y1729998D01*
X821802D01*
X819998Y1731802D01*
Y1756202D01*
X815202Y1760998D01*
X753302D01*
X749298Y1765003D01*
Y1780048D01*
X752001Y1782752D01*
X798966D01*
X800874Y1784660D01*
Y1801795D01*
G03X800475Y1802195I-400J0D01*
G01X800474D01*
G02X800192Y1802312I1J400D01*
G01X798315Y1804190D01*
G03X797709Y1804143I-283J-283D01*
G02X797270Y1803689I-1859J1358D01*
G01Y1803073D01*
X794160Y1799964D01*
X791561D01*
X791543Y1799782D01*
G02X789949Y1798332I-1594J151D01*
G01X788549D01*
G02X787549Y1798683I1J1602D01*
G02X787220Y1798480I-999J1251D01*
G01Y1797814D01*
G02X784378I-1421J-2180D01*
G01Y1798530D01*
G02X783564Y1799702I771J1404D01*
G01X783539Y1799874D01*
X780351D01*
Y1799392D01*
X771947D01*
Y1804994D01*
X770681D01*
X767128Y1808546D01*
Y1814454D01*
G02X769470Y1819067I1421J2179D01*
G01X769504Y1819054D01*
X772219D01*
G02X773649Y1819936I1431J-720D01*
G01X775049D01*
G02X776650Y1818334I-1J-1602D01*
G01Y1816932D01*
G02X775049Y1815332I-1601J1D01*
G01X773649D01*
G02X772219Y1816214I1J1602D01*
G01X771122D01*
X771086Y1816058D01*
G02X769970Y1814454I-2538J575D01*
G01Y1809722D01*
X771264Y1808428D01*
G03X771947Y1808710I283J283D01*
G37*
G36*
G01X276198Y1562048D02*
Y1563452D01*
G02X276737Y1564649I1601J-1D01*
G03X276472Y1565348I-265J299D01*
G01X275698D01*
X274702Y1564352D01*
Y1560002D01*
X274700Y1560001D01*
Y1541552D01*
X270647Y1537498D01*
X251202D01*
X249288Y1539412D01*
X241200D01*
Y1539348D01*
X234298D01*
Y1539412D01*
X226500D01*
X224498Y1541415D01*
X222700Y1539617D01*
Y1539348D01*
X215798D01*
Y1539412D01*
X189996D01*
X182996Y1532412D01*
X145500D01*
X144942Y1532971D01*
X144689D01*
Y1533224D01*
X143796Y1534116D01*
Y1536612D01*
X144689Y1537504D01*
Y1538224D01*
X143796Y1539116D01*
Y1551612D01*
X145500Y1553316D01*
X154717D01*
G03X154972Y1554023I-1J400D01*
G02X162796Y1556657I3099J3733D01*
G03X163469Y1556284I390J-90D01*
G01X172000Y1564816D01*
X241502D01*
X241698Y1565012D01*
Y1583298D01*
X247652Y1589252D01*
X283497D01*
X285002Y1587745D01*
Y1566353D01*
X284332Y1565684D01*
G03X284615Y1565002I283J-282D01*
G01X286661D01*
X289000Y1562662D01*
Y1548752D01*
X291001D01*
X294501Y1552252D01*
X300996D01*
G03X301316Y1552891I0J400D01*
G02X300998Y1553848I1283J958D01*
G01Y1555252D01*
G02X301381Y1556290I1601J-1D01*
G03Y1556810I-304J260D01*
G02X300998Y1557848I1218J1039D01*
G01Y1559252D01*
G02X301381Y1560290I1601J-1D01*
G03Y1560810I-304J260D01*
G02X300998Y1561848I1218J1039D01*
G01Y1563252D01*
G02X301356Y1564260I1601J-1D01*
G03X301046Y1564912I-310J252D01*
G01X289500D01*
X287296Y1567116D01*
Y1579612D01*
X289442Y1581757D01*
X289998Y1581202D01*
X295547D01*
Y1586002D01*
X300442D01*
X302111Y1587670D01*
X304198D01*
X304252Y1587785D01*
G02X305700Y1588702I1448J-685D01*
G01X306500D01*
Y1591500D01*
X304000Y1594000D01*
Y1594398D01*
G02X304444Y1599564I0J2602D01*
G01X304546Y1599546D01*
X305000Y1600000D01*
X326000D01*
X327000Y1599000D01*
Y1597722D01*
X327007Y1597696D01*
G02Y1596304I-2507J-696D01*
G01X327000Y1596278D01*
Y1595500D01*
X326000Y1594500D01*
Y1589113D01*
X335202Y1579912D01*
Y1578673D01*
X335210Y1578646D01*
G02X330700Y1578095I-2210J-646D01*
G01X330704Y1578183D01*
X326273Y1582614D01*
G03X325592Y1582367I-283J-283D01*
G02X320877Y1581095I-2592J233D01*
G01X320818Y1581180D01*
X320530D01*
G02X320255Y1580791I-1430J720D01*
G01X320199Y1580732D01*
Y1580452D01*
X320501D01*
Y1574910D01*
X321247D01*
X322480Y1573678D01*
Y1573052D01*
X323061D01*
Y1571270D01*
X324598D01*
Y1571500D01*
G02X326200Y1573102I1602J0D01*
G01X327800D01*
G02X329402Y1571500I0J-1602D01*
G01Y1569900D01*
G02X329207Y1569136I-1602J2D01*
G03X329431Y1568566I352J-191D01*
G02X330354Y1564178I-831J-2466D01*
G03X330576Y1563485I269J-296D01*
G02X332388Y1560230I-276J-2285D01*
G03X332580Y1559699I362J-169D01*
G02X333500Y1558250I-681J-1449D01*
G01Y1556850D01*
G02X333456Y1556475I-1601J-2D01*
G01X333450Y1556452D01*
Y1554648D01*
X333456Y1554625D01*
G02X333500Y1554250I-1557J-373D01*
G01Y1552850D01*
G02X333456Y1552475I-1601J-2D01*
G01X333450Y1552452D01*
Y1550752D01*
X361997D01*
X403497Y1509252D01*
X566997D01*
X570200Y1506048D01*
Y1486052D01*
X564497Y1480348D01*
X398001D01*
X344001Y1534348D01*
X327700D01*
Y1510388D01*
X318411Y1501098D01*
X277171D01*
G03X277044Y1500319I0J-400D01*
G02X266270I-5387J-16073D01*
G03X266191Y1501096I-127J380D01*
G01X264192Y1503095D01*
G03X263521Y1502910I-283J-283D01*
G02X258479Y1504199I-2522J640D01*
G03X258092Y1504698I-387J99D01*
G01X254412D01*
X253002Y1503288D01*
Y1494271D01*
X246000Y1487269D01*
Y1466070D01*
X282111D01*
X293411Y1477370D01*
X341519D01*
G02X345879I2180J-1420D01*
G01X400252D01*
X400295Y1477513D01*
G02X402313Y1474556I2204J-663D01*
G01X402221Y1474563D01*
X402187Y1474530D01*
X345879D01*
G02X341519I-2180J1420D01*
G01X294587D01*
X283287Y1463230D01*
X229261D01*
X219280Y1473211D01*
Y1485142D01*
X218780Y1485642D01*
Y1488558D01*
X219578Y1489357D01*
Y1494844D01*
X219414Y1494874D01*
G02X218098Y1496450I286J1576D01*
G01Y1499050D01*
G02X218639Y1500250I1601J0D01*
G03Y1500850I-265J300D01*
G02X218196Y1501498I1060J1200D01*
G02X217799Y1501448I-397J1551D01*
G01X216199D01*
G02X214745Y1502380I1J1601D01*
G01X213938D01*
G02X210806Y1501661I-2024J1635D01*
G01X210679Y1501721D01*
X202997Y1494040D01*
X156492D01*
Y1492972D01*
X144690D01*
Y1497974D01*
X156492D01*
Y1496880D01*
X201821D01*
X209340Y1504400D01*
X209351Y1504462D01*
G02X209972Y1505746I2563J-447D01*
G03X209674Y1506412I-299J266D01*
G01X200496D01*
X196496Y1502412D01*
X145000D01*
X143796Y1503616D01*
Y1507112D01*
X144549Y1507864D01*
X143796Y1508616D01*
Y1517612D01*
X145000Y1518816D01*
X157402D01*
X161096Y1522510D01*
X177602D01*
X187408Y1532316D01*
X256798D01*
Y1532612D01*
X256770Y1532659D01*
G02X261230I2230J1341D01*
G01X261202Y1532612D01*
Y1531998D01*
X262702Y1530498D01*
Y1530100D01*
X264298D01*
Y1530548D01*
X266501Y1532752D01*
X280497D01*
X282700Y1530548D01*
Y1507052D01*
X281832Y1506184D01*
G03X282115Y1505502I283J-282D01*
G01X316587D01*
X323298Y1512212D01*
Y1534348D01*
X284501D01*
X280761Y1538089D01*
G03X280420Y1537948I-141J-142D01*
G01Y1537589D01*
X296420Y1521588D01*
Y1514811D01*
G02X293580I-1420J-1811D01*
G01Y1520412D01*
X277578Y1536413D01*
Y1541198D01*
X276938D01*
Y1548402D01*
X279497D01*
Y1553798D01*
X279353Y1553840D01*
G02X277705Y1556236I646J2209D01*
G01X277712Y1556328D01*
X277078Y1556962D01*
Y1557220D01*
G02X276198Y1558650I722J1430D01*
G01Y1560052D01*
G02X276548Y1561050I1601J-1D01*
G02X276198Y1562048I1251J999D01*
G37*
G36*
G01X801798Y1139077D02*
Y1140848D01*
X792501D01*
X790298Y1143052D01*
Y1163548D01*
X793501Y1166752D01*
X832848D01*
X835002Y1164598D01*
Y1148300D01*
X835100D01*
Y1146752D01*
X880497D01*
X884785Y1142463D01*
X884839D01*
Y1142409D01*
X885200Y1142048D01*
Y1134552D01*
X884839Y1134191D01*
Y1131909D01*
X885200Y1131548D01*
Y1128552D01*
X884839Y1128191D01*
Y1127459D01*
X884107D01*
X883997Y1127348D01*
X871997D01*
X868851Y1124203D01*
G03X869134Y1123520I283J-283D01*
G01X871687D01*
X872831Y1122378D01*
X873036Y1122462D01*
X884838D01*
Y1117460D01*
X873036D01*
Y1118520D01*
X872671D01*
X870511Y1120680D01*
X834172D01*
X833521Y1121330D01*
X833477D01*
X833459Y1121348D01*
X821857D01*
X819860Y1119351D01*
G03X820142Y1118668I283J-283D01*
G01X825293D01*
Y1114752D01*
X836493D01*
X837335Y1115594D01*
X867331D01*
X869331Y1113594D01*
X882831D01*
X883961Y1112463D01*
X884839D01*
Y1097459D01*
X883099D01*
X882831Y1097190D01*
X869331D01*
X862293Y1090153D01*
G03X862576Y1089470I283J-283D01*
G01X863911D01*
X865802Y1091362D01*
X873036D01*
Y1092462D01*
X884838D01*
Y1087460D01*
X873036D01*
Y1088520D01*
X866978D01*
X865087Y1086630D01*
X859220D01*
X859181Y1086481D01*
G02X857633Y1085290I-1548J411D01*
G01X856033D01*
G02X855541Y1085368I2J1602D01*
G03X855062Y1085168I-122J-381D01*
G02X854693Y1084692I-1428J726D01*
G03Y1084092I265J-300D01*
G02X855234Y1082892I-1060J-1200D01*
G01Y1080292D01*
G02X854493Y1078941I-1602J0D01*
G03X854420Y1078688I108J-168D01*
G02X853720Y1075879I-2087J-972D01*
G01Y1074809D01*
X853755Y1074758D01*
G02X849336Y1072017I-2155J-1458D01*
G03X848657Y1072044I-348J-197D01*
G02X844055Y1072610I-2157J1456D01*
G01X844040Y1072651D01*
X842630Y1074062D01*
Y1081096D01*
G02X841970Y1081780I770J1404D01*
G01X841585D01*
X841566Y1081600D01*
G02X839575Y1079798I-1991J199D01*
G01X838175D01*
G02X836174Y1081800I1J2002D01*
G01Y1084700D01*
G02X836175Y1084775I2001J11D01*
G03X835776Y1085190I-400J15D01*
G01X827808D01*
G03X827496Y1084540I0J-400D01*
G02X827910Y1082454I-1796J-1440D01*
G01X827902Y1082427D01*
Y1080458D01*
X827913Y1080426D01*
G02X828002Y1079900I-1513J-527D01*
G01Y1078500D01*
G02X827651Y1077500I-1602J1D01*
G02X827854Y1077170I-1252J-998D01*
G01X832290D01*
X832305Y1077355D01*
G02X834300Y1079202I1995J-154D01*
G01X835700D01*
G02X837702Y1077200I0J-2002D01*
G01Y1074300D01*
G02X836420Y1072433I-2002J1D01*
G01Y1069356D01*
G02X833580Y1070034I-1920J-1756D01*
G01Y1072433D01*
G02X832305Y1074145I720J1867D01*
G01X832290Y1074330D01*
X827804D01*
G02X827585Y1074023I-1404J770D01*
G03X827579Y1073761I148J-134D01*
G02X826459Y1070094I-1779J-1461D01*
G01X826410Y1070080D01*
X824669Y1068338D01*
X817098D01*
Y1068400D01*
X816102D01*
Y1068338D01*
X808731D01*
X806390Y1070680D01*
X806341Y1070694D01*
G02X809206Y1073559I659J2206D01*
G01X809220Y1073510D01*
X809357Y1073374D01*
G03X809698Y1073515I141J142D01*
G01Y1077348D01*
X758172D01*
X758145Y1077340D01*
G02Y1081760I-646J2210D01*
G01X758172Y1081752D01*
X806500D01*
Y1083630D01*
X784179D01*
G02X779819I-2180J1420D01*
G01X760431D01*
X741680Y1102381D01*
Y1147938D01*
X745198Y1151457D01*
Y1152500D01*
G02X745549Y1153500I1602J-1D01*
G02X745204Y1154366I1251J1000D01*
G01X745198Y1154439D01*
X744798Y1154838D01*
Y1157613D01*
G02X746350Y1161519I2202J1386D01*
G01X746500Y1161558D01*
Y1164500D01*
X750000Y1168000D01*
X767000D01*
X768298Y1169298D01*
Y1172498D01*
X769502Y1173702D01*
X781998D01*
X787034Y1168665D01*
Y1148394D01*
X784831Y1146190D01*
X781285D01*
Y1141440D01*
X772381D01*
Y1144110D01*
X771981Y1144510D01*
X771793Y1144323D01*
X771783Y1144258D01*
G02X771451Y1143500I-1583J242D01*
G02X771802Y1142500I-1251J-1001D01*
G01Y1141100D01*
G02X771543Y1140228I-1602J1D01*
G03X771589Y1139961I168J-109D01*
G02X767839Y1139349I-1589J-2061D01*
G03X767765Y1139878I-332J223D01*
G02X767198Y1141100I1035J1223D01*
G01Y1142043D01*
X767193Y1142048D01*
X760920D01*
Y1141411D01*
X760001Y1140492D01*
Y1139488D01*
X753801D01*
X753768Y1139328D01*
G02X753709Y1139117I-1568J325D01*
G03X754095Y1138583I377J-134D01*
G02X756331Y1137402I56J-2601D01*
G01X759655D01*
X762004Y1135054D01*
Y1133454D01*
X764184D01*
Y1130894D01*
X770357D01*
G02X774801Y1130051I2142J-844D01*
G01Y1129852D01*
X775999D01*
G02X776999Y1129501I-1J-1602D01*
G02X777210Y1129644I1001J-1250D01*
G03X777381Y1130148I-197J348D01*
G02X781793Y1130864I2118J902D01*
G01X781786Y1130772D01*
X783656Y1128902D01*
X784997D01*
Y1135402D01*
X785578D01*
Y1136138D01*
X787212Y1137772D01*
X787205Y1137864D01*
G02X791310Y1139470I2294J185D01*
G01X795337D01*
X795456Y1139352D01*
X796499D01*
G02X797499Y1139001I-1J-1602D01*
G02X798499Y1139352I1001J-1251D01*
G01X799899D01*
G02X801098Y1138812I0J-1601D01*
G03X801798Y1139077I300J265D01*
G37*
G36*
G01X249162Y272501D02*
Y271556D01*
G02X247154Y267490I-1362J-1856D01*
G01X247127Y267498D01*
X245258D01*
X245226Y267487D01*
G02X244700Y267398I-527J1513D01*
G01X243300D01*
G02X242300Y267749I1J1602D01*
G02X241300Y267398I-1001J1251D01*
G01X239900D01*
G02X238709Y267930I1J1602D01*
G01X234210D01*
X234195Y267745D01*
G02X232946Y266043I-1995J155D01*
G01X232820Y265992D01*
Y264980D01*
G02X229980I-1420J-2180D01*
G01Y266074D01*
G02X228798Y267900I819J1826D01*
G01Y270800D01*
G02X230800Y272802I2002J0D01*
G01X232200D01*
G02X234195Y270955I0J-2001D01*
G01X234210Y270770D01*
X238335D01*
X238381Y270907D01*
G02X239845Y272001I1519J-507D01*
G03X240038Y272200I-7J200D01*
G01Y275331D01*
X238990Y276380D01*
X238941Y276394D01*
G02X238643Y276506I659J2206D01*
G03X238076Y276143I-167J-364D01*
G01Y275398D01*
G02X236075Y273398I-2001J1D01*
G01X234675D01*
G02X232674Y275400I1J2002D01*
G01Y278300D01*
G02X233208Y279661I2001J0D01*
G03X233202Y279939I-147J136D01*
G01X232715Y280426D01*
X227499D01*
X227450Y280297D01*
G02X226718Y279303I-2152J818D01*
G01Y276961D01*
X224487Y274730D01*
X223979D01*
G02X219305Y275407I-2180J1420D01*
G01X219263Y275550D01*
X143499D01*
X142499Y276550D01*
Y337550D01*
X143499Y338550D01*
X153336D01*
G03X153696Y339123I-1J400D01*
G02X162814Y342238I4375J2097D01*
G03X163488Y342039I391J84D01*
G01X170091Y348642D01*
X169885Y348849D01*
X169793Y348842D01*
G02X169478Y348830I-317J4189D01*
G01X165173D01*
G02Y357232I0J4201D01*
G01X169473D01*
G02X171414Y349305I0J-4201D01*
G03X171598Y348550I185J-355D01*
G01X240950D01*
X241400Y349000D01*
Y363951D01*
X250499Y373050D01*
X280999D01*
X281298Y372752D01*
X281497D01*
X284198Y370050D01*
X298580D01*
Y371588D01*
X299452Y372461D01*
X299435Y372563D01*
G02X303435Y375170I2565J437D01*
G01X304896D01*
G02X306300Y376002I1404J-769D01*
G01X307700D01*
G02X308720Y375635I0J-1601D01*
G03X308997Y375657I127J154D01*
G02X310200Y376202I1204J-1057D01*
G01X311800D01*
G02X312940Y375725I0J-1601D01*
G01X312941Y375724D01*
X313082Y375582D01*
X313500Y376000D01*
Y382500D01*
X314000Y383000D01*
X329000D01*
X329500Y382500D01*
Y376000D01*
X325500Y372000D01*
Y369540D01*
G02X322464Y365662I-856J-2457D01*
G01X320702D01*
Y364500D01*
G02X320162Y363302I-1601J1D01*
G01X320095Y363242D01*
Y362952D01*
X320501D01*
Y357557D01*
X322506Y355552D01*
X323061D01*
Y353770D01*
X324512D01*
X325098Y354357D01*
Y355600D01*
G02X326700Y357202I1602J0D01*
G01X328300D01*
G02X329902Y355600I0J-1602D01*
G01Y354000D01*
G02X328300Y352398I-1602J0D01*
G01X327157D01*
X325688Y350930D01*
X323061D01*
Y349148D01*
X319920D01*
Y348774D01*
X320047Y348724D01*
G02X318703Y343729I-946J-2424D01*
G01X318602Y343744D01*
X316668Y341811D01*
Y341176D01*
X318850D01*
Y338616D01*
X324512D01*
G02X328124Y339085I1987J-1162D01*
G02X329098Y339416I975J-1271D01*
G01X330498D01*
G02X331498Y339065I-1J-1602D01*
G02X332071Y339357I999J-1252D01*
G01X332121Y339371D01*
X333001Y340252D01*
X564497D01*
X567700Y337048D01*
Y322052D01*
X564497Y318848D01*
X329700D01*
Y303638D01*
X310975Y284912D01*
X275993D01*
G03X275893Y284125I0J-400D01*
G02X267421I-4236J-16414D01*
G03X267321Y284912I-100J387D01*
G01X252703D01*
G03X252362Y284303I0J-400D01*
G02X251059Y280894I-1962J-1203D01*
G01X251010Y280880D01*
X250629Y280498D01*
X249162D01*
Y279298D01*
X246020D01*
Y278302D01*
X249162D01*
Y277699D01*
G03X249671Y277314I400J0D01*
G02Y272886I629J-2214D01*
G03X249162Y272501I-109J-385D01*
G37*
G36*
G01X838100Y168350D02*
Y166748D01*
G02X837967Y166110I-1601J1D01*
G01X837950Y166072D01*
Y161752D01*
X838497D01*
X841200Y159048D01*
Y153052D01*
X838997Y150848D01*
X753001D01*
X750798Y153052D01*
Y160048D01*
X752501Y161752D01*
X814200D01*
Y161962D01*
G02X814198Y162050I1599J80D01*
G01Y163450D01*
G02X814781Y164686I1602J0D01*
G03X814821Y165266I-255J309D01*
G02X814398Y166350I1177J1084D01*
G01Y167750D01*
G02X815328Y169204I1602J0D01*
G01Y172388D01*
X815465Y172525D01*
X815448Y172627D01*
G02X818450Y175629I2565J437D01*
G01X818552Y175612D01*
X821297Y178356D01*
X823431D01*
Y180630D01*
X820179D01*
G02Y183470I-2180J1420D01*
G01X827087D01*
X828999Y181559D01*
X831411Y183970D01*
X838319D01*
G02Y181130I2180J-1420D01*
G01X834915D01*
Y172747D01*
X834814D01*
Y171032D01*
X835895Y169952D01*
X836499D01*
G02X838100Y168350I-1J-1602D01*
G37*
G36*
G01X901198Y131050D02*
Y132452D01*
G02X902799Y134052I1601J-1D01*
G01X904199D01*
G02X904574Y134007I-2J-1602D01*
G01X904597Y134002D01*
X906826D01*
X906853Y134010D01*
G02X907159Y129523I645J-2210D01*
G03X906700Y129128I-59J-396D01*
G01Y126952D01*
X908099D01*
G02X908874Y126752I0J-1602D01*
G01X910326D01*
X910353Y126760D01*
G02X913250Y125030I646J-2210D01*
G03X913924Y124831I391J84D01*
G01X919845Y130752D01*
X948204D01*
X960200Y118755D01*
Y110345D01*
X957540Y107684D01*
G03X957822Y107002I283J-282D01*
G01X960773D01*
X965744Y102031D01*
Y98019D01*
G02Y94081I-1702J-1969D01*
G01Y90888D01*
X962704Y87848D01*
X961156D01*
X961109Y87715D01*
G02X959599Y86648I-1510J535D01*
G01X956999D01*
G02X956280Y86819I1J1602D01*
G03X955700Y86462I-180J-357D01*
G01Y33552D01*
X951497Y29348D01*
X926501D01*
X924383Y31467D01*
G03X923700Y31184I-283J-283D01*
G01Y17052D01*
X920497Y13848D01*
X900001D01*
X896797Y17052D01*
Y35184D01*
G03X896115Y35467I-400J0D01*
G01X895997Y35348D01*
X839001D01*
X834798Y39552D01*
Y76548D01*
X836550Y78300D01*
X834298Y80552D01*
Y126548D01*
X838501Y130752D01*
X901200D01*
Y130962D01*
G02X901198Y131050I1599J80D01*
G37*
G54D108*
X68898Y17047D03*
Y190275D03*
Y422559D03*
Y1001299D03*
X895669Y1975079D03*
Y1801851D03*
Y1569567D03*
Y1396339D03*
Y1164055D03*
Y990827D03*
Y758543D03*
Y585315D03*
Y353031D03*
Y179803D03*
X167323Y1975079D03*
Y1569567D03*
Y1396339D03*
Y1164055D03*
Y758543D03*
Y585315D03*
Y179803D03*
X68898Y595787D03*
Y1639095D03*
G54D103*
X36500Y179000D03*
Y188500D03*
X35000Y198500D03*
X30000Y179000D03*
X23500D03*
X30000Y188500D03*
X24000D03*
X155999Y181050D03*
X161999Y768050D03*
X767159Y1792364D03*
G54D101*
X49799Y559150D03*
X90324Y1538800D03*
X164700Y1085400D03*
X99999Y1753575D03*
X141999Y1764550D03*
X344520Y406329D03*
X329499Y801550D03*
X330540Y795509D03*
X320499Y798050D03*
X400499Y406329D03*
X371999Y549300D03*
X394649Y630600D03*
X371500Y880600D03*
X364499Y1099050D03*
X345499Y1096550D03*
X370149Y1320050D03*
X345424Y1310050D03*
X347324Y1524000D03*
X366149Y1554050D03*
X354500Y1559500D03*
X353499Y1710450D03*
X377900Y1703800D03*
X385499Y1735050D03*
X967600Y1651100D03*
X971558Y1646500D03*
X74800Y1584700D03*
G54D109*
X12560Y1225216D03*
G54D105*
X78150Y434370D03*
Y178464D03*
Y28858D03*
Y989488D03*
X158071Y191614D03*
Y597126D03*
Y1152244D03*
Y1408150D03*
Y1963268D03*
X886417Y341220D03*
Y597126D03*
Y746732D03*
Y1002638D03*
Y1152244D03*
Y1408150D03*
Y1557756D03*
Y1813662D03*
Y1963268D03*
G54D100*
X41600Y407800D03*
X13000Y1104000D03*
Y1101000D03*
Y1099000D03*
X287399Y21613D03*
X290799D03*
X292299Y54613D03*
X295699D03*
X388300Y77000D03*
X390700D03*
X368100Y77100D03*
X370500D03*
X365300Y81500D03*
X367700D03*
X291799Y91113D03*
X812199Y165950D03*
X840499Y166350D03*
X812199Y168150D03*
X840499Y168750D03*
X859678Y276424D03*
X815300Y281500D03*
X863200Y346600D03*
X866600D03*
X328700Y350000D03*
X211898Y352614D03*
X215298D03*
X193300Y504000D03*
X195700D03*
X210800Y508500D03*
X213200D03*
X183199Y526050D03*
X858396Y677382D03*
X808800Y686000D03*
X861196Y748082D03*
X864596D03*
X212899Y759550D03*
X216299D03*
X237200Y913000D03*
X858033Y1082892D03*
X221700Y1085300D03*
X853633Y1119392D03*
X857033D03*
X215900Y1129500D03*
X219300D03*
X861233Y1150892D03*
X864633D03*
X134900Y1181900D03*
X138300D03*
X102299Y1233550D03*
X105699D03*
X178700Y1272000D03*
X141467Y1311260D03*
X143867D03*
X131799Y1311613D03*
X134199D03*
X120049Y1474950D03*
X99449Y1477150D03*
X120049D03*
X121599Y1480550D03*
X123999D03*
X860027Y1487796D03*
X215799Y1499050D03*
X856127Y1524296D03*
X308099Y1531950D03*
X310499D03*
X216299Y1536550D03*
X219699D03*
X864000Y1554100D03*
X867400D03*
X295800Y1554600D03*
X298200D03*
X325800Y1575500D03*
X328200D03*
X963700Y1658800D03*
Y1662200D03*
Y1663800D03*
Y1667200D03*
X876901Y1692150D03*
X179700Y1702500D03*
X122799Y1739613D03*
X125199D03*
X136304Y1740323D03*
X138704D03*
X840999Y1786850D03*
X812699Y1786950D03*
Y1789150D03*
X840999Y1789250D03*
X654349Y1791634D03*
X656749D03*
X638949Y1791834D03*
X745149Y1794334D03*
X705449Y1796834D03*
X694749Y1797134D03*
X645149Y1808434D03*
X702549Y1811934D03*
X692349Y1818134D03*
X694749D03*
X778849Y1818734D03*
X781349Y1821134D03*
X784749D03*
X786349D03*
X789749D03*
X860514Y1893613D03*
X254700Y1906500D03*
X312299Y1927050D03*
X314699D03*
X855614Y1930113D03*
X859014D03*
X862800Y1963900D03*
X866200D03*
X211900Y1964100D03*
X215300D03*
X112499Y1159800D03*
X123499D03*
X112499Y1164300D03*
X123499D03*
X134900Y1172900D03*
X96399Y1091350D03*
X89500Y1096300D03*
Y1098700D03*
Y1103300D03*
Y1105700D03*
X103499Y1260613D03*
X102299Y1242550D03*
X105699D03*
X121999Y1249613D03*
X126499D03*
X121999Y1283113D03*
X106199Y1275113D03*
X102799D03*
X100400Y1637000D03*
X103800D03*
X103799Y1680613D03*
X107199D03*
X123499Y1687613D03*
X127999D03*
X100400Y1646000D03*
X103800D03*
X122999Y1654113D03*
X127499D03*
X56799Y1895950D03*
Y1898150D03*
X58499Y1900350D03*
X48299Y1964550D03*
X51699D03*
X48399Y1906350D03*
X50599D03*
X40999Y1916850D03*
X177799Y70050D03*
X183699D03*
X173899Y70250D03*
X176099D03*
X178499Y100250D03*
X184399Y116250D03*
X133199Y422013D03*
Y424213D03*
Y426013D03*
Y428213D03*
X128500Y432400D03*
Y434800D03*
X140399Y439313D03*
X138499Y480050D03*
X132600Y453300D03*
X136000D03*
X132600Y462300D03*
X136000D03*
X156999Y469050D03*
X161499D03*
X137799Y487113D03*
X141199D03*
X137799Y496113D03*
X141199D03*
X157249Y502613D03*
X235999Y697550D03*
X240499D03*
X235999Y708550D03*
X216799Y717550D03*
X220199D03*
X235499Y742550D03*
X239999D03*
X212899Y750550D03*
X216299D03*
X165399Y807813D03*
X167599D03*
X169399D03*
X171599D03*
X158300Y823000D03*
X160700D03*
X166399Y832313D03*
X161999Y867613D03*
X166499D03*
X161299Y851113D03*
X164699D03*
X160799Y884613D03*
X164199D03*
X160799Y893613D03*
X164199D03*
X180499Y901113D03*
Y912113D03*
X184999D03*
X161299Y860113D03*
X164699D03*
X180499Y867613D03*
X184999D03*
X161999Y901113D03*
X101600Y1116300D03*
X117699Y1123950D03*
Y1126150D03*
X124200Y1132000D03*
X125900Y1132200D03*
X117299Y1299213D03*
X141467Y1305260D03*
X143867D03*
X131799Y1305613D03*
X134199D03*
X106199Y1266113D03*
X194249Y1629513D03*
Y1631713D03*
X197800Y1636500D03*
X200200D03*
X201900Y1636700D03*
X122799Y1733613D03*
X125199D03*
X136304Y1734323D03*
X138704D03*
X103799Y1671613D03*
X107199D03*
X234434Y1948487D03*
X238934D03*
X211900Y1955100D03*
X215300D03*
X240434Y1901187D03*
X235934Y1912187D03*
X240434D03*
X217114Y1918613D03*
X220514D03*
X217114Y1927613D03*
X220514D03*
X234999Y74850D03*
X193300Y498000D03*
X195700D03*
X217100Y895700D03*
Y901700D03*
X307799Y729550D03*
X310199D03*
X296800Y734500D03*
X299200D03*
X311299Y740950D03*
X307799Y723550D03*
X310199D03*
X306699Y761450D03*
Y763650D03*
Y765950D03*
Y768150D03*
X312299Y1933050D03*
X314699D03*
X295658Y1942828D03*
X298058D03*
X315021Y1943809D03*
X308977Y1961091D03*
Y1963291D03*
Y1965091D03*
Y1967291D03*
X308100Y1969076D03*
X778778Y309424D03*
X781178D03*
X763300Y309500D03*
X765700D03*
X755778Y322824D03*
X778778Y303424D03*
X781178D03*
X763300Y303500D03*
X765700D03*
X857299Y313550D03*
X860699D03*
X835728Y284624D03*
X840228D03*
Y295624D03*
X857299Y304550D03*
X860699D03*
X766100Y356800D03*
X767800Y357000D03*
X770200D03*
X839228Y329424D03*
X843728D03*
X863200Y337600D03*
X866600D03*
G54D112*
X180749Y70050D03*
G54D111*
X40999Y1919800D03*
G54D107*
X9843Y353144D03*
Y265767D03*
Y153168D03*
Y875216D03*
Y1137420D03*
Y1250019D03*
Y1337396D03*
G54D104*
X85630Y511653D03*
Y917165D03*
X150591Y669449D03*
Y1480473D03*
Y1885985D03*
X878937Y263937D03*
Y669449D03*
Y1074961D03*
Y1480473D03*
X150591Y263937D03*
X878937Y1885985D03*
G54D110*
X1019291Y1416024D03*
G54D106*
X21499Y17050D03*
X1010999Y18550D03*
X1008999Y1968550D03*
G54D102*
X29532Y309561D03*
Y1029522D03*
X271657Y1889758D03*
X994098Y149601D03*
Y673223D03*
X994099Y1068892D03*
X994093Y1889751D03*
%LPD*%
G75*
G36*
G01X24400Y138100D02*
X25800Y139500D01*
X37500D01*
X39000Y138000D01*
Y114500D01*
X36000Y111500D01*
X25800D01*
X24400Y112900D01*
Y138100D01*
G37*
G36*
G01X27500Y742000D02*
X31500Y746000D01*
X53000D01*
X55500Y743500D01*
Y712000D01*
X50000Y706500D01*
X32500D01*
X27500Y711500D01*
Y742000D01*
G37*
G36*
G01X91532Y859550D02*
Y859666D01*
X91382D01*
X89999Y861050D01*
X81499D01*
X80999Y861550D01*
Y862550D01*
X81999Y863550D01*
X91999D01*
X93499Y865050D01*
X97999D01*
X98999Y864050D01*
Y860550D01*
X98002Y859553D01*
X97923Y859551D01*
G03X97903Y859550I120J-2599D01*
G01X91532D01*
G37*
G36*
G01X81499Y880050D02*
X80499Y881050D01*
Y889050D01*
X80999Y889550D01*
X92777D01*
X92803Y889543D01*
G03X94195I696J2507D01*
G01X94221Y889550D01*
X97499D01*
X98999Y888050D01*
Y881550D01*
X97499Y880050D01*
X81499D01*
G37*
G36*
G01X98497Y858348D02*
X98599Y858450D01*
X99499Y857550D01*
Y851050D01*
X97999Y849550D01*
X81999D01*
X80999Y850550D01*
Y858550D01*
X81499Y859050D01*
X90300D01*
X91001Y858348D01*
X98497D01*
G37*
G36*
G01X98999Y890550D02*
X98599Y890150D01*
X97997Y890752D01*
X90298D01*
X89999Y891050D01*
X81499D01*
X80999Y891550D01*
Y892550D01*
X81999Y893550D01*
X91999D01*
X93038Y894589D01*
X93137Y894575D01*
G03X95033Y895050I362J2577D01*
G01X97999D01*
X98999Y894050D01*
Y890550D01*
G37*
G36*
G01X195998Y287114D02*
X145498D01*
X144998Y287614D01*
Y290114D01*
X145498Y290614D01*
X186498D01*
X198498Y302614D01*
X222998D01*
X223998Y301614D01*
Y292114D01*
X222998Y291114D01*
X199998D01*
X195998Y287114D01*
G37*
G36*
G01X250600Y314614D02*
X252800Y316814D01*
X252886Y316813D01*
G03X254576Y317500I49J2301D01*
G01X255935D01*
X256306Y317130D01*
X259270D01*
X260498Y315902D01*
Y300114D01*
X258284Y297900D01*
X248900D01*
Y290300D01*
X248000Y289400D01*
X232600D01*
X230900Y291100D01*
Y291114D01*
X227498D01*
X225998Y292614D01*
Y302614D01*
X224498Y304114D01*
X197498D01*
X185498Y292114D01*
X145498D01*
X144998Y292614D01*
Y300614D01*
X145498Y301114D01*
X158500D01*
X162686Y305300D01*
X175700D01*
X185014Y314614D01*
X250600D01*
G37*
G36*
G01X182498Y317114D02*
X145998D01*
X144998Y318114D01*
Y319614D01*
X145998Y320614D01*
X169498D01*
X183998Y335114D01*
X221998D01*
X223498Y333614D01*
Y325614D01*
X221998Y324114D01*
X189498D01*
X182498Y317114D01*
G37*
G36*
G01X242900Y361451D02*
X252999Y371550D01*
X280999D01*
X284999Y367550D01*
Y351050D01*
X282849Y348900D01*
X274399D01*
X273499Y348000D01*
Y321550D01*
X271999Y320050D01*
X258063D01*
X253999Y324114D01*
X226998D01*
X225498Y325614D01*
Y335114D01*
X223998Y336614D01*
X182498D01*
X167998Y322114D01*
X145998D01*
X144998Y323114D01*
Y334614D01*
X145998Y335614D01*
X160998D01*
X172498Y347114D01*
X242000D01*
X242900Y348014D01*
Y361451D01*
G37*
G36*
G01X229000Y1124200D02*
X229650Y1124850D01*
Y1140400D01*
X231300Y1142050D01*
X242850D01*
X244000Y1140900D01*
Y1133000D01*
X244900Y1132100D01*
X250700D01*
X251800Y1131000D01*
Y1126400D01*
X251100Y1125700D01*
X247500D01*
X246700Y1124900D01*
Y1097800D01*
X244800Y1095900D01*
X234500D01*
X233900Y1096500D01*
Y1106700D01*
X227800Y1112800D01*
X206300D01*
X197100Y1103600D01*
X146400D01*
X146100Y1103900D01*
Y1110400D01*
X146900Y1111200D01*
X159000D01*
X162600Y1114800D01*
X185400D01*
X194800Y1124200D01*
X229000D01*
G37*
G36*
G01X215700Y1096700D02*
X213900Y1098500D01*
X146200D01*
X145900Y1098800D01*
Y1101100D01*
X146500Y1101700D01*
X197900D01*
X207798Y1111598D01*
X224402D01*
X225400Y1110600D01*
Y1098700D01*
X223400Y1096700D01*
X215700D01*
G37*
G36*
G01X261500Y1518302D02*
X261356Y1518260D01*
G03X259708Y1516272I643J-2210D01*
G01X259701Y1516201D01*
X259524Y1516024D01*
X256524D01*
X256499Y1516050D01*
X249300D01*
X248752Y1515502D01*
X248548D01*
Y1515298D01*
X247950Y1514700D01*
Y1512650D01*
X248100Y1512500D01*
Y1506300D01*
X247200Y1505400D01*
X227500D01*
X225998Y1506902D01*
Y1519114D01*
X224498Y1520614D01*
X197498D01*
X185498Y1508614D01*
X145498D01*
X144998Y1509114D01*
Y1517114D01*
X145498Y1517614D01*
X157900D01*
X161594Y1521308D01*
X178100D01*
X187906Y1531114D01*
X260386D01*
X261500Y1530000D01*
Y1518302D01*
G37*
G36*
G01X167998Y1538614D02*
X145998D01*
X144998Y1539614D01*
Y1551114D01*
X145998Y1552114D01*
X160998D01*
X172498Y1563614D01*
X242000D01*
X242900Y1564514D01*
Y1582800D01*
X248150Y1588050D01*
X282999D01*
X283800Y1587248D01*
Y1566851D01*
X283499Y1566550D01*
X275200D01*
X273500Y1564850D01*
Y1560500D01*
X273499Y1560499D01*
Y1542050D01*
X270149Y1538700D01*
X251700D01*
X249786Y1540614D01*
X226998D01*
X225498Y1542114D01*
Y1551614D01*
X223998Y1553114D01*
X182498D01*
X167998Y1538614D01*
G37*
G36*
G01X182498Y1533614D02*
X145998D01*
X144998Y1534614D01*
Y1536114D01*
X145998Y1537114D01*
X169498D01*
X183998Y1551614D01*
X221998D01*
X223498Y1550114D01*
Y1542114D01*
X221998Y1540614D01*
X189498D01*
X182498Y1533614D01*
G37*
G36*
G01X195998Y1503614D02*
X145498D01*
X144998Y1504114D01*
Y1506614D01*
X145498Y1507114D01*
X186498D01*
X198498Y1519114D01*
X222998D01*
X223998Y1518114D01*
Y1508614D01*
X222998Y1507614D01*
X199998D01*
X195998Y1503614D01*
G37*
G36*
G01X270999Y1145050D02*
X220999D01*
X218999Y1147050D01*
Y1167050D01*
X222999Y1171050D01*
X269999D01*
X274999Y1166050D01*
Y1149050D01*
X270999Y1145050D01*
G37*
G36*
G01X246000Y1499500D02*
X245584Y1499916D01*
G02X245867Y1500598I283J282D01*
G01X248998D01*
Y1495929D01*
X246683Y1493613D01*
G02X246000Y1493896I-283J283D01*
G01Y1499500D01*
G37*
G36*
G01X284999Y34050D02*
X283499Y35550D01*
Y46050D01*
X286999Y49550D01*
X296499D01*
X298499Y47550D01*
Y40788D01*
G03X298159Y38840I2201J-1388D01*
G01X298182Y38733D01*
X296999Y37550D01*
X292999D01*
X292264Y36814D01*
X291648D01*
Y36198D01*
X289499Y34050D01*
X284999D01*
G37*
G36*
G01X290999Y60550D02*
X288499Y63050D01*
Y67050D01*
X290499Y69050D01*
X297999D01*
X301499Y72550D01*
Y81550D01*
X302999Y83050D01*
X323936D01*
X332499Y91613D01*
X356836D01*
X357599Y90850D01*
Y80213D01*
X356499Y79113D01*
X341999D01*
X323436Y60550D01*
X290999D01*
G37*
G36*
G01X357049Y43000D02*
X362999Y37050D01*
Y12499D01*
X361000Y10500D01*
X321000D01*
X319600Y11900D01*
Y26600D01*
X319100Y27100D01*
X287700D01*
X287100Y27700D01*
Y31000D01*
X288200Y32100D01*
X290049D01*
X294298Y36348D01*
X297497D01*
X297698Y36550D01*
X297800D01*
Y36600D01*
X298112Y36912D01*
X298700D01*
Y37500D01*
X299500Y38300D01*
Y38352D01*
X299700Y38552D01*
Y42752D01*
X305999Y49050D01*
X325999D01*
X326049Y49000D01*
X329500D01*
X335500Y43000D01*
X357049D01*
G37*
G36*
G01X296499Y71050D02*
X287999D01*
X286999Y72050D01*
Y81550D01*
X288499Y83050D01*
X297499D01*
X297999Y82550D01*
Y72550D01*
X296499Y71050D01*
G37*
G36*
G01X342499Y118499D02*
X344500Y120500D01*
X372000D01*
X374500Y118000D01*
Y100500D01*
X372500Y98500D01*
X363049D01*
X362999Y98550D01*
X343499D01*
X342499Y99550D01*
Y118499D01*
G37*
G36*
G01X295999Y289316D02*
Y292410D01*
G03Y294690I-2000J1140D01*
G01Y316550D01*
X297499Y318050D01*
X308499D01*
X309298Y318848D01*
X311322D01*
X311360Y318832D01*
G03X312000Y318698I641J1468D01*
G01X313600D01*
G03X314240Y318832I-1J1602D01*
G01X314278Y318848D01*
X325298D01*
Y305462D01*
X309151Y289316D01*
X295999D01*
G37*
G36*
G01X266999Y293050D02*
X265499Y294550D01*
X265498D01*
Y312550D01*
X265499D01*
Y316050D01*
X266499Y317050D01*
X275140D01*
G03X277860I1360J2450D01*
G01X281499D01*
X281524Y317024D01*
X288976D01*
X290000Y316000D01*
Y296000D01*
X287259Y293259D01*
X281240D01*
X281031Y293050D01*
X266999D01*
G37*
G36*
G01X302499Y320050D02*
X301999Y320550D01*
Y323050D01*
X301499Y323550D01*
X288508D01*
X288487Y323570D01*
X282478D01*
X281999Y324050D01*
Y329050D01*
X282999Y330050D01*
X305999D01*
X307499Y331550D01*
Y332788D01*
X307510Y332820D01*
G03X307600Y333350I-1511J529D01*
G01Y334750D01*
G03X307579Y335012I-1601J3D01*
G01X307562Y335113D01*
X307999Y335550D01*
X317499D01*
X317999Y335050D01*
Y332050D01*
X318999Y331050D01*
X328259D01*
G03X329098Y330812I840J1364D01*
G01X330498D01*
G03X332062Y332068I0J1602D01*
G01X332074Y332125D01*
X332499Y332550D01*
Y338050D01*
X333499Y339050D01*
X563999D01*
X566499Y336550D01*
Y322550D01*
X563999Y320050D01*
X302499D01*
G37*
G36*
G01X289998Y349114D02*
X288498Y350614D01*
Y362114D01*
X289498Y363114D01*
X304000D01*
X304500Y363614D01*
Y366000D01*
X305000Y366500D01*
X307500D01*
X308000Y366000D01*
Y362116D01*
X307998Y362114D01*
Y361309D01*
X307987Y361277D01*
G03X307898Y360750I1512J-526D01*
G01Y359350D01*
G03X307987Y358823I1601J-1D01*
G01X307998Y358791D01*
Y357309D01*
X307987Y357277D01*
G03X307898Y356750I1512J-526D01*
G01Y355350D01*
G03X307969Y354878I1601J-1D01*
G01X307978Y354849D01*
Y351701D01*
X305411Y349134D01*
X302325D01*
X302304Y349114D01*
X289998D01*
G37*
G36*
G01X310499Y348163D02*
Y350205D01*
X310818Y350525D01*
Y353552D01*
G02X311005Y353752I200J0D01*
G03X312329Y354630I-106J1598D01*
G01X316497D01*
Y349657D01*
X314683Y347843D01*
G03X311167Y347866I-1771J-1907D01*
G02X310499Y348163I-268J297D01*
G37*
G36*
G01X314990Y1556550D02*
X315078Y1556462D01*
Y1550005D01*
X315066Y1549971D01*
G03X320018Y1548400I2433J-921D01*
G01X320057Y1548550D01*
X324895D01*
G03X328665Y1549418I1605J1650D01*
G01X328713Y1549550D01*
X361499D01*
X390411Y1520638D01*
G02X390257Y1519977I-283J-282D01*
G03X389310Y1516234I742J-2179D01*
G02Y1515962I-147J-136D01*
G03X392688I1689J-1564D01*
G02Y1516234I147J136D01*
G03X393178Y1517056I-1689J1564D01*
G02X393839Y1517210I379J-129D01*
G01X402999Y1508050D01*
X566499D01*
X568999Y1505550D01*
Y1486550D01*
X563999Y1481550D01*
X398499D01*
X344499Y1535550D01*
X310164D01*
G03X310099Y1535552I-82J-1599D01*
G01X308499D01*
G03X308434Y1535550I17J-1601D01*
G01X284999D01*
X281999Y1538550D01*
Y1547050D01*
X282499Y1547550D01*
X291499D01*
X294999Y1551050D01*
X295796D01*
X295820Y1551044D01*
G03X296200Y1550998I381J1556D01*
G01X297800D01*
G03X298180Y1551044I-1J1602D01*
G01X298204Y1551050D01*
X301828D01*
Y1550212D01*
X301951Y1550089D01*
X301934Y1549987D01*
G03X305609Y1551903I2565J-437D01*
G02X305497Y1552548I171J362D01*
G01X305499Y1552550D01*
Y1553288D01*
X305510Y1553320D01*
G03X305600Y1553850I-1511J529D01*
G01Y1555250D01*
G03X305510Y1555780I-1601J1D01*
G01X305499Y1555812D01*
Y1555851D01*
G02X305919Y1556251I400J0D01*
G03X305999Y1556248I100J1598D01*
G01X307399D01*
G03X308334Y1556550I-1J1602D01*
G01X314990D01*
G37*
G36*
G01X280499Y1506550D02*
X267499D01*
X265499Y1508550D01*
Y1530050D01*
X266999Y1531550D01*
X279999D01*
X281499Y1530050D01*
Y1507550D01*
X280499Y1506550D01*
G37*
G36*
G01X311200Y1583898D02*
G03X311462Y1583920I-3J1602D01*
G01X311563Y1583937D01*
X312000Y1583500D01*
Y1582000D01*
X307998Y1577998D01*
Y1574309D01*
X307987Y1574277D01*
G03X307898Y1573750I1512J-526D01*
G01Y1572350D01*
G03X307987Y1571823I1601J-1D01*
G01X307998Y1571791D01*
Y1570282D01*
X307994Y1570262D01*
G03Y1569338I2255J-462D01*
G01X307998Y1569318D01*
Y1567114D01*
X306998Y1566114D01*
X289998D01*
X288498Y1567614D01*
Y1579114D01*
X289384Y1580000D01*
X303500D01*
X304500Y1581000D01*
Y1583500D01*
X305000Y1584000D01*
X305138D01*
X305170Y1583989D01*
G03X305700Y1583898I532J1511D01*
G01X307300D01*
G03X307830Y1583989I-2J1602D01*
G01X307862Y1584000D01*
X309238D01*
X309270Y1583989D01*
G03X309800Y1583898I532J1511D01*
G01X311200D01*
G37*
G36*
G01X309200Y1566616D02*
Y1567177D01*
G02X309696Y1567566I400J1D01*
G03X312049Y1571235I553J2234D01*
G03X312442Y1571923I-1151J1114D01*
G01X312483Y1572070D01*
X316497D01*
Y1566606D01*
X315162Y1565271D01*
X308819D01*
G02X308536Y1565953I0J400D01*
G01X309200Y1566616D01*
G37*
G36*
G01X323350Y1558470D02*
Y1559052D01*
X317000D01*
Y1563091D01*
X318850Y1564941D01*
X319112Y1564680D01*
X326420D01*
G03X328413Y1563505I2180J1420D01*
G02X328668Y1562824I-29J-399D01*
G03X328006Y1561014I1632J-1623D01*
G01X328013Y1560922D01*
X326936Y1559845D01*
X326870Y1559835D01*
G03X325542Y1558624I229J-1585D01*
G01X325505Y1558470D01*
X323350D01*
G37*
G36*
G01X391999Y54550D02*
X391499Y55050D01*
Y57550D01*
X391350Y57698D01*
Y58112D01*
X390938D01*
X389499Y59550D01*
X377499D01*
X376499Y58550D01*
Y58312D01*
X376488Y58280D01*
G03X376398Y57750I1511J-529D01*
G01Y56449D01*
X375999Y56050D01*
X369499D01*
X361499Y64050D01*
X352499D01*
X351499Y65050D01*
Y72050D01*
X352999Y73550D01*
X368096D01*
X368120Y73544D01*
G03X368500Y73498I381J1556D01*
G01X370100D01*
G03X370480Y73544I-1J1602D01*
G01X370504Y73550D01*
X388019D01*
X388057Y73533D01*
G03X388700Y73398I644J1467D01*
G01X390300D01*
G03X390943Y73533I-1J1602D01*
G01X390981Y73550D01*
X400499D01*
X401999Y72050D01*
Y57312D01*
X401988Y57280D01*
G03X401898Y56750I1511J-529D01*
G01Y55350D01*
G03X401919Y55088I1601J-3D01*
G01X401936Y54987D01*
X401499Y54550D01*
X391999D01*
G37*
G36*
G01X368999Y13050D02*
X367499Y14550D01*
Y32050D01*
X368999Y33550D01*
X383499D01*
X384499Y32550D01*
Y31812D01*
X384488Y31780D01*
G03X384398Y31250I1511J-529D01*
G01Y29850D01*
G03X384488Y29320I1601J-1D01*
G01X384499Y29288D01*
Y27312D01*
X384488Y27280D01*
G03X384398Y26750I1511J-529D01*
G01Y25350D01*
G03X384488Y24820I1601J-1D01*
G01X384499Y24788D01*
Y15050D01*
X382499Y13050D01*
X368999D01*
G37*
G36*
G01X383957Y41052D02*
X382146Y42863D01*
G02X382305Y43526I283J283D01*
G03X380631Y48453I-806J2474D01*
G02X380098Y48852I-134J377D01*
G03X379764Y50283I-2598J148D01*
G02X379969Y50854I348J197D01*
G03X380710Y51430I-569J1497D01*
G02X380964Y51494I164J-115D01*
G03X383753Y52059I1035J2056D01*
G01X383813Y52130D01*
X384148D01*
Y51548D01*
X390648D01*
Y48988D01*
X397850D01*
Y49570D01*
X398701D01*
G03X399328Y48946I1399J779D01*
G01Y48212D01*
X400451Y47089D01*
X400434Y46987D01*
G03X400577Y45598I2565J-438D01*
G02X400205Y45052I-372J-146D01*
G01X399299D01*
G03X397730Y43772I0J-1602D01*
G01X397697Y43612D01*
X396694D01*
G02X396324Y44166I-1J400D01*
G03X392074I-2125J884D01*
G02X391704Y43612I-369J-154D01*
G01X390997D01*
Y43030D01*
X390471D01*
X389078Y41638D01*
Y41052D01*
X383957D01*
G37*
G36*
G01X656461Y1814054D02*
X655754Y1813348D01*
X655647Y1813371D01*
G03X652799Y1812304I-598J-2737D01*
G01X651203D01*
G03X651000Y1812634I-1455J-668D01*
G03X651350Y1813634I-1251J999D01*
G01Y1815034D01*
G03X651180Y1815753I-1601J1D01*
G02X651537Y1816332I357J179D01*
G01X651949D01*
G03X653185Y1816916I-1J1602D01*
G02X653765Y1816956I309J-255D01*
G03X654849Y1816532I1085J1177D01*
G01X656249D01*
G03X657850Y1818134I0J1601D01*
G01Y1819177D01*
X659587Y1820913D01*
X659729Y1820775D01*
G03X663672Y1821129I1820J1859D01*
G01X663731Y1821214D01*
X663961D01*
X664978Y1820196D01*
Y1816371D01*
X662197D01*
Y1814054D01*
X656461D01*
G37*
G36*
G01X753499Y152050D02*
X751999Y153550D01*
Y159550D01*
X752999Y160550D01*
X815237D01*
X815269Y160539D01*
G03X815799Y160448I532J1511D01*
G01X817199D01*
G03X817729Y160539I-2J1602D01*
G01X817761Y160550D01*
X822737D01*
X822769Y160539D01*
G03X823299Y160448I532J1511D01*
G01X824699D01*
G03X825229Y160539I-2J1602D01*
G01X825261Y160550D01*
X830237D01*
X830269Y160539D01*
G03X830799Y160448I532J1511D01*
G01X832199D01*
G03X832729Y160539I-2J1602D01*
G01X832761Y160550D01*
X837999D01*
X839999Y158550D01*
Y153550D01*
X838499Y152050D01*
X753499D01*
G37*
G36*
G01X744999Y709050D02*
X743999Y710050D01*
Y720550D01*
X745499Y722050D01*
X750999D01*
X752499Y723550D01*
Y726550D01*
X761999D01*
X762999Y725550D01*
Y721550D01*
X763999Y720550D01*
X770570D01*
X770592Y720545D01*
G03X771618I513J2244D01*
G01X771640Y720550D01*
X775499D01*
X776499Y721550D01*
Y722788D01*
X776510Y722820D01*
G03X776600Y723350I-1511J529D01*
G01Y724750D01*
G03X776510Y725280I-1601J1D01*
G01X776499Y725312D01*
Y727288D01*
X776510Y727320D01*
G03X776600Y727850I-1511J529D01*
G01Y729250D01*
G03X776579Y729512I-1601J3D01*
G01X776562Y729613D01*
X776999Y730050D01*
X779999D01*
X780499Y729550D01*
Y727296D01*
G03Y723804I1500J-1746D01*
G01Y719050D01*
X780999Y718550D01*
X787499D01*
X788999Y720050D01*
Y724050D01*
X789499Y724550D01*
X794999D01*
X795999Y723550D01*
Y718050D01*
X794504Y716554D01*
X790333D01*
X790329Y716550D01*
X789499D01*
X787499Y714550D01*
Y710050D01*
X786499Y709050D01*
X744999D01*
G37*
G36*
G01X747999Y697050D02*
X746499Y698550D01*
Y706550D01*
X747499Y707550D01*
X754019D01*
X754057Y707533D01*
G03X754700Y707398I644J1467D01*
G01X756300D01*
G03X756943Y707533I-1J1602D01*
G01X756981Y707550D01*
X776019D01*
X776057Y707533D01*
G03X776700Y707398I644J1467D01*
G01X778300D01*
G03X778943Y707533I-1J1602D01*
G01X778981Y707550D01*
X784999D01*
X787499Y705050D01*
Y698050D01*
X786499Y697050D01*
X747999D01*
G37*
G36*
G01X747499Y1109550D02*
X746499Y1110550D01*
Y1121050D01*
X747999Y1122550D01*
X750999D01*
X752999Y1124550D01*
Y1127050D01*
X753999Y1128050D01*
X761999D01*
X762999Y1127050D01*
Y1124050D01*
X765499Y1121550D01*
X773664D01*
G03X774599Y1121248I936J1300D01*
G01X775999D01*
G03X776886Y1121517I-1J1602D01*
G01X776936Y1121550D01*
X776999D01*
X777499Y1122050D01*
Y1122288D01*
X777510Y1122320D01*
G03X777600Y1122850I-1511J529D01*
G01Y1124250D01*
G03X777510Y1124780I-1601J1D01*
G01X777499Y1124812D01*
Y1126288D01*
X777510Y1126320D01*
G03X777600Y1126850I-1511J529D01*
G01Y1127652D01*
X778499Y1128550D01*
X779499D01*
X780499Y1127550D01*
Y1123550D01*
X783499Y1120550D01*
X791499D01*
X791999Y1121050D01*
X792999D01*
X793999Y1120050D01*
Y1111550D01*
X791999Y1109550D01*
X779704D01*
X779680Y1109556D01*
G03X779300Y1109602I-381J-1556D01*
G01X777700D01*
G03X777320Y1109556I1J-1602D01*
G01X777296Y1109550D01*
X761704D01*
X761680Y1109556D01*
G03X761300Y1109602I-381J-1556D01*
G01X759700D01*
G03X759320Y1109556I1J-1602D01*
G01X759296Y1109550D01*
X747499D01*
G37*
G36*
G01X761607Y1086470D02*
X744520Y1103557D01*
Y1121413D01*
G02X745111Y1121765I400J0D01*
G03X745165Y1121740I194J349D01*
G01X745298Y1121693D01*
Y1110052D01*
X747001Y1108348D01*
X792497D01*
X793615Y1109467D01*
G02X794298Y1109184I283J-283D01*
G01Y1094052D01*
X796501Y1091848D01*
X804921D01*
G02X805243Y1091211I0J-400D01*
G03X806351Y1086994I2256J-1661D01*
G01X806385Y1086979D01*
X806552Y1086811D01*
X806212Y1086470D01*
X784179D01*
G03X779819I-2180J-1420D01*
G01X761607D01*
G37*
G36*
G01X747662Y1145220D02*
X747539Y1145098D01*
X747437Y1145115D01*
G03X745198Y1144427I-437J-2565D01*
G02X744520Y1144715I-278J288D01*
G01Y1146762D01*
X747257Y1149498D01*
X748200D01*
G03X749604Y1150330I0J1601D01*
G01X756462D01*
X758078Y1148713D01*
Y1147139D01*
X758098Y1147120D01*
Y1146052D01*
X753574D01*
G02X752998Y1145838I-377J133D01*
G03X752199Y1146052I-800J-1388D01*
G01X750799D01*
G03X749395Y1145220I0J-1601D01*
G01X747662D01*
G37*
G36*
G01X750999Y1515050D02*
X746499Y1519550D01*
Y1526050D01*
X747999Y1527550D01*
X754499D01*
X755999Y1529050D01*
Y1531550D01*
X756999Y1532550D01*
X765499D01*
X766476Y1531574D01*
Y1529234D01*
X766499D01*
Y1525550D01*
X767499Y1524550D01*
X778499D01*
X779499Y1525550D01*
Y1526283D01*
G03X779782Y1527193I-1318J909D01*
G01Y1528593D01*
G03X779499Y1529503I-1601J1D01*
G01Y1530283D01*
G03X779782Y1531193I-1318J909D01*
G01Y1532593D01*
G03X779777Y1532728I-1601J8D01*
G01X779769Y1532820D01*
X779999Y1533050D01*
X780999D01*
X781999Y1532050D01*
Y1527550D01*
X783999Y1525550D01*
X785692D01*
Y1525526D01*
X789694D01*
Y1525550D01*
X790999D01*
X791999Y1526550D01*
Y1531050D01*
X792499Y1531550D01*
X793499D01*
X794999Y1530050D01*
Y1526050D01*
X790999Y1522050D01*
Y1516550D01*
X789499Y1515050D01*
X784862D01*
G03X784000Y1515302I-862J-1350D01*
G01X782400D01*
G03X781538Y1515050I0J-1602D01*
G01X764009D01*
G03X762800Y1515602I-1210J-1050D01*
G01X761200D01*
G03X759991Y1515050I1J-1602D01*
G01X750999D01*
G37*
G36*
G01X758587Y1493970D02*
X742420Y1510138D01*
Y1549911D01*
X744838Y1552330D01*
X748896D01*
G03X750300Y1551498I1404J769D01*
G01X751700D01*
G03X753104Y1552330I0J1601D01*
G01X759162D01*
X761100Y1550392D01*
Y1548798D01*
X755689D01*
G03X754527Y1549298I-1163J-1102D01*
G01X753127D01*
G03X751723Y1548466I0J-1601D01*
G01X750829D01*
X750799Y1548476D01*
G03X749130Y1543548I-799J-2476D01*
G02X749279Y1542888I-134J-377D01*
G01X747880Y1541488D01*
Y1538112D01*
X751116Y1534876D01*
X751497D01*
G03X752156Y1534192I1431J719D01*
G01Y1533400D01*
G03X751497Y1532716I772J-1403D01*
G01X747780D01*
G03Y1529876I-2180J-1420D01*
G01X751497D01*
G03X751818Y1529440I1432J718D01*
G02X751542Y1528752I-277J-288D01*
G01X747501D01*
X745298Y1526548D01*
Y1519052D01*
X748942Y1515408D01*
X748949Y1515398D01*
G03X749398Y1514949I2051J1602D01*
G01X749408Y1514942D01*
X750501Y1513848D01*
X789997D01*
X790361Y1514213D01*
G02X791043Y1513930I282J-283D01*
G01Y1501224D01*
X793247Y1499021D01*
X801590D01*
G02X801828Y1498299I0J-400D01*
G03X801113Y1494580I1671J-2249D01*
G02X800773Y1493970I-340J-210D01*
G01X793679D01*
G03X789319I-2180J-1420D01*
G01X758587D01*
G37*
G36*
G01X822300Y1731200D02*
X821200Y1732300D01*
Y1756700D01*
X815700Y1762200D01*
X753800D01*
X750499Y1765501D01*
Y1779550D01*
X752499Y1781550D01*
X813737D01*
X813769Y1781539D01*
G03X814299Y1781448I532J1511D01*
G01X815699D01*
G03X816229Y1781539I-2J1602D01*
G01X816261Y1781550D01*
X818298D01*
G03X820888I1295J2257D01*
G01X823237D01*
X823269Y1781539D01*
G03X823799Y1781448I532J1511D01*
G01X825199D01*
G03X825729Y1781539I-2J1602D01*
G01X825761Y1781550D01*
X827810D01*
G03X830588I1389J2200D01*
G01X832237D01*
X832269Y1781539D01*
G03X832799Y1781448I532J1511D01*
G01X834199D01*
G03X834729Y1781539I-2J1602D01*
G01X834761Y1781550D01*
X838350D01*
X839500Y1780400D01*
Y1774300D01*
X832700Y1767500D01*
Y1738452D01*
X830798D01*
Y1731200D01*
X822300D01*
G37*
G36*
G01X739049Y1800936D02*
G03X738049Y1800585I1J-1602D01*
G03X737049Y1800936I-1001J-1251D01*
G01X735649D01*
G03X735123Y1800847I1J-1602D01*
G01X735091Y1800836D01*
X734410D01*
Y1801114D01*
X734463Y1801171D01*
G03X734729Y1801514I-1916J1760D01*
G01X736687D01*
X739506Y1804332D01*
X740449D01*
G03X741496Y1804722I-1J1602D01*
G02X742076Y1804662I262J-302D01*
G03X743349Y1804032I1273J971D01*
G01X744749D01*
G03X746217Y1804994I0J1601D01*
G01X747434D01*
G02X747717Y1804311I0J-400D01*
G01X746628Y1803222D01*
Y1800722D01*
X746508Y1800602D01*
G02X745931Y1800615I-282J283D01*
G03X744749Y1801136I-1182J-1080D01*
G01X743349D01*
G03X742113Y1800552I1J-1602D01*
G02X741533Y1800512I-309J255D01*
G03X740449Y1800936I-1085J-1177D01*
G01X739049D01*
G37*
G36*
G01X695096Y1806697D02*
X697024Y1804768D01*
G02X696741Y1804085I-283J-283D01*
G01X695208D01*
G03X694349Y1804336I-861J-1350D01*
G01X692749D01*
G03X691597Y1803847I0J-1601D01*
G01X691538Y1803786D01*
X691310D01*
X688860Y1801336D01*
X686936D01*
G03X686178Y1801659I-1386J-2202D01*
G01X686124Y1801672D01*
X684750Y1803046D01*
Y1803634D01*
G03X684626Y1804364I-2201J2D01*
G02X685003Y1804897I377J133D01*
G01X686901D01*
Y1806862D01*
X688466D01*
G03X691288Y1807107I1265J1802D01*
G01X691363Y1807182D01*
X692071D01*
X692109Y1807166D01*
G03X692749Y1807032I641J1468D01*
G01X694349D01*
G03X694628Y1807057I-3J1602D01*
G02X695096Y1806697I69J-394D01*
G37*
G36*
G01X754100Y1921700D02*
X752499Y1923301D01*
Y1938550D01*
X752999Y1939050D01*
X761999D01*
X762962Y1938087D01*
Y1935152D01*
X762999D01*
Y1934550D01*
X764999Y1932550D01*
X776499D01*
X776999Y1933050D01*
Y1933788D01*
X777010Y1933820D01*
G03X777100Y1934350I-1511J529D01*
G01Y1935750D01*
G03X777010Y1936280I-1601J1D01*
G01X776999Y1936312D01*
Y1937788D01*
X777010Y1937820D01*
G03X777100Y1938350I-1511J529D01*
G01Y1939652D01*
X777499Y1940050D01*
X778999D01*
X779499Y1939550D01*
Y1936050D01*
X784999Y1930550D01*
X787499D01*
X789999Y1933050D01*
Y1937550D01*
X790499Y1938050D01*
X791499D01*
X791999Y1937550D01*
Y1922900D01*
X790799Y1921700D01*
X754100D01*
G37*
G36*
G01X795550Y1904981D02*
X798879Y1901653D01*
G02X798596Y1900970I-283J-283D01*
G01X792679D01*
G03X788319I-2180J-1420D01*
G01X768068D01*
X755237Y1913802D01*
X755210D01*
X754802Y1914210D01*
Y1914237D01*
X743320Y1925718D01*
Y1941322D01*
X743567Y1941424D01*
X743662Y1941330D01*
X747815D01*
X747849Y1941172D01*
G03X748551Y1940164I1565J341D01*
G01X748644Y1940105D01*
Y1939821D01*
X748551Y1939762D01*
G03X747812Y1938413I862J-1349D01*
G01Y1937013D01*
G03X748255Y1935907I1602J0D01*
G02X748170Y1935287I-289J-276D01*
G03X750711Y1930748I1329J-2237D01*
G02X751298Y1930394I187J-354D01*
G01Y1922803D01*
X753602Y1920498D01*
X758142D01*
X758174Y1920487D01*
G03X758700Y1920398I527J1513D01*
G01X760300D01*
G03X760826Y1920487I-1J1602D01*
G01X760858Y1920498D01*
X767488D01*
X767507Y1920495D01*
G03X768491I492J2555D01*
G01X768510Y1920498D01*
X783142D01*
X783174Y1920487D01*
G03X783700Y1920398I527J1513D01*
G01X785300D01*
G03X785826Y1920487I-1J1602D01*
G01X785858Y1920498D01*
X791297D01*
X791552Y1920754D01*
G02X792234Y1920471I282J-283D01*
G01Y1907867D01*
X794438Y1905664D01*
X795033D01*
G02X795433Y1905264I0J-400D01*
G03X795550Y1904981I400J0D01*
G37*
G36*
G01X839499Y36550D02*
X835999Y40050D01*
Y76050D01*
X837249Y77300D01*
X886749D01*
X895249Y85800D01*
X911282D01*
G03X913552Y85818I1116J2350D01*
G01X915454D01*
Y85718D01*
X920332D01*
X920499Y85550D01*
Y61550D01*
X895499Y36550D01*
X839499D01*
G37*
G36*
G01X895521Y91572D02*
X883499Y79550D01*
X836999D01*
X835499Y81050D01*
Y126050D01*
X838999Y129550D01*
X902237D01*
X902269Y129539D01*
G03X902799Y129448I532J1511D01*
G01X904199D01*
G03X904729Y129539I-2J1602D01*
G01X904761Y129550D01*
X904999D01*
X905499Y129050D01*
Y126601D01*
G03X904898Y125350I1000J-1250D01*
G01Y123750D01*
G03X904908Y123566I1601J-5D01*
G01X904919Y123470D01*
X904499Y123050D01*
X900499D01*
X896374Y118925D01*
Y92470D01*
G03X895534Y91597I1180J-1976D01*
G01X895521Y91572D01*
G37*
G36*
G01X825504Y172064D02*
X822828Y169388D01*
Y169204D01*
G03X821898Y167750I672J-1454D01*
G01Y166350D01*
G03X822321Y165266I1600J0D01*
G02X822281Y164686I-295J-271D01*
G03X821698Y163450I1019J-1236D01*
G01Y162050D01*
G03X821700Y161962I1601J-8D01*
G01Y161752D01*
X818798D01*
Y161962D01*
G03X818800Y162050I-1599J80D01*
G01Y163450D01*
G03X818377Y164534I-1600J0D01*
G02X818417Y165114I295J271D01*
G03X819000Y166350I-1019J1236D01*
G01Y167750D01*
G03X818170Y169154I-1601J1D01*
G01Y170461D01*
X818344Y170483D01*
G03X820578Y173501I-331J2581D01*
G01X820561Y173603D01*
X822473Y175516D01*
X823431D01*
Y172747D01*
X825221D01*
G02X825504Y172064I0J-400D01*
G37*
G36*
G01X826181Y168723D02*
X828349Y170891D01*
G02X829032Y170608I283J-283D01*
G01Y167759D01*
X829398Y167393D01*
Y166350D01*
G03X829821Y165266I1600J0D01*
G02X829781Y164686I-295J-271D01*
G03X829198Y163450I1019J-1236D01*
G01Y162050D01*
G03X829200Y161962I1601J-8D01*
G01Y161752D01*
X826298D01*
Y161962D01*
G03X826300Y162050I-1599J80D01*
G01Y163450D01*
G03X825877Y164534I-1600J0D01*
G02X825917Y165114I295J271D01*
G03X826500Y166350I-1019J1236D01*
G01Y167750D01*
G03X826263Y168588I-1600J0D01*
G01X826181Y168723D01*
G37*
G36*
G01X815500Y684700D02*
X813400Y686800D01*
Y692300D01*
X815999Y694899D01*
Y707050D01*
X817999Y709050D01*
X843441D01*
X844762Y707730D01*
X861665D01*
G03X863377Y708439I1J2420D01*
G01X863820Y708882D01*
X867196D01*
X869196Y706882D01*
X871688D01*
G03X871884I98J2600D01*
G01X882696D01*
X883696Y705882D01*
Y698882D01*
X882898Y698084D01*
X851698D01*
X851498Y697884D01*
X851244D01*
Y697882D01*
X850196D01*
X848696Y696382D01*
Y685882D01*
X847514Y684700D01*
X815500D01*
G37*
G36*
G01X837999Y719050D02*
X833999Y723050D01*
X805499D01*
X801999Y726550D01*
Y740101D01*
X801550Y740550D01*
X792999D01*
X791499Y742050D01*
Y760050D01*
X793999Y762550D01*
X831850D01*
X833800Y760600D01*
Y743100D01*
X834350Y742550D01*
X876999D01*
X883999Y735550D01*
Y728550D01*
X883499Y728050D01*
X870850D01*
X866850Y732050D01*
X855000D01*
X852000Y729050D01*
Y722000D01*
X849050Y719050D01*
X837999D01*
G37*
G36*
G01X826999Y710550D02*
X825499Y712050D01*
Y718050D01*
X826999Y719550D01*
X832499D01*
X835999Y716050D01*
X839703D01*
G02X839927Y715319I0J-400D01*
G03X839348Y711206I1573J-2319D01*
G02X839040Y710550I-307J-256D01*
G01X826999D01*
G37*
G36*
G01X791331Y693353D02*
X789831Y694853D01*
Y714353D01*
X790831Y715353D01*
X807331D01*
X808831Y713853D01*
Y706391D01*
X808580Y706139D01*
Y694102D01*
X807831Y693353D01*
X791331D01*
G37*
G36*
G01X765300Y753602D02*
G03X765038Y753580I3J-1602D01*
G01X764937Y753563D01*
X764500Y754000D01*
Y755500D01*
X766500Y757500D01*
X768000D01*
X769000Y758500D01*
Y766000D01*
X770500Y767500D01*
X783500D01*
X785696Y765304D01*
Y747382D01*
X784314Y746000D01*
X772009D01*
X771500Y746509D01*
Y748960D01*
G03X772402Y750400I-700J1441D01*
G01Y752000D01*
G03X770800Y753602I-1602J0D01*
G01X769200D01*
G03X768670Y753511I2J-1602D01*
G01X768638Y753500D01*
X767262D01*
X767230Y753511D01*
G03X766700Y753602I-532J-1511D01*
G01X765300D01*
G37*
G36*
G01X818402Y1095100D02*
G03X817520Y1096531I-1602J0D01*
G01Y1113042D01*
X818028Y1113550D01*
X836991D01*
X837833Y1114392D01*
X866833D01*
X868833Y1112392D01*
X882333D01*
X883333Y1111392D01*
Y1104392D01*
X882620Y1103679D01*
X850120D01*
X848333Y1101892D01*
Y1091392D01*
X847333Y1090392D01*
X827208D01*
X827200Y1090400D01*
X818700D01*
X818402Y1090698D01*
Y1091500D01*
G03X818051Y1092500I-1602J-1D01*
G03X818402Y1093500I-1251J1001D01*
G01Y1095100D01*
G37*
G36*
G01X803999Y1124050D02*
X802999Y1125050D01*
Y1142050D01*
X792999D01*
X791499Y1143550D01*
Y1163050D01*
X793999Y1165550D01*
X832350D01*
X833800Y1164100D01*
Y1146200D01*
X834450Y1145550D01*
X879999D01*
X883999Y1141550D01*
Y1135050D01*
X882999Y1134050D01*
X867300D01*
X863800Y1137550D01*
X855450D01*
X852100Y1134200D01*
Y1125600D01*
X850550Y1124050D01*
X834819D01*
X834697Y1124172D01*
X834653D01*
X834635Y1124190D01*
X820681D01*
X820541Y1124050D01*
X803999D01*
G37*
G36*
G01X796999Y1093050D02*
X795499Y1094550D01*
Y1118550D01*
X796499Y1119550D01*
X807999D01*
X808003Y1119554D01*
X810995D01*
X812999Y1117550D01*
Y1096581D01*
X809468Y1093050D01*
X796999D01*
G37*
G36*
G01X762300Y1157602D02*
G03X762038Y1157580I3J-1602D01*
G01X761937Y1157563D01*
X761500Y1158000D01*
Y1160000D01*
X763500Y1162000D01*
X768000D01*
X769500Y1163500D01*
Y1172000D01*
X770000Y1172500D01*
X781500D01*
X785833Y1168167D01*
Y1148892D01*
X784333Y1147392D01*
X773500D01*
X772946Y1147946D01*
Y1156000D01*
X772000Y1156946D01*
Y1157000D01*
X771500Y1157500D01*
X768362D01*
X768330Y1157511D01*
G03X767800Y1157602I-532J-1511D01*
G01X766200D01*
G03X765670Y1157511I2J-1602D01*
G01X765638Y1157500D01*
X764262D01*
X764230Y1157511D01*
G03X763700Y1157602I-532J-1511D01*
G01X762300D01*
G37*
G36*
G01X819100Y1493200D02*
X818402Y1493898D01*
Y1495000D01*
G03X818051Y1496000I-1602J-1D01*
G03X818402Y1497000I-1251J1001D01*
G01Y1498600D01*
G03X817999Y1499662I-1601J0D01*
G01Y1516270D01*
X826696D01*
Y1518050D01*
X832999D01*
X833024Y1518024D01*
X838555D01*
X839827Y1519296D01*
X868827D01*
X870827Y1517296D01*
X884327D01*
X885327Y1516296D01*
Y1509296D01*
X884528Y1508498D01*
X853329D01*
X853129Y1508298D01*
X853126D01*
Y1508296D01*
X851827D01*
X850327Y1506796D01*
Y1496296D01*
X849327Y1495296D01*
X844800D01*
X842704Y1493200D01*
X819100D01*
G37*
G36*
G01X808499Y1529550D02*
X804999Y1533050D01*
Y1546050D01*
X803999Y1547050D01*
X795999D01*
X794999Y1548050D01*
Y1567050D01*
X796499Y1568550D01*
X833950D01*
X836300Y1566200D01*
Y1549250D01*
X837000Y1548550D01*
X881999D01*
X883999Y1546550D01*
Y1539050D01*
X883499Y1538550D01*
X869499D01*
X866499Y1541550D01*
X866198D01*
X865997Y1541752D01*
X858001D01*
X857800Y1541550D01*
X857700D01*
X845700Y1529550D01*
X808499D01*
G37*
G36*
G01X765800Y1560602D02*
G03X765538Y1560580I3J-1602D01*
G01X765437Y1560563D01*
X765000Y1561000D01*
Y1562500D01*
X766500Y1564000D01*
X769500D01*
X772500Y1567000D01*
Y1574500D01*
X773500Y1575500D01*
X785000D01*
X788327Y1572173D01*
Y1552796D01*
X786827Y1551296D01*
X776000D01*
X773500Y1553796D01*
Y1554000D01*
X773066Y1554434D01*
X773055Y1554494D01*
G03X773007Y1554696I-2554J-500D01*
G01X773000Y1554722D01*
Y1560000D01*
X772500Y1560500D01*
X771862D01*
X771830Y1560511D01*
G03X771300Y1560602I-532J-1511D01*
G01X769700D01*
G03X769170Y1560511I2J-1602D01*
G01X769138Y1560500D01*
X767762D01*
X767730Y1560511D01*
G03X767200Y1560602I-532J-1511D01*
G01X765800D01*
G37*
G36*
G01X810245Y1500222D02*
X793745D01*
X792245Y1501722D01*
Y1521222D01*
X793245Y1522222D01*
X809745D01*
X811245Y1520722D01*
Y1501222D01*
X810245Y1500222D01*
G37*
G36*
G01X832300Y1720300D02*
X831381Y1721219D01*
G03X830900Y1721770I-2181J-1419D01*
G01Y1729500D01*
X831700Y1730300D01*
X833400D01*
X834100Y1731000D01*
Y1737100D01*
X835200Y1738200D01*
X865100D01*
X865700Y1737600D01*
Y1725500D01*
X860500Y1720300D01*
X832300D01*
G37*
G36*
G01X827000Y1788750D02*
G03X826170Y1790154I-1601J1D01*
G01Y1792212D01*
X828349Y1794391D01*
G02X829031Y1794108I282J-283D01*
G01Y1793509D01*
X829192Y1793349D01*
Y1791004D01*
X830333Y1789862D01*
X830227Y1789723D01*
G03X829898Y1788750I1272J-972D01*
G01Y1787707D01*
X828425Y1786235D01*
X828380Y1786220D01*
G03X827151Y1785355I819J-2470D01*
G02X826509Y1785371I-315J246D01*
G03X826377Y1785534I-1308J-924D01*
G02X826417Y1786114I295J271D01*
G03X827000Y1787350I-1019J1236D01*
G01Y1788750D01*
G37*
G36*
G01X819839Y1786399D02*
X819749Y1786404D01*
G03X819545Y1786409I-166J-2597D01*
G02X819359Y1786691I-4J200D01*
G03X819500Y1787350I-1460J657D01*
G01Y1788750D01*
G03X818670Y1790154I-1601J1D01*
G01Y1790870D01*
G03Y1795230I-1421J2180D01*
G01Y1796212D01*
X819829Y1797372D01*
X820033Y1797576D01*
X823431D01*
Y1794795D01*
X823769D01*
G02X824052Y1794112I0J-400D01*
G01X823328Y1793388D01*
Y1790204D01*
G03X822398Y1788750I672J-1454D01*
G01Y1787812D01*
X821656Y1787070D01*
X820511D01*
X819839Y1786399D01*
G37*
G36*
G01X773000Y1957213D02*
X772000Y1958213D01*
Y1961500D01*
X771169Y1962331D01*
G03X770631Y1962869I-1369J-831D01*
G01X770500Y1963000D01*
X770362D01*
X770330Y1963011D01*
G03X769800Y1963102I-532J-1511D01*
G01X768200D01*
G03X767670Y1963011I2J-1602D01*
G01X767638Y1963000D01*
X766262D01*
X766230Y1963011D01*
G03X765700Y1963102I-532J-1511D01*
G01X764657D01*
X763500Y1964259D01*
Y1965000D01*
X765000Y1966500D01*
X769500D01*
X770000Y1967000D01*
Y1976213D01*
X771500Y1977713D01*
X784314D01*
X785814Y1976213D01*
Y1958713D01*
X784314Y1957213D01*
X773000D01*
G37*
G36*
G01X770500Y1946741D02*
Y1942124D01*
G03X769909Y1941714I1000J-2073D01*
G01X763666D01*
Y1944274D01*
X761226D01*
X761000Y1944500D01*
Y1948697D01*
X761768Y1949465D01*
Y1950211D01*
X767080D01*
X767698Y1949593D01*
Y1948600D01*
G03X769300Y1946998I1602J0D01*
G01X770243D01*
X770500Y1946741D01*
G37*
G36*
G01X819100Y1899800D02*
X818000Y1900900D01*
Y1907600D01*
X817999D01*
Y1921550D01*
X819362Y1922914D01*
X825888D01*
Y1923013D01*
X832987D01*
X833000Y1923026D01*
X838413D01*
X840500Y1925113D01*
X868814D01*
X870814Y1923113D01*
X884314D01*
X885314Y1922113D01*
Y1915113D01*
X884516Y1914314D01*
X853316D01*
X853115Y1914113D01*
X851814D01*
X850314Y1912613D01*
Y1902113D01*
X849314Y1901113D01*
X842000D01*
X840687Y1899800D01*
X819100D01*
G37*
G36*
G01X805149Y1935400D02*
X803999Y1936550D01*
Y1949804D01*
G03X800480Y1952656I-1500J1746D01*
G01X800466Y1952631D01*
X800386Y1952550D01*
X793499D01*
X792499Y1953550D01*
Y1972550D01*
X794499Y1974550D01*
X833450D01*
X834900Y1973100D01*
Y1961100D01*
X836600Y1959400D01*
X862638D01*
X862670Y1959389D01*
G03X863200Y1959298I532J1511D01*
G01X865250D01*
X871999Y1952550D01*
X882999D01*
X883999Y1951550D01*
Y1945050D01*
X883499Y1944550D01*
X866499D01*
X862499Y1948550D01*
X854400D01*
X851800Y1945950D01*
Y1936500D01*
X850700Y1935400D01*
X805149D01*
G37*
G36*
G01X794936Y1906865D02*
X793436Y1908365D01*
Y1927865D01*
X794436Y1928865D01*
X810936D01*
X812416Y1927386D01*
Y1907873D01*
X811407Y1906865D01*
X794936D01*
G37*
G36*
G01X919999Y15050D02*
X900499D01*
X897999Y17550D01*
Y37050D01*
X910999Y50050D01*
X920999D01*
X922499Y48550D01*
Y17550D01*
X919999Y15050D01*
G37*
G36*
G01X923115Y49633D02*
X921497Y51252D01*
X912865D01*
G02X912582Y51934I0J400D01*
G01X921700Y61052D01*
Y73905D01*
X922258D01*
Y96848D01*
X924204D01*
X928200Y100845D01*
Y101079D01*
X928265Y101139D01*
G03X927453Y105471I-1766J1911D01*
G02X927546Y105856I74J186D01*
G03X927699Y105848I160J1594D01*
G01X929299D01*
G03X930158Y106098I0J1601D01*
G01X931401D01*
X931424Y106093D01*
G03X931799Y106048I377J1557D01*
G01X933199D01*
G03X933416Y106063I-2J1602D01*
G02X933807Y105451I54J-396D01*
G03X934233Y102139I2192J-1401D01*
G01X934298Y102079D01*
Y101845D01*
X936440Y99702D01*
Y97195D01*
X934740D01*
Y73905D01*
X934798D01*
Y72048D01*
X933001Y70252D01*
X927501D01*
X923798Y66548D01*
Y49916D01*
G02X923115Y49633I-400J0D01*
G37*
G36*
G01X898711Y92485D02*
G03X897576Y92796I-1156J-1991D01*
G01Y100848D01*
X901041D01*
X901073Y100837D01*
G03X901599Y100748I527J1513D01*
G01X902999D01*
G03X903072Y100750I-7J1602D01*
G02X903471Y100231I18J-399D01*
G03X903398Y99750I1528J-478D01*
G01Y98350D01*
G03X903798Y97291I1602J0D01*
G01Y96519D01*
G03X902897Y94559I1701J-1969D01*
G02X902349Y94189I-400J2D01*
G03X899295Y92715I-850J-2139D01*
G02X898711Y92485I-383J116D01*
G37*
G36*
G01X914700Y114638D02*
X917615Y117552D01*
G02X918298Y117269I283J-283D01*
G01Y113008D01*
X918286Y112976D01*
G03X918198Y112450I1513J-524D01*
G01Y111050D01*
G03X918228Y110740I1601J-2D01*
G01X918232Y110721D01*
Y110502D01*
X917877D01*
X917839Y110518D01*
G03X917199Y110652I-641J-1468D01*
G01X915799D01*
G03X915318Y110578I0J-1602D01*
G02X914799Y110977I-120J381D01*
G03X914800Y111050I-1600J58D01*
G01Y112450D01*
G03X914712Y112976I-1601J2D01*
G01X914700Y113008D01*
Y114638D01*
G37*
G36*
G01X883499Y726050D02*
X883999Y725550D01*
Y723550D01*
X883499Y723050D01*
X863499D01*
X859499Y719050D01*
X855499D01*
X854999Y719550D01*
Y730050D01*
X855499Y730550D01*
X866200D01*
X870700Y726050D01*
X883499D01*
G37*
G36*
G01X845938Y710570D02*
X844214Y712295D01*
X844237Y712402D01*
G03X843073Y715319I-2737J598D01*
G02X843297Y716050I224J331D01*
G01X861499D01*
X862499Y715050D01*
Y711579D01*
X861491Y710570D01*
X845938D01*
G37*
G36*
G01X861196Y684882D02*
X852196D01*
X851196Y685882D01*
Y695882D01*
X852196Y696882D01*
X882696D01*
X883696Y695882D01*
Y693882D01*
X882696Y692882D01*
X869196D01*
X861196Y684882D01*
G37*
G36*
G01X866499Y1123550D02*
X856499D01*
X855499Y1124550D01*
Y1135050D01*
X855999Y1135550D01*
X862999D01*
X866999Y1131550D01*
X883499D01*
X883999Y1131050D01*
Y1129050D01*
X883499Y1128550D01*
X871499D01*
X866499Y1123550D01*
G37*
G36*
G01X860833Y1090392D02*
X851833D01*
X850833Y1091392D01*
Y1101392D01*
X851833Y1102392D01*
X882333D01*
X883333Y1101392D01*
Y1099392D01*
X882333Y1098392D01*
X868833D01*
X860833Y1090392D01*
G37*
G36*
G01X863988Y1528050D02*
X863969Y1528068D01*
X858509D01*
X857499Y1529079D01*
Y1539550D01*
X858499Y1540550D01*
X865499D01*
X868999Y1537050D01*
X883499D01*
X883999Y1536550D01*
Y1534050D01*
X883499Y1533550D01*
X869999D01*
X864499Y1528050D01*
X863988D01*
G37*
G36*
G01X862827Y1495296D02*
X853827D01*
X852827Y1496296D01*
Y1506296D01*
X853827Y1507296D01*
X884327D01*
X885327Y1506296D01*
Y1504296D01*
X884327Y1503296D01*
X870827D01*
X862827Y1495296D01*
G37*
G36*
G01X882500Y1712000D02*
X882102Y1712398D01*
Y1717700D01*
X882000D01*
Y1719500D01*
X881500Y1720000D01*
Y1725000D01*
X880154Y1726346D01*
X880174Y1726450D01*
G03X880202Y1726750I-1573J298D01*
G01Y1728150D01*
G03X880158Y1728523I-1601J0D01*
G01X880132Y1728632D01*
X880500Y1729000D01*
X885201D01*
X886298Y1727902D01*
Y1726002D01*
X888002Y1724298D01*
X890202D01*
X891500Y1723000D01*
Y1720000D01*
X890602Y1719102D01*
X889300D01*
G03X887698Y1717500I0J-1602D01*
G01Y1716612D01*
X887598Y1716512D01*
Y1713598D01*
X886000Y1712000D01*
X884622D01*
X884596Y1712007D01*
G03X883204I-696J-2507D01*
G01X883178Y1712000D01*
X882500D01*
G37*
G36*
G01X882900Y1691200D02*
X882300Y1691800D01*
Y1705100D01*
X883000Y1705800D01*
X888935D01*
G03X889000Y1705798I82J1599D01*
G01X890400D01*
G03X890465Y1705800I-17J1601D01*
G01X896900D01*
X897300Y1705400D01*
Y1692400D01*
X896100Y1691200D01*
X882900D01*
G37*
G36*
G01X845400Y1706200D02*
X844100Y1707500D01*
Y1716800D01*
X845400Y1718100D01*
X872201D01*
X872502Y1717798D01*
X876798D01*
Y1712502D01*
X877000Y1712300D01*
X876700Y1712000D01*
X876621D01*
G03X875204Y1712007I-721J-2500D01*
G01X875178Y1712000D01*
X871863D01*
G03X871001Y1712252I-862J-1350D01*
G01X869401D01*
G03X868539Y1712000I0J-1602D01*
G01X867800D01*
X862000Y1706200D01*
X845400D01*
G37*
G36*
G01X879000Y1712000D02*
X878352Y1712648D01*
Y1717700D01*
X878000D01*
Y1718500D01*
X877500Y1719000D01*
X873000D01*
X871500Y1720500D01*
Y1742200D01*
X872100Y1742800D01*
X878239D01*
G02X878631Y1742320I0J-400D01*
G03X878598Y1742000I1569J-323D01*
G01Y1739400D01*
G03X879200Y1738149I1601J0D01*
G01Y1729399D01*
X878798Y1728998D01*
Y1726002D01*
X879200Y1725601D01*
Y1725300D01*
X880000Y1724500D01*
Y1719500D01*
X880298Y1719202D01*
Y1719198D01*
X880302D01*
X880798Y1718701D01*
Y1712298D01*
X880500Y1712000D01*
X879000D01*
G37*
G36*
G01X881200Y1738300D02*
X880959Y1738541D01*
X881026Y1738670D01*
G03X881202Y1739400I-1426J730D01*
G01Y1742000D01*
G03X880500Y1743325I-1601J0D01*
G01Y1745400D01*
X881100Y1746000D01*
X887400D01*
X887900Y1745500D01*
Y1741500D01*
X884700Y1738300D01*
X881200D01*
G37*
G36*
G01X886147Y1729753D02*
X884900Y1731000D01*
Y1736600D01*
X886800Y1738500D01*
X892300D01*
X893800Y1737000D01*
Y1726000D01*
X893300Y1725500D01*
X888500D01*
X887654Y1726346D01*
X887674Y1726450D01*
G03X887702Y1726750I-1573J298D01*
G01Y1728150D01*
G03X886221Y1729747I-1602J0D01*
G01X886147Y1729753D01*
G37*
G36*
G01X862999Y1935050D02*
X856999D01*
X856499Y1935550D01*
Y1946050D01*
X856999Y1946550D01*
X861999D01*
X865999Y1942550D01*
X882999D01*
X883999Y1941550D01*
Y1940050D01*
X883499Y1939550D01*
X867499D01*
X862999Y1935050D01*
G37*
G36*
G01X853814Y1901113D02*
X852814Y1902113D01*
Y1912113D01*
X853814Y1913113D01*
X884314D01*
X885314Y1912113D01*
Y1910113D01*
X884314Y1909113D01*
X870814D01*
X862834Y1901134D01*
X860076D01*
X860055Y1901113D01*
X853814D01*
G37*
G36*
G01X926999Y30550D02*
X924999Y32550D01*
Y66050D01*
X927999Y69050D01*
X933499D01*
X935999Y71550D01*
Y73398D01*
X936250D01*
Y85718D01*
X941544D01*
Y85818D01*
X946973D01*
X947205Y86050D01*
X947499D01*
X949999Y88550D01*
Y88844D01*
X951700Y90545D01*
Y91050D01*
X953999D01*
X954499Y90550D01*
Y34050D01*
X950999Y30550D01*
X926999D01*
G37*
G36*
G01X954404Y95052D02*
X953750Y95705D01*
Y95955D01*
X953600Y96105D01*
Y96850D01*
G03X952650Y98313I-1602J0D01*
G01Y103295D01*
X952954Y103598D01*
X959363D01*
X962340Y100621D01*
Y98019D01*
G03X961447Y95854I1702J-1969D01*
G02X961268Y95640I-199J-15D01*
G03X959948Y95052I229J-2291D01*
G01X954404D01*
G37*
G36*
G01X946794Y127348D02*
X954341Y119802D01*
G02X954117Y119124I-283J-282D01*
G03X952269Y115209I382J-2574D01*
G01X952298Y115162D01*
Y114712D01*
X951867Y114281D01*
X948700Y117448D01*
Y118852D01*
X945298D01*
Y118609D01*
G02X944615Y118326I-400J0D01*
G01X941989Y120952D01*
X940609D01*
G02X940223Y121455I0J400D01*
G03X939105Y124069I-2224J595D01*
G01X939080Y124083D01*
X936497Y126666D01*
G02X936780Y127348I283J282D01*
G01X946794D01*
G37*
%LPC*%
G75*
G36*
G01X902899Y127750D02*
Y126750D01*
X902999Y126250D01*
Y125250D01*
X901999D01*
Y126250D01*
X901899Y126750D01*
Y127750D01*
X902899D01*
G37*
G54D100*
X28000Y121000D03*
Y118000D03*
Y116000D03*
Y113000D03*
X235498Y291114D03*
X239998D03*
X235498Y302114D03*
X217298Y310614D03*
X220698D03*
X235498Y335114D03*
X239998D03*
X211898Y343614D03*
X215298D03*
X219300Y1120500D03*
X215900D03*
X240000Y1108600D03*
X235500D03*
X240000Y1097600D03*
X235500D03*
X217000Y1108600D03*
X221500D03*
X234300Y1507900D03*
X238800D03*
X234300Y1518900D03*
X216299Y1527550D03*
X219699D03*
X251500Y1542200D03*
X254900D03*
X235499Y1551550D03*
X239999D03*
X292299Y63613D03*
X295699D03*
X311499Y71613D03*
X315999D03*
X290799Y30613D03*
X311499Y38113D03*
X315999D03*
X311600Y316300D03*
X314000D03*
X311600Y322300D03*
X314000D03*
X294300Y328000D03*
X296700D03*
X334298Y332014D03*
X309799Y332950D03*
X334298Y334214D03*
Y336014D03*
X305699Y354950D03*
Y357150D03*
Y358950D03*
Y361150D03*
X308099Y1537950D03*
X310499D03*
X295800Y1548600D03*
X298200D03*
X307799Y1553450D03*
X305699Y1571950D03*
Y1574150D03*
X307700Y1581500D03*
X309400Y1581700D03*
X399699Y57150D03*
X374199Y58150D03*
X388300Y71000D03*
X390700D03*
X368100Y71100D03*
X370500D03*
X382199Y24950D03*
Y27150D03*
Y29450D03*
Y31650D03*
X815399Y158250D03*
X817599D03*
X822899D03*
X825099D03*
X830399D03*
X832599D03*
X754300Y711000D03*
X756700D03*
X776300D03*
X778700D03*
X778799Y722950D03*
X754496Y723782D03*
X778799Y727450D03*
X754300Y705000D03*
X756700D03*
X776300D03*
X778700D03*
X759300Y1112000D03*
X761700D03*
X777300D03*
X779700D03*
X779799Y1122450D03*
X755133Y1125292D03*
X759300Y1106000D03*
X761700D03*
X777300D03*
X779700D03*
X782000Y1517700D03*
X784400D03*
X760800Y1518000D03*
X763200D03*
X758127Y1530196D03*
X782000Y1511700D03*
X784400D03*
X760800Y1512000D03*
X763200D03*
X813899Y1779250D03*
X816099D03*
X823399D03*
X825599D03*
X832399D03*
X834599D03*
X758300Y1924000D03*
X760700D03*
X783300D03*
X785700D03*
X779299Y1933950D03*
X754614Y1936613D03*
X758300Y1918000D03*
X760700D03*
X783300D03*
X785700D03*
X903299Y83550D03*
X909199D03*
X899399Y83750D03*
X901599D03*
X833946Y696682D03*
X838446D03*
X853996Y704882D03*
X857396D03*
X864596Y739082D03*
X861196D03*
X841499Y730050D03*
X836999D03*
X767100Y755800D03*
X768800Y756000D03*
X771200D03*
X838583Y1102192D03*
X853633Y1110392D03*
X857033D03*
X837499Y1135050D03*
X841999D03*
X764100Y1159800D03*
X765800Y1160000D03*
X768200D03*
X835827Y1496096D03*
X840327D03*
Y1507096D03*
X856127Y1515296D03*
X859527D03*
X840327Y1539796D03*
X844827D03*
X864000Y1545100D03*
X767600Y1562800D03*
X771700Y1563000D03*
X766100Y1965300D03*
X770200Y1965500D03*
X836064Y1901813D03*
X840564D03*
Y1912813D03*
X855614Y1921113D03*
X859014D03*
X838999Y1946050D03*
X843499D03*
X862800Y1954900D03*
X866200D03*
X901199Y97950D03*
X853996Y713882D03*
X857396D03*
X888000Y1723200D03*
X882401Y1726350D03*
X884301D03*
X885901Y1695550D03*
X893100Y1702500D03*
X888600Y1703600D03*
X890800D03*
X869001Y1714650D03*
X871401D03*
X876801Y1726350D03*
Y1728550D03*
X875400Y1739000D03*
X884400Y1742400D03*
X889901Y1728550D03*
X950999Y87850D03*
X955999Y97250D03*
G54D112*
X906249Y83550D03*
%LPD*%
G75*
G54D10*
X-30766Y56622D03*
X-33866Y1947322D03*
X21499Y17050D03*
X1010999Y18550D03*
X1008999Y1968550D03*
X1073334Y50022D03*
G54D11*
G01X8499Y1937550D02*
X12749Y1933300D01*
X19749D01*
X21749Y1935300D01*
Y1936050D01*
G01X38462Y1937069D02*
Y1933013D01*
X36499Y1931050D01*
X32499D01*
X27999Y1935550D01*
X26499D01*
G01X21749Y1936050D02*
X25999D01*
X26499Y1935550D01*
G01X37999Y1968750D02*
X40431Y1966318D01*
Y1956355D01*
G01X36494Y1937069D02*
Y1934045D01*
X35999Y1933550D01*
X33499D01*
X28799Y1938250D01*
Y1939750D01*
X26999Y1941550D01*
G01X43462Y1961160D02*
X43704D01*
X44499Y1961955D01*
Y1964300D01*
X43999Y1964800D01*
G01X42399Y1956355D02*
Y1959855D01*
X43462Y1960918D01*
Y1961160D01*
G01X38462Y1956355D02*
Y1961716D01*
X36878Y1963300D01*
X36699D01*
G01X31999Y1964800D02*
X32249Y1964550D01*
X35499D01*
X36699Y1963350D01*
Y1963300D01*
G01X32999Y1960555D02*
X35489D01*
X36494Y1959550D01*
Y1956355D01*
G01X27999Y1964800D02*
X32244Y1960555D01*
X32999D01*
G01X34525Y1956355D02*
X33194D01*
X31499Y1958050D01*
X28701D01*
X28389Y1958362D01*
G01X23999Y1964800D02*
X24499Y1964300D01*
X24934D01*
X26485Y1962749D01*
Y1960266D01*
X28389Y1958362D01*
G01X19999Y1964800D02*
X23999D01*
G01X34525Y1937069D02*
X33980D01*
X30999Y1940050D01*
Y1942550D01*
X26499Y1947050D01*
G01X21749Y1948050D02*
X25499D01*
X26499Y1947050D01*
G01X40431Y1937069D02*
Y1931482D01*
X37599Y1928650D01*
X33573D01*
G01X18499Y1929550D02*
X19199D01*
X21037Y1931388D01*
X28150D01*
X30888Y1928650D01*
X33573D01*
G01X36249Y1918050D02*
X34699Y1916500D01*
X28100D01*
X24700Y1919900D01*
X21349D01*
X18499Y1922750D01*
Y1923550D01*
G01X36249Y1918050D02*
Y1917300D01*
X40899Y1912650D01*
Y1912934D01*
X41597D01*
G01X36249Y1921550D02*
Y1922800D01*
X37299Y1923850D01*
X43799D01*
X43999Y1924050D01*
G01X42399Y1937069D02*
Y1935468D01*
X42299Y1935368D01*
Y1929754D01*
X39990Y1927445D01*
G01X27030Y1928688D02*
X27830Y1927888D01*
X28150D01*
X29988Y1926050D01*
X38595D01*
X39990Y1927445D01*
G01X201033Y82371D02*
Y84050D01*
X202999Y86016D01*
X206965D01*
X208999Y88050D01*
Y92050D01*
G01X209499Y97800D02*
X208999Y97300D01*
Y92050D01*
G01X213499Y97800D02*
X209499D01*
G01X217499D02*
X213499D01*
G01X220319Y78434D02*
X225383D01*
X226896Y79947D01*
Y82045D01*
X226999Y82148D01*
Y84750D01*
X227022Y84773D01*
Y85278D01*
G01X230122Y92572D02*
X226999Y89449D01*
Y85478D01*
X227022Y85455D01*
Y85278D01*
G01X197226Y90428D02*
X193999Y87201D01*
Y80050D01*
X195615Y78434D01*
X201033D01*
G01X197499Y97800D02*
X197226Y97527D01*
Y90428D01*
G01X229296Y81050D02*
Y82574D01*
X233722Y87000D01*
X233834D01*
X233884Y87050D01*
X238199D01*
X240999Y89850D01*
G01X220319Y76465D02*
X226914D01*
X229296Y78847D01*
Y81050D01*
G01X201499Y97800D02*
Y95050D01*
X202999Y93550D01*
Y90550D01*
G01X205499Y97800D02*
X201499D01*
G01X201033Y80402D02*
X197647D01*
X196499Y81550D01*
Y83902D01*
X198647Y86050D01*
Y86198D01*
X202999Y90550D01*
G01X230749Y76300D02*
X228946Y74497D01*
X220319D01*
G01X235499Y84800D02*
X234634D01*
X232999Y83165D01*
Y80800D01*
X231999Y79800D01*
Y77550D01*
X230749Y76300D01*
G01X238249Y95550D02*
X236600D01*
X233622Y92572D01*
G01D02*
Y90974D01*
X230874Y88226D01*
X230811D01*
G01X220319Y80402D02*
X223851D01*
X224499Y81050D01*
Y92050D01*
G01X230249Y97050D02*
X226499D01*
X224499Y95050D01*
Y92050D01*
G01X220319Y82371D02*
Y96870D01*
X223499Y100050D01*
X225499D01*
G01X230249Y101050D02*
X229249Y100050D01*
X225499D01*
G01X230249Y105050D02*
Y101050D01*
G01X201033Y76465D02*
X194584D01*
X190499Y80550D01*
Y87050D01*
X188999Y88550D01*
G01X185999Y95050D02*
X188999Y92050D01*
Y88550D01*
G01X201033Y74497D02*
X191499D01*
G01X182922Y86572D02*
X187999Y81495D01*
Y79550D01*
X191499Y76050D01*
Y74497D01*
G01X952499Y108300D02*
X955749D01*
X958499Y111050D01*
Y118050D01*
X947499Y129050D01*
X920550D01*
X909799Y118299D01*
Y110680D01*
X911379Y109100D01*
X911699D01*
X912499Y108300D01*
G01X914999Y103050D02*
X912499Y105550D01*
Y108300D01*
G01X918856Y91456D02*
X915593D01*
X912999Y94050D01*
Y101050D01*
X914999Y103050D01*
G01X918856Y93424D02*
X916499D01*
X915499Y94424D01*
Y97550D01*
X920999Y103050D01*
G01X918856Y89487D02*
X914762D01*
X910499Y93750D01*
Y98550D01*
G01X906499Y115050D02*
Y110323D01*
X908999Y107823D01*
Y103550D01*
X910499Y102050D01*
Y98550D01*
G01X907999Y88300D02*
Y89438D01*
X905499Y91938D01*
Y94550D01*
G01X905749Y99050D02*
X905499Y98800D01*
Y94550D01*
G01X918856Y95393D02*
Y96907D01*
X920499Y98550D01*
X923499D01*
X926499Y101550D01*
Y103050D01*
G01X904499Y88300D02*
Y89050D01*
X901499Y92050D01*
G01X918856Y87519D02*
X913030D01*
X912399Y88150D01*
G01X905749Y103050D02*
X907999Y100800D01*
Y92550D01*
X912399Y88150D01*
G01X951249Y96050D02*
X949999Y94800D01*
Y91250D01*
X946268Y87519D01*
X938142D01*
G01X961499Y93350D02*
X953699D01*
X952049Y95000D01*
Y95250D01*
X951249Y96050D01*
G01X958499Y89550D02*
X961999D01*
X964042Y91593D01*
Y96050D01*
G01X946999Y98199D02*
Y99350D01*
X949199Y101550D01*
G01X946999Y98199D02*
Y92050D01*
X944436Y89487D01*
X938142D01*
G01X964042Y96050D02*
Y101326D01*
X960068Y105300D01*
X952249D01*
X949199Y102250D01*
Y101550D01*
G01X938142Y91456D02*
X942405D01*
X944499Y93550D01*
Y95050D01*
G01X948499Y108300D02*
X945749Y105550D01*
X945499D01*
X944499Y104550D01*
Y95050D01*
G01X938142Y93424D02*
X940873D01*
X941873Y94424D01*
Y103050D01*
G01X944499Y108300D02*
X941873Y105674D01*
Y103050D01*
G01X938142Y95393D02*
Y100407D01*
X935999Y102550D01*
Y104050D01*
G01X936499Y108300D02*
X935999Y107800D01*
Y104050D01*
G01X940499Y108300D02*
X936499D01*
G01X924499D02*
Y105050D01*
X926499Y103050D01*
X-39052Y28742D03*
X9843Y153168D03*
Y265767D03*
X-43327Y310478D03*
X9843Y353144D03*
Y717711D03*
Y762617D03*
Y875216D03*
X-39686Y917251D03*
X9843Y1137420D03*
X-38801Y1082342D03*
X9843Y1250019D03*
X-44886Y1294251D03*
X9843Y1337396D03*
Y1701963D03*
Y1746869D03*
Y1859468D03*
X-43103Y1928864D03*
X78150Y28858D03*
Y178464D03*
Y434370D03*
Y583976D03*
Y839882D03*
Y989488D03*
Y1245394D03*
Y1395000D03*
Y1650906D03*
Y1800512D03*
X158071Y191614D03*
Y341220D03*
Y597126D03*
Y746732D03*
Y1002638D03*
Y1152244D03*
Y1408150D03*
Y1557756D03*
Y1813662D03*
Y1963268D03*
X886417Y191614D03*
Y341220D03*
Y597126D03*
Y746732D03*
Y1002638D03*
Y1152244D03*
Y1408150D03*
Y1557756D03*
Y1813662D03*
Y1963268D03*
X1071932Y32074D03*
X1074813Y1348051D03*
X1019291Y1416024D03*
Y1694212D03*
X1076613Y1740651D03*
X1074813Y1957551D03*
G54D20*
X26300Y119500D03*
Y114500D03*
X185799Y95050D03*
X906299Y115050D03*
X896200Y1716200D03*
X884201Y1693850D03*
X971000Y1665500D03*
Y1660500D03*
G54D30*
X46800Y412300D03*
X42900Y604800D03*
X30499Y1592060D03*
X23999Y1968250D03*
X31999Y1922250D03*
X27999Y1968250D03*
X174999Y74750D03*
X141499Y443813D03*
X146499D03*
X159199Y520550D03*
X167199D03*
X174199D03*
X136000Y532200D03*
X170499Y812313D03*
X166499D03*
X167499Y836813D03*
X172499D03*
X119000Y1136700D03*
X119499Y1109750D03*
X100500Y1107200D03*
X109499Y1201813D03*
X105499D03*
X106999Y1227313D03*
X111999D03*
X103999Y1472000D03*
X111499D03*
X115599Y1471950D03*
X152600Y1684600D03*
X135999Y1706750D03*
X131999D03*
X209499Y101250D03*
X217499D03*
X201499D03*
X185499Y120750D03*
X188000Y424200D03*
X211500Y822700D03*
X203500D03*
X184600Y1376500D03*
X180500D03*
X192800Y1654500D03*
X223436Y1897065D03*
X315000Y373700D03*
X313500Y1973700D03*
X644049Y1796334D03*
Y1807334D03*
X752978Y339124D03*
X751196Y738582D03*
X751499Y1143750D03*
X753827Y1546996D03*
X710549Y1801334D03*
X708549Y1812034D03*
X751000Y1950700D03*
X816499Y162750D03*
X823999D03*
X831499D03*
X765000Y355700D03*
X771500Y341200D03*
X826100Y670100D03*
X766000Y754700D03*
X770000Y742200D03*
X763000Y1158700D03*
X769500Y1145200D03*
X772000Y1549200D03*
X766500Y1561700D03*
X833499Y1783750D03*
X814999D03*
X824499D03*
X828000Y1884700D03*
X765000Y1964200D03*
X770000Y1952700D03*
X916499Y111750D03*
X900499Y88250D03*
X903499Y131750D03*
X940499Y111750D03*
X944499D03*
X924499D03*
X932499D03*
X952499D03*
G54D12*
G01X12560Y223247D02*
X26247D01*
G01X12560Y235058D02*
X23442D01*
G01X12560Y1207499D02*
X21563D01*
X23200Y1209136D01*
Y1209300D01*
G01X23442Y235058D02*
X23500Y235000D01*
X11999Y53550D03*
X11499Y34050D03*
X10000Y16500D03*
X11499Y142050D03*
X11999Y69050D03*
X6891Y161611D03*
X11302Y161500D03*
X7089Y166111D03*
X11500Y166000D03*
X9499Y301050D03*
Y281550D03*
X8999Y318550D03*
X8599Y751650D03*
X10999Y774050D03*
X8999Y889550D03*
X8499Y979050D03*
X8999Y961550D03*
Y942050D03*
Y926550D03*
X8499Y907050D03*
X8999Y1060550D03*
Y1041050D03*
Y1025550D03*
X8499Y1006050D03*
X8999Y988550D03*
X6500Y1098000D03*
Y1103500D03*
Y1110000D03*
Y1116500D03*
X8499Y1078050D03*
X6500Y1146000D03*
X13000Y1145500D03*
Y1151000D03*
X7000Y1151500D03*
X8799Y1302550D03*
X7499Y1282050D03*
X7999Y1264550D03*
X9399Y1347350D03*
X8299Y1320050D03*
X7099Y1717750D03*
X7199Y1731450D03*
X6099Y1753750D03*
X11299Y1850050D03*
X9099Y1881550D03*
X8499Y1979550D03*
X11500Y1987000D03*
X92999Y52050D03*
X90899Y14850D03*
X23499Y27050D03*
X50999Y21150D03*
Y47750D03*
X27799Y38450D03*
X25799Y64050D03*
X65499Y59050D03*
Y41550D03*
Y27050D03*
X40999Y42050D03*
Y27550D03*
X17600Y5604D03*
X36000D03*
X55700Y5900D03*
X73900Y6200D03*
X90900Y5800D03*
X88000Y36400D03*
X93000Y44900D03*
X92900Y39700D03*
X32400Y115400D03*
X37000Y115300D03*
X32300Y121000D03*
X36900Y120900D03*
X32100Y130700D03*
X37000D03*
X32100Y136600D03*
X36800Y136700D03*
X52499Y145050D03*
Y130550D03*
X59499Y108050D03*
Y90550D03*
Y76050D03*
X96184Y151065D03*
X71015Y123666D03*
X78165Y137116D03*
X95814Y136065D03*
X77165Y110799D03*
X69510Y217221D03*
X61757Y216415D03*
X36500Y179000D03*
Y188500D03*
X35000Y198500D03*
X30000Y179000D03*
X23500D03*
X30000Y188500D03*
X24000D03*
X29000Y198000D03*
X23500D03*
X15302Y161500D03*
X19500D03*
X15500Y166000D03*
X19198Y152000D03*
X19698Y166000D03*
X92899Y231450D03*
X48499Y228550D03*
X23999Y229050D03*
X52499Y162550D03*
X96184Y166065D03*
X52499Y198550D03*
X56999Y217050D03*
X77749Y213500D03*
X41499Y219050D03*
X23895Y238995D03*
X51099Y300050D03*
X90899Y309550D03*
X93199Y279650D03*
X84899Y289250D03*
X86899Y242750D03*
X75299Y261750D03*
X42999Y275650D03*
X48499Y260550D03*
Y243050D03*
X23999Y261050D03*
Y243550D03*
X52199Y342350D03*
X89899Y368350D03*
X94199Y325550D03*
X93499Y337450D03*
X95499Y355450D03*
X89999Y396450D03*
X39999Y359550D03*
Y342050D03*
Y327550D03*
X15499Y360050D03*
Y342550D03*
Y328050D03*
X94500Y456800D03*
X75300Y454100D03*
X67300Y450200D03*
X68899Y445450D03*
X87599Y403950D03*
X76099Y414250D03*
X95399Y416350D03*
X89099Y426150D03*
X93499Y481550D03*
Y477050D03*
X93199Y449850D03*
X93500Y445300D03*
X52730Y406470D03*
X42299Y564150D03*
X62055Y561550D03*
X49555Y563550D03*
X75999Y556640D03*
X70800Y540300D03*
X77165Y514650D03*
X94499Y486550D03*
X60400Y616000D03*
X62500Y633300D03*
X34700Y623000D03*
X41367Y639102D03*
X53400Y630500D03*
X52333Y641295D03*
X72599Y578236D03*
X39999Y576550D03*
X61099Y603236D03*
X93599Y581236D03*
X92599Y606236D03*
X93100Y571640D03*
X66023Y638100D03*
X71800Y622700D03*
X76499Y637550D03*
X43500Y631500D03*
X55500Y618500D03*
X39499Y615550D03*
X28586Y600248D03*
X28519Y605048D03*
X44000Y728500D03*
X40000Y729000D03*
X47800Y692800D03*
X53210Y701486D03*
X61999Y661550D03*
X43499Y657550D03*
X40734Y802473D03*
X44500Y733000D03*
X40000D03*
X43999Y737550D03*
X39999Y738050D03*
X44499Y742050D03*
X39999D03*
X39899Y754850D03*
X39399Y768750D03*
X27199Y764950D03*
X28599Y775450D03*
X26399Y750850D03*
X14799Y751450D03*
X17299Y773950D03*
X79900Y791300D03*
X67999Y790400D03*
X53999Y791000D03*
X93299Y862050D03*
X26799Y874550D03*
X26099Y891650D03*
X76399Y820450D03*
X70100Y818900D03*
X93690Y887139D03*
X93900Y882400D03*
X94001Y856895D03*
X93808Y852063D03*
X93499Y892050D03*
X25699Y916150D03*
X25099Y942150D03*
X23899Y957950D03*
X93499Y897152D03*
X93000Y907165D03*
X77499Y921550D03*
X77002Y952079D03*
X76711Y948089D03*
X77499Y962152D03*
X83988Y934028D03*
X24799Y992250D03*
X33899Y1005950D03*
X65799Y994050D03*
X72799Y982950D03*
X86900Y981600D03*
X52499Y1013550D03*
X67000Y1011500D03*
X74999Y1126550D03*
X21500Y1122500D03*
Y1092500D03*
X17500D03*
X26500Y1064500D03*
X96000Y1107000D03*
X22500Y1183000D03*
Y1176500D03*
Y1170000D03*
Y1164500D03*
X18000Y1145500D03*
X17500Y1150500D03*
X22447Y1223247D03*
X23200Y1209300D03*
X21299Y1300250D03*
X21799Y1282750D03*
X22321Y1231121D03*
X18099Y1343550D03*
X96000Y1369000D03*
X96100Y1384650D03*
X77166Y1353400D03*
X93316Y1351000D03*
X77165Y1327335D03*
X95899Y1475350D03*
X76499Y1507050D03*
Y1498050D03*
Y1512050D03*
Y1503050D03*
X76999Y1528050D03*
Y1519050D03*
X38499Y1601050D03*
X83499Y1602050D03*
X92499Y1589050D03*
X86999D03*
X83499Y1594050D03*
Y1598050D03*
X74999Y1602050D03*
X78999D03*
X81499Y1589050D03*
X78999Y1593550D03*
X74999Y1598050D03*
Y1593550D03*
X78999Y1598050D03*
X90999Y1628550D03*
Y1624550D03*
X91121Y1632549D03*
X86299Y1632550D03*
X85999Y1628550D03*
Y1624550D03*
X42449Y1588600D03*
X63014Y1560986D03*
X60172Y1566828D03*
X15299Y1723450D03*
X15399Y1708350D03*
X14899Y1736250D03*
X15299Y1753250D03*
X84099Y1737150D03*
X83599Y1744750D03*
X77165Y1759550D03*
X93499D03*
X94336Y1773113D03*
X78529Y1788113D03*
X78099Y1827250D03*
X89499Y1843113D03*
X38600Y1880200D03*
X31400Y1885200D03*
X30400Y1849650D03*
X23999Y1857950D03*
X27199Y1874350D03*
X52999Y1871550D03*
X57499Y1871050D03*
X83499Y1841550D03*
X81499Y1847550D03*
X77999Y1832350D03*
X46499Y1850050D03*
X46999Y1832550D03*
X82999Y1887550D03*
X78999D03*
X57999Y1830050D03*
X90800Y1832500D03*
X36100Y1892200D03*
X58999Y1958050D03*
X82499Y1957050D03*
X73499D03*
X66499D03*
X92499Y1959050D03*
X36699Y1963300D03*
X28389Y1958362D03*
X26499Y1947050D03*
X47499Y1915050D03*
X62999Y1914550D03*
Y1926050D03*
X81499Y1915550D03*
X47499Y1930550D03*
X62499Y1939550D03*
X73499Y1945550D03*
X83999Y1945050D03*
X33573Y1928650D03*
X41597Y1912934D03*
X43999Y1924050D03*
X78999Y1891550D03*
X82999D03*
X78999Y1896050D03*
X78433Y1900010D03*
X78999Y1904050D03*
X83499Y1896050D03*
X83433Y1904010D03*
X83999Y1900050D03*
X39990Y1927445D03*
X79500Y1987500D03*
X61500D03*
X44500Y1987000D03*
X26500D03*
X55999Y1982550D03*
X44624Y1974886D03*
X26999Y1973550D03*
X96999Y49550D03*
X157299Y5150D03*
X107000Y6000D03*
X97800Y36000D03*
X96900Y40400D03*
X167499Y43550D03*
X116400Y56000D03*
X129100Y55900D03*
X127499Y65050D03*
X141999Y65550D03*
X156499Y66050D03*
X169300Y130300D03*
X178700Y129900D03*
X152999Y141050D03*
X123499Y149050D03*
X133999D03*
X142999Y141050D03*
X132999Y141550D03*
X176499Y140050D03*
X167499Y149550D03*
X144499Y149050D03*
X163499Y140050D03*
X160999Y149550D03*
X123499Y140050D03*
X129999Y78050D03*
X166999Y88050D03*
X166499Y83550D03*
Y79050D03*
X158499D03*
Y84050D03*
Y88550D03*
Y93550D03*
X166999Y92550D03*
Y97050D03*
X127999Y99550D03*
X165499Y106050D03*
X169999Y103050D03*
X114800Y68500D03*
X166999Y155550D03*
X177899Y199250D03*
X117500Y162300D03*
X124300Y167800D03*
X131799Y201950D03*
X142688Y218861D03*
X143110Y203861D03*
X171499Y153550D03*
X162177Y154550D03*
X97999Y199050D03*
X155999Y181050D03*
X135399Y277050D03*
X130799Y300250D03*
X158999Y259800D03*
X152808Y246341D03*
X166800Y240800D03*
X133000Y240500D03*
X157740Y273924D03*
X139399Y372350D03*
X167299Y369350D03*
X130099Y326150D03*
X134699Y356050D03*
X126099Y396150D03*
X152499Y395950D03*
X137500Y444600D03*
X137100Y436800D03*
X129400Y426900D03*
X132999Y475550D03*
X135999Y472550D03*
X135140Y478930D03*
X100500Y456700D03*
X99399Y437450D03*
X124899Y409050D03*
X133499Y445050D03*
X128999Y445550D03*
X130000Y452000D03*
X144999Y419550D03*
X97699Y477050D03*
Y481550D03*
X168500Y472000D03*
X149700Y471600D03*
X154100Y476500D03*
X164600Y476700D03*
X171300D03*
X97999Y445550D03*
X97699Y449850D03*
X161999Y426450D03*
X175000Y425000D03*
X156959Y426292D03*
X162000Y421250D03*
X171000Y414500D03*
X167200Y561000D03*
X147300Y526700D03*
X147590Y521500D03*
X151699Y524650D03*
X108599Y557236D03*
X154099Y529236D03*
X101500Y536500D03*
X139200Y484300D03*
X134499Y488050D03*
X135300Y524329D03*
X145649Y509550D03*
X136349Y509050D03*
X98999Y488050D03*
X168299Y503150D03*
X140499Y499050D03*
X153499Y502550D03*
X148999D03*
X136299Y499050D03*
X172199Y557108D03*
X157749Y562000D03*
X155999Y535775D03*
X156499Y548550D03*
X177999Y559300D03*
X134899Y538200D03*
X135300Y549500D03*
X108900Y587600D03*
X162500Y623400D03*
X140000Y587700D03*
X140499Y600550D03*
X152400Y643300D03*
X140499Y626050D03*
X143999Y605550D03*
X170799Y689150D03*
X171999Y672450D03*
X131099Y700450D03*
X139099Y707150D03*
X152124Y651868D03*
X159054Y665400D03*
X152499Y810550D03*
X110800Y772700D03*
X178899Y765250D03*
X172599Y774250D03*
X161999Y768050D03*
X166499Y841550D03*
X152499Y816050D03*
Y820550D03*
Y825050D03*
X156499Y876050D03*
Y870550D03*
X97499Y862050D03*
X106499Y834550D03*
X111299Y821050D03*
X172099Y877450D03*
X168499Y846713D03*
X173899Y846550D03*
X161999Y843550D03*
Y848050D03*
X156499Y846050D03*
X156999Y850050D03*
X158114Y883290D03*
X156499Y886950D03*
X155499Y891050D03*
Y896050D03*
X97700Y887400D03*
X97900Y882400D03*
X163999Y863050D03*
X159999D03*
X155999Y859050D03*
Y863050D03*
X97800Y851800D03*
X98001Y856950D03*
X97499Y892550D03*
X151999Y936550D03*
X152499Y931550D03*
X109500Y901100D03*
X153299Y943750D03*
X106500Y943000D03*
X105300Y960300D03*
X169299Y956350D03*
X156969Y917050D03*
X159459Y896616D03*
X163499Y896550D03*
X157499Y909050D03*
Y904550D03*
X171499Y965050D03*
X158800Y967500D03*
X164999Y965050D03*
X160999Y942550D03*
X159186Y946117D03*
X171000Y927000D03*
X151300Y1049300D03*
X171499Y998650D03*
X156499Y985950D03*
X149499Y997650D03*
X162499Y1023550D03*
X163499Y1035050D03*
X158300Y1015000D03*
X141234Y1029885D03*
X140864Y1044885D03*
X159499Y1044579D03*
X165600Y1057428D03*
X125999Y1087550D03*
X126999Y1143550D03*
X100999Y1099550D03*
X105000Y1100500D03*
X100999Y1095050D03*
X105006Y1095366D03*
X110999Y1130550D03*
X115200Y1130300D03*
X110999Y1126050D03*
Y1122050D03*
Y1118050D03*
X114999Y1126050D03*
Y1122050D03*
Y1118050D03*
X137900Y1103400D03*
X139100Y1097100D03*
X169299Y1067150D03*
X168099Y1083550D03*
X167999Y1092850D03*
X143200Y1116300D03*
X134500Y1108100D03*
X171599Y1139950D03*
X167499Y1118550D03*
X167999Y1130550D03*
X133200Y1132100D03*
X164999Y1075550D03*
X159055Y1070400D03*
X106999Y1114960D03*
X124249Y1108500D03*
X121245Y1120753D03*
X131491Y1128483D03*
X113500Y1134500D03*
X127800Y1163400D03*
X100499Y1226050D03*
X144149Y1226113D03*
Y1222113D03*
X148499D03*
Y1226113D03*
X99999Y1202550D03*
X173499Y1217050D03*
X158500Y1181000D03*
X145900Y1163200D03*
X163499Y1171650D03*
X151699Y1158550D03*
X144399Y1171150D03*
X150999Y1181150D03*
X141499Y1185550D03*
X151499Y1173050D03*
X121657Y1224604D03*
X120999Y1188050D03*
X111999D03*
X102999D03*
X128400Y1188600D03*
X115499Y1197550D03*
X117499Y1214050D03*
X121000Y1207000D03*
X148500Y1196000D03*
X100999Y1213550D03*
X127500Y1207500D03*
X127000Y1196000D03*
X144149Y1230113D03*
X148486D03*
X143900Y1262600D03*
X146300Y1277900D03*
X104999Y1231050D03*
X100999Y1231032D03*
X120999Y1228550D03*
X120499Y1264550D03*
X126499D03*
X123938Y1267623D03*
X103499Y1305050D03*
X117149Y1267550D03*
X164999Y1305550D03*
X175823Y1297070D03*
X175499Y1302113D03*
Y1306113D03*
Y1292550D03*
X113999Y1380550D03*
X115499Y1364550D03*
X145999Y1353050D03*
X167499Y1389050D03*
X105999Y1311050D03*
X148000Y1346500D03*
X116499Y1335050D03*
X176999Y1367550D03*
X123500Y1372000D03*
X171499Y1370550D03*
X112499Y1329050D03*
X123500Y1360300D03*
X136200Y1342600D03*
X153500Y1326700D03*
X129699Y1315605D03*
X120499Y1470550D03*
X156999Y1397750D03*
X143199Y1412050D03*
X163499Y1433350D03*
X166799Y1409350D03*
X178200Y1393400D03*
X176599Y1447450D03*
X172299Y1465850D03*
X165499Y1453550D03*
X157915Y1420460D03*
X140799Y1435460D03*
X97999Y1486550D03*
X166799Y1487450D03*
X176299Y1500150D03*
X159054Y1476200D03*
X121499Y1511050D03*
X108000Y1517000D03*
X124999Y1616050D03*
Y1620050D03*
Y1629050D03*
Y1633050D03*
X119999Y1629050D03*
X120100Y1633100D03*
X135400Y1624100D03*
X171999Y1658550D03*
X105749Y1712749D03*
X122499Y1668550D03*
Y1672550D03*
X126562Y1670613D03*
X118999Y1670550D03*
X121499Y1708050D03*
X168999Y1651050D03*
X143500Y1702900D03*
X151499Y1673550D03*
X144999Y1711050D03*
X172499Y1714050D03*
X167499Y1714113D03*
X162499D03*
X174800Y1670800D03*
X148100Y1683400D03*
X172999Y1775050D03*
X130499Y1730050D03*
X128000Y1735000D03*
X144499Y1729550D03*
X139500Y1730500D03*
X133000Y1734500D03*
X157500Y1797400D03*
X126599Y1789650D03*
X120299Y1796150D03*
X142144Y1801644D03*
X104417Y1791480D03*
X144499Y1745550D03*
X137999Y1747723D03*
X129999Y1747050D03*
X123499D03*
X117499Y1745050D03*
X109249Y1725800D03*
X177314Y1772050D03*
X158027Y1778300D03*
X166999Y1774550D03*
X158499Y1729050D03*
X170499Y1731050D03*
X165499Y1730613D03*
X172499Y1726613D03*
X167999D03*
X163499D03*
X97999Y1815050D03*
X104500Y1813400D03*
X173899Y1813250D03*
X177599Y1866750D03*
X168299Y1879850D03*
X168499Y1855550D03*
X127499Y1889050D03*
X126999Y1882550D03*
X111499Y1877550D03*
Y1882550D03*
X122999Y1883050D03*
X115999Y1882550D03*
X157999Y1840972D03*
X158000Y1825400D03*
X159054Y1881800D03*
X167200Y1868000D03*
X159054Y1855050D03*
X143491Y1856400D03*
X116499Y1877550D03*
X122999Y1889050D03*
X132700Y1972400D03*
X137900Y1972200D03*
X126500Y1972400D03*
X168899Y1960750D03*
X163599Y1892050D03*
X159173Y1935972D03*
X142499Y1905972D03*
X141499Y1895972D03*
X131100Y1908500D03*
X129600Y1912400D03*
X124433Y1908510D03*
X124999Y1912550D03*
X98433Y1940510D03*
X98999Y1944550D03*
X102433Y1940555D03*
X103433Y1944510D03*
X132700Y1978600D03*
X137900Y1978400D03*
X126600Y1978500D03*
X119999Y1978550D03*
X119499Y1972550D03*
X98000Y1987500D03*
X163500D03*
X146000D03*
X128500D03*
X115000Y1987000D03*
X189499Y39150D03*
X197999Y39900D03*
X193999D03*
X208499Y45650D03*
X199999Y46050D03*
X194499Y44050D03*
X246200Y65800D03*
X246000Y61300D03*
Y56500D03*
Y52100D03*
X245600Y43800D03*
X245500Y39100D03*
X247100Y47900D03*
X189499Y4550D03*
X206999Y5050D03*
X226499D03*
X241999D03*
X261499Y4550D03*
X225499Y52550D03*
Y46550D03*
Y63550D03*
Y58050D03*
X183499Y45550D03*
X192499Y57550D03*
X246000Y70800D03*
X244900Y149100D03*
X244499Y136550D03*
Y122050D03*
X208999Y92050D03*
X227022Y85278D03*
X229296Y81050D03*
X230811Y88226D03*
X224499Y92050D03*
X225499Y100050D03*
X188999Y88550D03*
X187024Y76235D03*
X191499Y74497D03*
X200999Y159050D03*
X201561Y164541D03*
X229099Y161350D03*
X206899Y171650D03*
X190199Y178650D03*
X232400Y220700D03*
X210999Y221550D03*
X191999D03*
X218499Y183050D03*
X227499Y192050D03*
X231999D03*
X227999Y187050D03*
X231999D03*
X227999Y182550D03*
X231999D03*
X227999Y178050D03*
X231999D03*
X191449Y152000D03*
X221799Y276150D03*
X249800Y248800D03*
X235399Y263350D03*
X201199Y266750D03*
X181299Y267350D03*
X217999Y250550D03*
X203499D03*
X185999D03*
X212578Y287448D03*
X212499Y296050D03*
X257000Y316214D03*
X212499Y307050D03*
X231400Y262800D03*
X236800Y283500D03*
X211999Y327550D03*
X187199Y359050D03*
X223799Y365350D03*
X209199Y365050D03*
X181599Y396250D03*
X217599Y396450D03*
X258999Y396650D03*
X253999Y370050D03*
X179999Y442550D03*
X179649Y438550D03*
X183999D03*
Y442550D03*
Y447050D03*
X179999D03*
X209999Y426150D03*
X237699Y426050D03*
X218499Y474850D03*
X251499Y446050D03*
X231999Y445550D03*
X251999Y462050D03*
X232499Y461550D03*
X209499Y412550D03*
X220000Y421000D03*
X232999Y414550D03*
X252499Y415050D03*
X207128Y440421D03*
X194999Y490050D03*
X190499Y487550D03*
X191199Y491550D03*
X179000Y535500D03*
X179499Y542550D03*
X244199Y483350D03*
X224299Y494650D03*
X242099Y511750D03*
X244999Y559550D03*
Y545050D03*
X220499Y560050D03*
Y545550D03*
X257499Y530050D03*
Y512550D03*
Y498050D03*
X205300Y508100D03*
X190499Y507513D03*
X215400Y516400D03*
X199800Y546100D03*
X187499Y531613D03*
Y536113D03*
X193499Y541113D03*
X188999D03*
X193499Y549613D03*
X188999D03*
Y545613D03*
X193999Y545550D03*
Y558050D03*
X200999Y565050D03*
X200417Y569815D03*
X257199Y640050D03*
X224999Y613450D03*
X256499Y609050D03*
Y591550D03*
Y577050D03*
X245000Y647000D03*
X244499Y632050D03*
X219999Y647050D03*
Y632550D03*
X207300Y639400D03*
X206499Y623550D03*
Y609050D03*
X181999Y641550D03*
Y624050D03*
Y609550D03*
X244999Y577050D03*
X220499Y577550D03*
X258200Y722300D03*
X216999Y713050D03*
X199199Y659150D03*
X234200Y668300D03*
X226399Y677550D03*
X212999Y677350D03*
X190399Y689050D03*
X182599Y688350D03*
X246500Y663300D03*
X218800Y668700D03*
X213299Y693800D03*
X212499Y701550D03*
X239300Y669600D03*
X234500Y690652D03*
X212499Y736050D03*
X247000Y768500D03*
X244700Y743100D03*
X224099Y770250D03*
X209500Y759000D03*
X208799Y766750D03*
X214799Y774750D03*
X245599Y773450D03*
X234299Y773750D03*
X247099Y795050D03*
X227199D03*
X197099D03*
X254699Y807650D03*
X233799Y806350D03*
X208299Y805350D03*
X198199Y805950D03*
X190699Y778350D03*
X217500Y812500D03*
X215999Y887550D03*
X220499D03*
X215499Y883550D03*
X204496Y846111D03*
X204649Y838050D03*
X208999D03*
X209000Y846113D03*
X204649Y842113D03*
X208986D03*
X244099Y857450D03*
X245199Y878050D03*
X232399Y886550D03*
X252899Y886350D03*
X252399Y838250D03*
X245399Y823550D03*
X217300Y816800D03*
X198499Y884113D03*
X232500Y834500D03*
X179999Y826050D03*
X179499Y820550D03*
X191936Y825184D03*
X199500Y819132D03*
X199999Y971050D03*
X245399Y907450D03*
X243899Y923650D03*
X242199Y938750D03*
X256199Y916250D03*
X254899Y929250D03*
X253499Y938050D03*
X252499Y948850D03*
X244199Y973250D03*
X225299Y957650D03*
X213999Y958650D03*
X206699Y953050D03*
X203999Y943350D03*
X204699Y929450D03*
X205999Y978250D03*
X256499Y967050D03*
X233499Y966050D03*
X216999Y967550D03*
X203000Y918000D03*
X237499Y900050D03*
X178999Y961550D03*
X227500Y943500D03*
X219499Y939613D03*
Y948613D03*
Y943813D03*
X214999Y939613D03*
Y944113D03*
Y948613D03*
X219499Y926613D03*
X214999D03*
X193549Y962550D03*
X194800Y925500D03*
X188499Y982050D03*
X254499Y984550D03*
X245899Y995250D03*
X232299Y981950D03*
X206299Y990250D03*
X207299Y1008150D03*
X202100Y1028100D03*
X253999Y1052050D03*
X253499Y1038550D03*
X232499Y1038050D03*
X216499Y1053050D03*
X215999Y1039550D03*
X258999Y1011550D03*
X233999Y1012550D03*
Y997050D03*
X217999Y1012050D03*
X217499Y998550D03*
Y981050D03*
X250000Y1128000D03*
X233500Y1113100D03*
X244400Y1110200D03*
X255999Y1112150D03*
X199499Y1093850D03*
X209900Y1093600D03*
X249499Y1104150D03*
X260349Y1139200D03*
X212600Y1089961D03*
X210999Y1100550D03*
X227028Y1071148D03*
X223700Y1078500D03*
X214499Y1154250D03*
X223099Y1182750D03*
X210199Y1173450D03*
X204199Y1163850D03*
X208199Y1145850D03*
X180400Y1202800D03*
X201600Y1205900D03*
X220999Y1224350D03*
X242199Y1210050D03*
X242599Y1198350D03*
X232599Y1195750D03*
X247899Y1208650D03*
X251999Y1184550D03*
X212499Y1212550D03*
X181700Y1219900D03*
X212499Y1184550D03*
X196499Y1224550D03*
Y1215550D03*
Y1196550D03*
X250800Y1166700D03*
X259999Y1152992D03*
X259499Y1161550D03*
X202199Y1276850D03*
X202899Y1291450D03*
X179500Y1262000D03*
X179800Y1244100D03*
X196399Y1236650D03*
X221599Y1237250D03*
X222299Y1251850D03*
X229899Y1250550D03*
X216300Y1274800D03*
X234299Y1232650D03*
X261199Y1227950D03*
X250900Y1248500D03*
X242900Y1263000D03*
X232799Y1276150D03*
X254899Y1289950D03*
X241399Y1303250D03*
X211499Y1267050D03*
Y1258050D03*
Y1239050D03*
X195499Y1279050D03*
Y1270050D03*
Y1251050D03*
X179999Y1306050D03*
Y1301550D03*
Y1292550D03*
Y1296613D03*
X186000Y1382400D03*
X216499Y1377550D03*
X239099Y1314150D03*
X252399Y1326350D03*
X219099Y1325950D03*
X226599Y1340250D03*
X207699Y1337950D03*
X195500Y1352500D03*
X213199Y1350050D03*
X227399Y1363050D03*
X234300Y1375700D03*
X217499Y1387450D03*
X249800Y1388400D03*
X245999Y1358050D03*
X246499Y1370050D03*
X245999Y1339050D03*
X208049Y1385550D03*
X190499Y1367550D03*
X197999Y1359050D03*
X208999Y1366550D03*
X258999Y1396950D03*
X230599Y1400250D03*
X217999Y1408850D03*
X204699Y1418350D03*
X203199Y1393250D03*
X201000Y1408500D03*
X180599Y1424050D03*
X180000Y1439500D03*
X204999Y1472650D03*
X250199Y1473550D03*
X226300Y1447800D03*
X230899Y1437350D03*
X238899Y1453750D03*
X259299Y1438750D03*
X227999Y1421550D03*
X212400Y1433700D03*
X194200Y1457900D03*
X244999Y1412550D03*
X245499Y1424550D03*
X259000Y1534000D03*
X217500Y1522500D03*
X260500Y1541000D03*
X212000Y1544500D03*
X181500Y1479000D03*
X202399Y1500750D03*
X208999Y1491250D03*
X247500Y1499000D03*
X248000Y1482000D03*
X212899Y1535550D03*
X230999D03*
X213399Y1500300D03*
X236999Y1535550D03*
X211914Y1504015D03*
X211500Y1512000D03*
X260999Y1503550D03*
X223501Y1487433D03*
X242700Y1499400D03*
X253500Y1586500D03*
X180299Y1626550D03*
X180000Y1619600D03*
X195700Y1619100D03*
X195600Y1623700D03*
X180299Y1634550D03*
X179733Y1630590D03*
X246200Y1617600D03*
X239400Y1624300D03*
X218000Y1614300D03*
X209200Y1624000D03*
X228999Y1637550D03*
X211999Y1568550D03*
X238300Y1575100D03*
X231499Y1575050D03*
X224499D03*
X217999Y1574550D03*
X211999D03*
X195000Y1640613D03*
X258700Y1645100D03*
X237400Y1663800D03*
X230600Y1670500D03*
X197600Y1694900D03*
X204400Y1688200D03*
X216601Y1684350D03*
X226800Y1684200D03*
X220100Y1691700D03*
X209901Y1691850D03*
X212000Y1701300D03*
X201801Y1701450D03*
X195001Y1708150D03*
X205200Y1708000D03*
X180701Y1716050D03*
X195500Y1717000D03*
X200600Y1663600D03*
X199900Y1670600D03*
X213000Y1672500D03*
X181900Y1675300D03*
X255699Y1722550D03*
X222700Y1710100D03*
X242999Y1658050D03*
X193499Y1674050D03*
X253999Y1676550D03*
X235499Y1697050D03*
X256499Y1710050D03*
X184000Y1695000D03*
X197500Y1650000D03*
X192800Y1658800D03*
X201499Y1784750D03*
X180000Y1731000D03*
X179701Y1724550D03*
X195000Y1725500D03*
X249199Y1743150D03*
X222499Y1743850D03*
X259499Y1760650D03*
X221499Y1760950D03*
X199699Y1761450D03*
X220799Y1791550D03*
X252199Y1793050D03*
X238699Y1801850D03*
X205199Y1801950D03*
X182299Y1801350D03*
X206900Y1726700D03*
X185999Y1746050D03*
X237999Y1730550D03*
X244999Y1755050D03*
X192999Y1771550D03*
X253899Y1813250D03*
X215299Y1813950D03*
X255999Y1855950D03*
X204399Y1855450D03*
X206999Y1867550D03*
X241199Y1867150D03*
X244700Y1878700D03*
X224800Y1867000D03*
X212399Y1885850D03*
X199599Y1879850D03*
X181099Y1885850D03*
X261499Y1825050D03*
X209999D03*
X192100Y1813500D03*
X228999Y1856050D03*
X240100Y1875000D03*
X226999Y1941050D03*
X218499Y1897050D03*
X241255Y1896055D03*
X205499Y1968650D03*
X183999Y1968150D03*
X190399Y1961250D03*
X207199Y1892850D03*
X191599Y1891550D03*
X238999Y1970550D03*
X232999Y1971050D03*
X227499D03*
X221300Y1971200D03*
X245249Y1896283D03*
X240900Y1979000D03*
X225199Y1978750D03*
X209699D03*
X188199Y1978250D03*
X254500Y1987500D03*
X236500D03*
X216999Y1987550D03*
X199000Y1987500D03*
X183000D03*
X199600Y1974900D03*
X289499Y39050D03*
X286603Y34928D03*
X286499Y43613D03*
X278999Y5050D03*
X292999Y4550D03*
X310499Y5050D03*
X329999D03*
X306999Y55450D03*
X311299D03*
X315799Y55350D03*
X290999Y67550D03*
X300700Y39400D03*
X304500Y44500D03*
X305100Y39700D03*
X294100Y28000D03*
X308900Y41000D03*
X308800Y46400D03*
X305999Y141050D03*
X306100Y126500D03*
X332200Y94200D03*
X283599Y106250D03*
X274700Y131500D03*
X280999Y120050D03*
X287100Y86363D03*
X289999Y72550D03*
X288499Y76550D03*
X289499Y80550D03*
X328500Y71500D03*
X308499Y72550D03*
X303999Y74050D03*
X307999Y78550D03*
X307300Y113300D03*
X295500Y101900D03*
X343799Y204550D03*
X321799Y173950D03*
X343399Y161350D03*
X307199Y205550D03*
X317499Y192950D03*
X331499Y193250D03*
X262699Y208550D03*
X262299Y164050D03*
X280999Y152050D03*
X343999Y190050D03*
X337999Y219050D03*
X310499Y216550D03*
X290999Y216050D03*
X271999D03*
X325499Y249450D03*
X313199Y270350D03*
X297999Y245050D03*
X283499D03*
X265999D03*
X343499Y253550D03*
X337499Y282550D03*
X313000Y313900D03*
X316999Y312576D03*
X279998Y308614D03*
Y304114D03*
Y299614D03*
Y295114D03*
X267498Y310114D03*
Y305114D03*
Y300114D03*
Y295114D03*
X299000Y340500D03*
X305998Y352114D03*
X293998Y361114D03*
Y356614D03*
Y352114D03*
X289998Y361114D03*
Y356614D03*
Y352114D03*
X276299Y376050D03*
X299899Y376650D03*
X328799Y372350D03*
X339399Y358050D03*
X289399Y395750D03*
X310999Y396250D03*
X338399Y395650D03*
X321748Y343299D03*
X277799Y338599D03*
X265499Y322050D03*
X312912Y345936D03*
X302000Y373000D03*
X319102Y346300D03*
X324644Y367083D03*
X320500Y373000D03*
X266699Y425050D03*
X336099Y417550D03*
X322099Y426850D03*
X338899Y433850D03*
X300899Y431850D03*
X328599Y442250D03*
X291599Y446150D03*
X266199Y472350D03*
X327900Y463200D03*
X306100Y462000D03*
X286999Y462050D03*
X272499Y445050D03*
X272999Y461050D03*
X269999Y415050D03*
X284499D03*
X303999Y415550D03*
X324999Y414550D03*
X277999Y545350D03*
X329999Y510450D03*
X298599Y501250D03*
X309399Y513450D03*
X321999Y533150D03*
X297599Y519350D03*
X340799Y512050D03*
X341399Y535850D03*
Y558950D03*
X331999Y555050D03*
Y540550D03*
X307499Y555550D03*
Y541050D03*
X281999Y529550D03*
Y512050D03*
Y497550D03*
X321999Y550550D03*
X297499Y551050D03*
X333499Y483050D03*
X312499Y484050D03*
X292999Y483550D03*
X321299Y565250D03*
X296199Y568550D03*
X320799Y582050D03*
X340299Y586550D03*
X342199Y613050D03*
X328599Y602450D03*
X302899Y607950D03*
X328499Y635650D03*
X317999Y627850D03*
X342099Y646350D03*
X280999Y608550D03*
Y591050D03*
Y576550D03*
X331999Y572550D03*
X307499Y573050D03*
X331999Y646550D03*
X307499Y647050D03*
X293999Y630550D03*
Y616050D03*
X269499Y631050D03*
Y616550D03*
X341899Y664950D03*
X342599Y678850D03*
X341399Y715050D03*
X330799Y712450D03*
X324599Y696150D03*
X297699Y681850D03*
X296399Y716950D03*
X308899Y705150D03*
X298399Y703450D03*
X331999Y678550D03*
Y661050D03*
X307499Y679050D03*
Y661550D03*
X293999Y648050D03*
X269499Y648550D03*
X283999Y708550D03*
X268499Y716550D03*
Y711550D03*
Y701550D03*
Y706550D03*
X280999Y717550D03*
X280433Y713590D03*
X280999Y701550D03*
Y705550D03*
X301099Y750750D03*
X294999Y767050D03*
X290999D03*
X294999Y762550D03*
Y758050D03*
X290999Y762550D03*
Y758050D03*
X306999D03*
X338099Y811650D03*
X307999Y803150D03*
X307899Y794550D03*
X287799Y794850D03*
X268099Y795450D03*
X275299Y806350D03*
X315000Y754500D03*
X330249Y750050D03*
X318499Y752050D03*
X304000Y785500D03*
X324499Y753050D03*
X323500Y772300D03*
X325000Y785500D03*
X338599Y821650D03*
X318999Y814350D03*
X338599Y840450D03*
X325599Y823950D03*
X283599Y857450D03*
X293899Y843850D03*
X304899Y856150D03*
X315199Y869450D03*
X323099Y885050D03*
X340099Y887350D03*
X330299Y871850D03*
X323799Y859850D03*
X313499Y847850D03*
X300199Y835250D03*
X288899Y820550D03*
X264999Y858450D03*
X280999Y843050D03*
Y827550D03*
X264999Y842550D03*
X264499Y829050D03*
X297499Y884050D03*
Y868550D03*
X281499Y883550D03*
X280999Y870050D03*
X301499Y927050D03*
X265799Y901850D03*
X274299Y912950D03*
X310699Y943550D03*
X323499Y956950D03*
X329799Y970650D03*
X331099Y923650D03*
X322099Y913650D03*
X302499Y899050D03*
X321099Y899650D03*
X338399Y901050D03*
X340099Y910350D03*
X340399Y931250D03*
X340099Y952850D03*
X328099Y937250D03*
X315199Y925950D03*
X302199Y914650D03*
X287299Y901050D03*
X269599Y923950D03*
X267199Y935350D03*
X264799Y946850D03*
X263299Y959350D03*
X281099Y943550D03*
X278799Y956150D03*
X277599Y975250D03*
X290099Y948650D03*
X289399Y963350D03*
X288099Y971250D03*
X299399Y965950D03*
X298099Y977250D03*
X307999Y970650D03*
X272999Y965550D03*
X333099Y983450D03*
X285399Y982950D03*
X294699Y989550D03*
X306699Y981250D03*
X304399Y997550D03*
X320999Y997250D03*
X331299Y1017150D03*
X331599Y1028750D03*
X329599Y1040750D03*
X321299Y1012450D03*
Y1024750D03*
X318299Y1038750D03*
X329599Y1057050D03*
X317699Y1054650D03*
X299999Y1052350D03*
X289699Y1021750D03*
X298399Y1008150D03*
X287099Y1000150D03*
X306399Y1020750D03*
X303699Y1038050D03*
X304699Y1057050D03*
X287099Y1035050D03*
X275099Y1024750D03*
X262499Y995850D03*
X269999Y1052550D03*
Y1037050D03*
X274999Y1012050D03*
Y996550D03*
X272999Y981050D03*
X339599Y1081550D03*
X319999Y1066950D03*
X274900Y1115600D03*
X262499Y1129150D03*
X272999Y1102850D03*
X312299Y1093550D03*
X276299Y1134550D03*
X290699Y1122650D03*
X329299Y1098550D03*
X326599Y1112350D03*
X307999Y1142050D03*
X299499Y1113550D03*
Y1098050D03*
X283499Y1113050D03*
X282999Y1099550D03*
X332999Y1138550D03*
Y1123050D03*
X317999Y1137550D03*
X316499Y1124550D03*
X283299Y1144850D03*
X323999Y1153250D03*
X304499Y1156650D03*
X313499Y1170150D03*
X291399Y1174150D03*
X300699Y1185150D03*
X279799Y1191750D03*
X286599Y1203750D03*
X315408Y1202663D03*
X329799Y1182750D03*
X311999Y1213850D03*
X300699Y1227350D03*
X272999Y1214150D03*
X326649Y1218850D03*
X328999Y1200550D03*
X272499Y1153050D03*
X268499D03*
X263999D03*
X271999Y1161550D03*
X267999D03*
X263499D03*
X333349Y1307000D03*
X310299Y1240050D03*
X264800Y1261300D03*
X283799Y1249250D03*
X304699Y1265850D03*
X312499Y1280350D03*
X300499Y1305350D03*
X274299Y1276450D03*
X295399Y1292950D03*
X281099Y1302850D03*
X333349Y1288900D03*
Y1270500D03*
X327999Y1255050D03*
X326649Y1227850D03*
X333349Y1332800D03*
X311500Y1316300D03*
X264799Y1313850D03*
X286799Y1326450D03*
X297899Y1336150D03*
X298099Y1357250D03*
X265299Y1339650D03*
X263699Y1359550D03*
X301699Y1377950D03*
X278799Y1386250D03*
X265499Y1376950D03*
X343599Y1360050D03*
X344399Y1338150D03*
X313600Y1391300D03*
X312900Y1366900D03*
X333349Y1363500D03*
X311900Y1344900D03*
X286499Y1364050D03*
Y1345050D03*
X301699Y1395750D03*
X268499Y1453550D03*
X278000Y1422000D03*
X270599Y1408550D03*
X303499Y1411250D03*
X300899Y1433350D03*
X286600Y1449700D03*
X304699Y1457550D03*
X344099Y1449550D03*
Y1421150D03*
Y1393750D03*
X313600Y1442700D03*
X312800Y1467400D03*
X333349Y1429500D03*
X312100Y1420700D03*
X285499Y1418550D03*
Y1427550D03*
Y1399550D03*
X333349Y1393100D03*
X304499Y1549550D03*
X343699Y1475950D03*
X333349Y1481900D03*
X332500Y1519700D03*
X296599Y1497150D03*
X312000Y1514600D03*
X286700Y1516100D03*
X317499Y1549050D03*
X279500Y1521000D03*
X267349Y1518150D03*
Y1522550D03*
X266999Y1512550D03*
X267349Y1527172D03*
X279499Y1510550D03*
Y1515050D03*
X279075Y1525957D03*
X278567Y1529925D03*
X305998Y1569114D03*
X293998Y1578114D03*
Y1573614D03*
Y1569114D03*
X289998Y1578114D03*
Y1573614D03*
Y1569114D03*
X307000Y1619600D03*
X344500Y1583600D03*
X337199Y1636350D03*
X278499Y1621550D03*
X265700Y1635100D03*
X328600Y1566100D03*
X304000Y1597000D03*
X323000Y1582600D03*
X324500Y1597000D03*
X268499Y1706550D03*
X289000Y1641800D03*
X320299Y1642950D03*
X316799Y1657450D03*
X302399Y1662950D03*
X284300Y1676900D03*
X334399Y1691650D03*
X329999Y1716950D03*
X291099Y1707450D03*
X335767Y1662735D03*
X318499Y1675550D03*
X299999Y1696050D03*
X270999Y1660550D03*
X273499Y1694050D03*
X280499Y1718550D03*
X320999Y1706050D03*
X303999Y1722050D03*
X343899Y1752650D03*
X297099Y1733850D03*
X270599Y1748950D03*
X290699Y1760750D03*
X286599Y1791850D03*
X327299D03*
X322299Y1802150D03*
X303999Y1800850D03*
X270599Y1801450D03*
X263499Y1734550D03*
X285499Y1742550D03*
X321999Y1733050D03*
X303499Y1753550D03*
X321499Y1772550D03*
X334999Y1797050D03*
X297499D03*
X326301Y1766030D03*
X315499Y1812250D03*
X284299Y1811150D03*
X270299Y1867250D03*
X337499Y1855950D03*
X316999D03*
X298999D03*
X308099Y1880550D03*
X295299Y1870250D03*
X313599Y1889250D03*
Y1870250D03*
X326399Y1876250D03*
X336799Y1888950D03*
Y1869950D03*
X283999Y1856050D03*
X278999Y1950550D03*
X306199Y1937010D03*
X306999Y1932550D03*
X302499D03*
X298499D03*
X293999Y1933050D03*
X306000Y1961500D03*
X305500Y1965500D03*
X293999Y1971050D03*
Y1966550D03*
Y1962050D03*
X289499Y1961550D03*
Y1966550D03*
Y1971050D03*
X314099Y1901250D03*
X326899Y1907250D03*
X326399Y1895250D03*
X335799Y1916450D03*
X336799Y1897950D03*
X305999Y1913050D03*
X302499Y1922050D03*
X296858Y1956228D03*
X335520Y1953650D03*
X319500Y1954500D03*
X329500Y1956500D03*
X323999Y1938550D03*
X281999Y1918550D03*
Y1923550D03*
Y1928550D03*
X266999Y1915550D03*
Y1920050D03*
Y1924550D03*
Y1929050D03*
Y1933550D03*
X325500Y1971500D03*
X330000Y1962500D03*
X326799Y1977050D03*
X329999Y1987550D03*
X311500Y1987500D03*
X291499Y1987550D03*
X272000Y1987500D03*
X305691Y1976200D03*
X409999Y54050D03*
X381499Y65550D03*
X376999D03*
X371999Y15550D03*
X376499D03*
X380999D03*
X369999Y23550D03*
Y19050D03*
X382499Y20050D03*
X416999Y25050D03*
X417499Y46550D03*
X416999Y63550D03*
X345499Y5050D03*
X364999Y4550D03*
X382499Y5050D03*
X395999Y5550D03*
X413499Y6050D03*
X404499Y39300D03*
X359000Y47500D03*
X361616Y58933D03*
X402999Y46550D03*
X381500Y46000D03*
X377500Y49000D03*
X381499Y70050D03*
X376999D03*
X381299Y136750D03*
X389599Y90950D03*
X400499Y134050D03*
Y119550D03*
X363999Y136050D03*
X417499Y79050D03*
Y93550D03*
Y108050D03*
Y125550D03*
X416999Y145050D03*
X360999Y113050D03*
X356499D03*
X351999D03*
X347499D03*
X360999Y100550D03*
X355999D03*
X350999D03*
X345999D03*
X387599Y220150D03*
X385999Y207250D03*
X354099Y175350D03*
X389299Y161650D03*
X400499Y151550D03*
X363999Y153550D03*
X369999Y219050D03*
X382499Y190550D03*
X355499Y219050D03*
X362999Y190050D03*
X416999Y164050D03*
X417999Y185050D03*
X423799Y259750D03*
X383299Y310250D03*
X386899Y299250D03*
X359399Y307250D03*
X347399Y301950D03*
X355999Y242750D03*
X347699Y269050D03*
X382999Y276650D03*
X412999Y307550D03*
Y290050D03*
Y275550D03*
X369499Y282550D03*
X381999Y254050D03*
X354999Y282550D03*
X362499Y253550D03*
X411300Y328000D03*
X354099Y373050D03*
X368299Y386350D03*
X357999Y359050D03*
X380599Y381050D03*
X386599Y348450D03*
X394899Y357750D03*
X422499Y348150D03*
X422199Y363350D03*
X420199Y391350D03*
X419599Y458550D03*
X426599Y415350D03*
X415099Y422550D03*
X410799Y431150D03*
X354699Y426650D03*
X356399Y451750D03*
X351399Y470750D03*
X358399Y498650D03*
X357399Y521250D03*
Y530550D03*
Y543850D03*
X357999Y559450D03*
X415999Y518550D03*
X420199Y638550D03*
X427499Y624550D03*
X359399Y576050D03*
Y599650D03*
X360399Y615550D03*
X359699Y627550D03*
X345399Y698950D03*
X358899Y657150D03*
X359399Y669450D03*
X359199Y690650D03*
X357699Y707750D03*
X353999Y787750D03*
X347699Y773450D03*
X355999Y752850D03*
X424999Y766550D03*
X422999Y785050D03*
Y799550D03*
X418799Y896050D03*
Y877050D03*
X422499Y855550D03*
Y836550D03*
X422999Y817050D03*
X374500Y973500D03*
X375000Y939000D03*
Y1034000D03*
X424299Y1034050D03*
X423299Y1013050D03*
Y994050D03*
X373500Y1089500D03*
X419999Y1115550D03*
X409499Y1102550D03*
X416099Y1183550D03*
X415499Y1176050D03*
Y1161550D03*
X419499Y1219550D03*
X377499Y1210050D03*
Y1201050D03*
Y1182050D03*
X420099Y1241550D03*
X419499Y1234050D03*
X376599Y1293950D03*
X376499Y1264550D03*
Y1255550D03*
Y1236550D03*
X424999Y1278550D03*
X425499Y1290550D03*
X424999Y1259550D03*
X416699Y1342650D03*
X416199Y1367550D03*
X375599Y1323350D03*
X374499Y1375550D03*
Y1366550D03*
Y1347550D03*
X423299Y1430350D03*
X426799Y1416050D03*
X422299Y1394950D03*
X425799Y1447950D03*
X427099Y1469150D03*
X376299Y1437650D03*
X373099Y1456550D03*
X373499Y1430050D03*
Y1421050D03*
Y1402050D03*
X414799Y1532350D03*
X424299Y1541350D03*
X374099Y1554550D03*
X374799Y1491250D03*
X415999Y1603250D03*
X416199Y1625250D03*
X425499Y1635050D03*
X418299Y1561250D03*
X351899Y1570850D03*
X350600Y1610900D03*
X349099Y1634550D03*
X376099Y1572850D03*
X375099Y1608250D03*
X377700Y1629000D03*
X414799Y1653750D03*
X414399Y1678350D03*
X414499Y1707250D03*
X374999Y1656750D03*
X377099Y1696350D03*
X380099Y1709650D03*
X351099Y1691150D03*
X352000Y1700400D03*
X427499Y1662050D03*
X417799Y1790850D03*
X387899Y1802850D03*
X359499Y1736850D03*
X376799Y1734050D03*
X393499Y1759550D03*
X376499Y1775550D03*
X357999Y1796050D03*
X410757Y1772872D03*
X393999Y1784550D03*
X422999Y1778550D03*
X414499Y1810450D03*
X355699Y1810750D03*
X426499Y1855450D03*
X406999Y1855950D03*
X391499D03*
X369499D03*
X351999Y1855450D03*
X359999Y1878550D03*
X421399Y1888050D03*
X369799Y1880050D03*
X389499Y1885050D03*
X348999Y1879050D03*
X406499Y1874050D03*
X367299Y1956950D03*
X358999Y1925050D03*
X359999Y1897550D03*
Y1906550D03*
X420399Y1962550D03*
Y1934550D03*
Y1953550D03*
X421399Y1916050D03*
Y1907050D03*
X347699Y1972250D03*
X367999Y1940250D03*
X369199Y1919750D03*
X369999Y1901950D03*
X388499Y1959550D03*
Y1950550D03*
Y1932950D03*
X389499Y1913050D03*
Y1904050D03*
X349499Y1910050D03*
X348499Y1956550D03*
X347999Y1944550D03*
Y1925550D03*
X348999Y1898050D03*
X406999Y1905050D03*
X405999Y1951550D03*
X405499Y1939550D03*
Y1920550D03*
X406499Y1893050D03*
X385099Y1975950D03*
X420799Y1977250D03*
X399299Y1976750D03*
X367299Y1972950D03*
X420500Y1987000D03*
X403500D03*
X364999Y1987050D03*
X382499Y1987550D03*
X345499D03*
X436499Y50350D03*
Y31350D03*
X466799Y64750D03*
X465799Y43750D03*
Y24750D03*
X499999Y64050D03*
X500499Y47050D03*
X499999Y25550D03*
X432999Y6050D03*
X448499D03*
X467999Y5550D03*
X485499Y6050D03*
X498999D03*
X437499Y71350D03*
X442799Y142450D03*
X441799Y121450D03*
Y102450D03*
X471399Y124550D03*
X470399Y103550D03*
Y84550D03*
X473099Y141050D03*
X499999Y145550D03*
X500499Y126050D03*
Y108550D03*
Y79550D03*
Y94050D03*
X502899Y217150D03*
X504199Y193250D03*
X472999Y214550D03*
X483599Y179350D03*
X446799Y205650D03*
X445799Y184650D03*
Y165650D03*
X474099Y181050D03*
X473099Y160050D03*
X449999Y217050D03*
X430499D03*
X499999Y164550D03*
X466399Y304950D03*
X479299Y297250D03*
X437499Y307050D03*
Y289550D03*
Y275050D03*
X444499Y283050D03*
X463999Y283550D03*
X481499D03*
X495999D03*
X448999Y255550D03*
X469999Y254550D03*
X508499Y255050D03*
X488999Y254550D03*
X438999Y381550D03*
X458499Y382050D03*
X484900Y394700D03*
X485000Y373200D03*
X509999Y382550D03*
X443499Y354050D03*
X464499Y353050D03*
X502999Y353550D03*
X483499Y353050D03*
X498399Y470050D03*
X503699Y419250D03*
X472499Y458050D03*
X468799Y414250D03*
X443199Y440850D03*
X440099Y459250D03*
X431099Y479350D03*
X450300Y404200D03*
X490499Y464050D03*
X490999Y444550D03*
Y427050D03*
Y412550D03*
X454499Y472550D03*
X454999Y438550D03*
X454499Y458050D03*
X453999Y417550D03*
X430099Y551450D03*
X485299Y534550D03*
X508699Y498950D03*
X471499Y493950D03*
X452499Y565050D03*
X456499Y518050D03*
X435499Y519050D03*
X491499Y504050D03*
X490499Y483050D03*
X453999Y509550D03*
X454499Y490050D03*
X503379Y621150D03*
X504499Y598050D03*
Y580550D03*
Y566050D03*
X479999Y598550D03*
Y581050D03*
Y566550D03*
X509999Y640550D03*
X452499Y597050D03*
Y579550D03*
X427999Y597550D03*
Y580050D03*
Y565550D03*
X506599Y711650D03*
X487299Y716950D03*
X451099Y711650D03*
X450399Y672750D03*
X444799Y687350D03*
X509999Y672550D03*
Y655050D03*
X488499Y691050D03*
Y673550D03*
Y659050D03*
X463999Y691550D03*
Y674050D03*
Y659550D03*
X467699Y772750D03*
X468699Y788350D03*
X472999Y736550D03*
X489599Y752450D03*
X490299Y734550D03*
X453399Y807950D03*
X452099Y781450D03*
Y762450D03*
X435299Y795150D03*
Y777650D03*
Y763150D03*
X437299Y744650D03*
X495999Y795050D03*
X475699Y880450D03*
X479599Y847550D03*
X462999Y884050D03*
Y865050D03*
X453399Y826950D03*
X434799Y833650D03*
Y814650D03*
X464499Y896050D03*
X493499Y884050D03*
Y865050D03*
X493999Y845550D03*
Y813550D03*
Y828050D03*
X506899Y919950D03*
Y900950D03*
X443599Y945650D03*
X442599Y924650D03*
Y905650D03*
X486799Y941050D03*
X485799Y920050D03*
Y901050D03*
X461999Y966050D03*
X462499Y946550D03*
Y914550D03*
Y929050D03*
X494099Y1017350D03*
X493099Y996350D03*
X462499Y1043850D03*
X461999Y985050D03*
X478599Y1075450D03*
X474499Y1115050D03*
X491999Y1115550D03*
X454999D03*
X439499D03*
X501499Y1102550D03*
X463999Y1102050D03*
X481499Y1102550D03*
X444499D03*
X428999D03*
X436999Y1142550D03*
Y1128050D03*
X504399Y1132250D03*
X473099Y1144550D03*
X453499Y1140550D03*
X484499Y1085850D03*
X483499Y1064850D03*
X433599Y1085550D03*
X432599Y1064550D03*
X463499Y1083850D03*
X462499Y1062850D03*
X437599Y1150050D03*
X487099Y1218050D03*
X486499Y1210550D03*
Y1196050D03*
X443199Y1224250D03*
X507199Y1224350D03*
X506599Y1202350D03*
Y1216850D03*
X505399Y1153250D03*
X474099Y1165550D03*
X454499Y1161550D03*
X443799Y1274250D03*
Y1246250D03*
Y1265250D03*
X443199Y1238750D03*
X507199Y1252350D03*
Y1243350D03*
X465499Y1284550D03*
Y1293550D03*
Y1265550D03*
X498299Y1323350D03*
X468999Y1323950D03*
X428499Y1325350D03*
X508599Y1370550D03*
X444899Y1377950D03*
X434499Y1360250D03*
X448099Y1341250D03*
X473999Y1342450D03*
X485599Y1367550D03*
X468699Y1362850D03*
X466699Y1378150D03*
X498899Y1386450D03*
X499199Y1350550D03*
X459699Y1468050D03*
X464199Y1401450D03*
X459999Y1424050D03*
X498899Y1408350D03*
X500899Y1434350D03*
X505899Y1466250D03*
X482599Y1449950D03*
X456399Y1445950D03*
X445099Y1464250D03*
X478299Y1464850D03*
X481499Y1417050D03*
Y1402550D03*
X441499Y1431550D03*
Y1414050D03*
Y1399550D03*
X496300Y1492000D03*
X499699Y1538950D03*
X466999Y1530650D03*
X488299Y1531050D03*
X461399Y1541650D03*
X474299Y1544750D03*
X452199Y1550650D03*
X444299Y1532650D03*
X439599Y1552150D03*
X465999Y1603450D03*
X487099Y1606250D03*
X449199Y1579050D03*
X443799Y1612250D03*
X460199Y1632850D03*
X484999Y1636550D03*
X501399Y1634550D03*
X508199Y1610450D03*
X510100Y1579800D03*
X472299Y1572050D03*
X502199Y1566250D03*
X472499Y1620550D03*
Y1611550D03*
X484200Y1579900D03*
X432499Y1617550D03*
X434500Y1579500D03*
X431999Y1605550D03*
X435300Y1715300D03*
X448399Y1699450D03*
X447699Y1682850D03*
X449599Y1656950D03*
X483599Y1662550D03*
X485599Y1694850D03*
X502899Y1709650D03*
X507399Y1683350D03*
X509199Y1660550D03*
X468499Y1712550D03*
X467999Y1687050D03*
Y1696050D03*
Y1668050D03*
X432400Y1680100D03*
X428600Y1691200D03*
X509900Y1731700D03*
X436799Y1772550D03*
X472699Y1792150D03*
X429499Y1748050D03*
X458499Y1742050D03*
X441499Y1758050D03*
X480999Y1756050D03*
X463999Y1772050D03*
X445499Y1792550D03*
X508200Y1758200D03*
X484999Y1779050D03*
X496999Y1799550D03*
X459999Y1862050D03*
X481299Y1811150D03*
X448099Y1809450D03*
X499999Y1854950D03*
X480499Y1855450D03*
X464999D03*
X443999Y1855950D03*
X476199Y1877450D03*
X434299Y1876050D03*
X446999Y1880050D03*
X492999Y1878050D03*
X504799Y1967550D03*
Y1939550D03*
Y1958550D03*
X505799Y1921050D03*
Y1912050D03*
Y1893050D03*
X475199Y1951950D03*
Y1923950D03*
Y1942950D03*
X476199Y1905450D03*
Y1896450D03*
X459299Y1966850D03*
Y1938850D03*
Y1957850D03*
X460299Y1920350D03*
Y1911350D03*
Y1892350D03*
X433299Y1950550D03*
Y1922550D03*
Y1941550D03*
X434299Y1904050D03*
Y1895050D03*
X445999Y1954550D03*
Y1945550D03*
Y1926550D03*
X446999Y1908050D03*
Y1899050D03*
X493499Y1909050D03*
X492499Y1955550D03*
X491999Y1943550D03*
Y1924550D03*
X492999Y1897050D03*
X509299Y1977250D03*
X493799D03*
X473299D03*
X455799Y1976750D03*
X436299Y1977250D03*
X492500Y1987500D03*
X476000Y1987000D03*
X456500Y1987500D03*
X438999Y1987550D03*
X522899Y64350D03*
Y45350D03*
X587999Y63550D03*
X588499Y46550D03*
X587999Y25050D03*
X541499Y63550D03*
X541999Y46550D03*
X541499Y25050D03*
X516499Y6550D03*
X535999D03*
X551499D03*
X570999Y6050D03*
X588499Y6550D03*
X523899Y85350D03*
X520299Y141450D03*
Y122450D03*
X569099Y112550D03*
X568099Y91550D03*
Y72550D03*
X562799Y146750D03*
Y127750D03*
X587999Y145050D03*
X588499Y125550D03*
X541499Y145050D03*
X541999Y125550D03*
Y108050D03*
Y79050D03*
Y93550D03*
X565999Y199950D03*
X528799D03*
X521299Y162450D03*
X563799Y167750D03*
X587999Y217050D03*
X568499Y217550D03*
X552999D03*
X533499D03*
X588999Y185050D03*
X587999Y164050D03*
X542499Y185050D03*
X541499Y164050D03*
X544799Y293950D03*
X540099Y306550D03*
X516899Y306950D03*
X515499Y284050D03*
X536499Y283050D03*
X525999Y255050D03*
X540499D03*
X572999Y287050D03*
X572499Y306550D03*
X572999Y269550D03*
Y255050D03*
X558099Y335050D03*
X557933Y331010D03*
X557999Y322550D03*
Y326550D03*
X579899Y375750D03*
X530999Y381550D03*
X520499Y353550D03*
X548100Y362200D03*
X573499Y346550D03*
X572499Y325550D03*
X577899Y460550D03*
X578399Y441050D03*
X577399Y420050D03*
X539799Y466050D03*
X538799Y445050D03*
X576099Y481850D03*
X511299Y449150D03*
X519499Y471550D03*
X518999Y416550D03*
X592499Y478050D03*
Y459050D03*
X592999Y439550D03*
Y422050D03*
Y407550D03*
X556499Y467550D03*
X555999Y412550D03*
X539299Y485550D03*
X576599Y522350D03*
X577099Y502850D03*
X579499Y561550D03*
X558499Y562550D03*
X538999Y562050D03*
X535499Y545050D03*
X514499Y546050D03*
X518999Y508550D03*
X519499Y489050D03*
X555999Y504550D03*
X556499Y485050D03*
X558499Y616050D03*
X554304Y615840D03*
X554499Y624550D03*
X558699D03*
X554499Y620050D03*
X558709Y620245D03*
X534499Y640050D03*
X586299Y711250D03*
X565699Y710650D03*
X549999Y710050D03*
X547999Y728550D03*
X573499Y690550D03*
Y673050D03*
Y658550D03*
X534499Y672050D03*
Y654550D03*
Y805950D03*
X511199Y782050D03*
X527499Y747150D03*
X525499Y772450D03*
X547499Y799050D03*
Y780050D03*
X547999Y760550D03*
Y743050D03*
X575499Y802050D03*
X575999Y782550D03*
Y765050D03*
X577999Y732050D03*
X575999Y750550D03*
X526499Y851150D03*
X510899Y868150D03*
X578299Y895650D03*
X541399Y873450D03*
Y854450D03*
X512899Y842550D03*
Y823550D03*
X521999Y895550D03*
X522499Y876050D03*
X576499Y842050D03*
X575499Y821050D03*
X583299Y961450D03*
X578299Y914650D03*
X540299Y956850D03*
X539299Y935850D03*
X570899Y965850D03*
Y946850D03*
X521999Y914550D03*
X562999Y898050D03*
X560499Y968050D03*
X560999Y948550D03*
Y916550D03*
Y931050D03*
X516499Y957050D03*
X514499Y975550D03*
X583299Y980450D03*
X534599Y1048550D03*
X571899Y986850D03*
X573499Y1055550D03*
Y1036550D03*
X541899Y1021450D03*
X540899Y1000450D03*
Y981450D03*
X560499Y987050D03*
X560999Y999050D03*
X558999Y1049550D03*
Y1017550D03*
Y1032050D03*
X513999Y1046050D03*
Y1027050D03*
X514499Y1007550D03*
Y990050D03*
X588499Y1101550D03*
X578999Y1114550D03*
X568499Y1101550D03*
X564499Y1116050D03*
X548999D03*
X529499D03*
X511999Y1115550D03*
X553999Y1103050D03*
X538499D03*
X518999D03*
X535599Y1069550D03*
X574499Y1076550D03*
X558499Y1088050D03*
Y1069050D03*
X547099Y1202750D03*
Y1221750D03*
X546499Y1180750D03*
Y1195250D03*
X567999Y1215550D03*
Y1206550D03*
Y1187550D03*
X527999Y1212550D03*
X527499Y1200550D03*
Y1181550D03*
X579299Y1300750D03*
X527499Y1278150D03*
X530499Y1297050D03*
X561099Y1301050D03*
X566399Y1273850D03*
X549399Y1302850D03*
Y1274850D03*
Y1293850D03*
X548799Y1252850D03*
Y1267350D03*
X547099Y1230750D03*
X583299Y1283250D03*
Y1255250D03*
Y1274250D03*
X582699Y1233250D03*
Y1247750D03*
X565999Y1248550D03*
Y1234050D03*
X525999Y1263050D03*
Y1245550D03*
Y1231050D03*
X530200Y1327300D03*
X555699Y1322950D03*
X581999Y1370150D03*
X559099Y1343250D03*
X545099Y1355250D03*
X518499Y1346950D03*
X540399Y1382150D03*
X523999Y1391050D03*
X523499Y1360050D03*
Y1379050D03*
X580999Y1412750D03*
X575699Y1438950D03*
X538799Y1409750D03*
X536799Y1436350D03*
X528499Y1460250D03*
X546099Y1467550D03*
X582999Y1461250D03*
X557499Y1443050D03*
Y1452050D03*
Y1424050D03*
X516999Y1437050D03*
X517499Y1449050D03*
X516999Y1418050D03*
X563499Y1497550D03*
Y1486550D03*
Y1503550D03*
Y1492050D03*
X590599Y1483450D03*
X529799Y1555050D03*
X567999Y1549950D03*
X582299Y1534150D03*
X538999Y1528350D03*
X518899Y1530150D03*
X532499Y1635550D03*
X552099Y1601950D03*
X553399Y1624550D03*
X590799Y1627850D03*
X588000Y1604000D03*
X588099Y1572050D03*
X552199Y1576650D03*
X569499Y1619550D03*
Y1610550D03*
X573400Y1577600D03*
X529499Y1616550D03*
X533800Y1575500D03*
X528999Y1604550D03*
X518499Y1643950D03*
X538299Y1721050D03*
X532599Y1655650D03*
X554199Y1651950D03*
X555199Y1674750D03*
X555399Y1689350D03*
X555899Y1706750D03*
X580299Y1722550D03*
X590599Y1694450D03*
X580799Y1646150D03*
X572999Y1694550D03*
Y1703550D03*
Y1675550D03*
X532499Y1688550D03*
X532999Y1700550D03*
X532499Y1669550D03*
X582599Y1740050D03*
X560399Y1792550D03*
X555500Y1802700D03*
X539499Y1788150D03*
X526499Y1801150D03*
X556199Y1727050D03*
X522300Y1739200D03*
X532499Y1763050D03*
X515499Y1779050D03*
X544300Y1784638D03*
X531799Y1818450D03*
X514199Y1815750D03*
X591499Y1855950D03*
X573999Y1855450D03*
X554499Y1855950D03*
X538999D03*
X517499Y1855450D03*
X588899Y1882350D03*
X562599Y1874450D03*
X519399Y1876750D03*
X533499Y1884050D03*
X575999Y1888050D03*
X587899Y1956850D03*
Y1928850D03*
Y1947850D03*
X588899Y1910350D03*
Y1901350D03*
X561599Y1948950D03*
Y1920950D03*
Y1939950D03*
X562599Y1902450D03*
Y1893450D03*
X546999Y1966850D03*
Y1938850D03*
Y1957850D03*
X547999Y1920350D03*
Y1911350D03*
Y1892350D03*
X518399Y1951250D03*
Y1923250D03*
Y1942250D03*
X519399Y1904750D03*
Y1895750D03*
X532499Y1958550D03*
Y1949550D03*
Y1930550D03*
X533499Y1912050D03*
Y1903050D03*
X575999Y1907050D03*
X576499Y1919050D03*
X574999Y1953550D03*
X575499Y1965550D03*
X574999Y1934550D03*
X585799Y1976250D03*
X570299D03*
X546299Y1977250D03*
X528799Y1976750D03*
X568999Y1987050D03*
X553499D03*
X588499Y1986550D03*
X511999Y1987550D03*
X531500Y1987500D03*
X603999Y54350D03*
Y35350D03*
X651799Y59650D03*
Y40650D03*
X674999Y59050D03*
X675499Y42050D03*
X674999Y20550D03*
X624499Y61550D03*
X624999Y44550D03*
X624499Y23050D03*
X608499Y6550D03*
X625999Y7050D03*
X645499D03*
X660999D03*
X646100Y106900D03*
X599499Y79550D03*
X604999Y75350D03*
X603999Y133750D03*
X652799Y80650D03*
X649899Y138350D03*
X674999Y140550D03*
X675499Y121050D03*
Y103550D03*
Y74550D03*
Y89050D03*
X624499Y143050D03*
X624999Y123550D03*
X623899Y202550D03*
X604999Y173750D03*
X603999Y152750D03*
X650899Y178350D03*
X649899Y157350D03*
X662499Y218050D03*
X642999D03*
X625499Y217550D03*
X605499D03*
X675999Y180550D03*
X674999Y159550D03*
X625499Y183050D03*
X624499Y162050D03*
X656499Y307050D03*
X653999Y286550D03*
X627999Y280050D03*
X627499Y299550D03*
X627999Y262550D03*
Y248050D03*
X599799Y385150D03*
X600299Y365650D03*
X599299Y344650D03*
X659899Y363250D03*
X632399Y358750D03*
X635399Y376250D03*
X607399Y380250D03*
X643599Y395950D03*
X655999Y344050D03*
X656499Y324550D03*
X628499Y339550D03*
X628200Y320000D03*
X644099Y450950D03*
X644599Y416950D03*
X644099Y436450D03*
X621499Y466550D03*
X621999Y432550D03*
X621499Y452050D03*
X620999Y411550D03*
X666999Y476550D03*
X643499Y546750D03*
X642499Y525750D03*
X613700Y504600D03*
X621499Y484050D03*
X593499Y499050D03*
X666499Y547050D03*
X666999Y508550D03*
X666499Y528050D03*
X666999Y491050D03*
X642999Y566250D03*
X640599Y604650D03*
X673999Y645150D03*
X645099Y639150D03*
X631999Y639650D03*
X665999Y623550D03*
X620499D03*
Y609050D03*
X595999Y641550D03*
Y624050D03*
Y609550D03*
X674999Y601550D03*
X646999Y584550D03*
X625999Y585050D03*
X606499Y584550D03*
X667499Y568050D03*
X651999Y718350D03*
X648999Y702350D03*
X629099Y714050D03*
X605299Y661750D03*
X609499Y708050D03*
X607499Y726550D03*
X647499Y689050D03*
Y671550D03*
Y657050D03*
X622999Y689550D03*
Y672050D03*
X597999Y690050D03*
X647399Y742150D03*
X653099Y803350D03*
X621499Y767150D03*
X633499Y750150D03*
X606999Y797050D03*
Y778050D03*
X607499Y758550D03*
Y741050D03*
X664999Y805050D03*
Y786050D03*
X665499Y766550D03*
X645799Y816650D03*
X642599Y883250D03*
X641599Y862250D03*
Y843250D03*
X621999Y835050D03*
X612999Y854550D03*
X629499Y853050D03*
Y868550D03*
X613499Y868050D03*
X663499Y896050D03*
X663999Y876550D03*
Y844550D03*
Y859050D03*
X665999Y826050D03*
X640300Y911500D03*
X639499Y971150D03*
Y952150D03*
X616699Y967250D03*
Y948250D03*
X658999Y959050D03*
X656999Y977550D03*
X603499Y904050D03*
X601499Y954550D03*
Y922550D03*
Y937050D03*
X664499Y936050D03*
X663499Y915050D03*
X673999Y1036550D03*
Y1017550D03*
X674699Y1061450D03*
X611399Y1045650D03*
Y1026650D03*
X617699Y988250D03*
X656499Y1048050D03*
Y1029050D03*
X656999Y1009550D03*
Y992050D03*
X631999Y1001550D03*
X629999Y1052050D03*
Y1020050D03*
Y1034550D03*
X600999Y1002050D03*
X598999Y1052550D03*
Y1020550D03*
Y1035050D03*
X633999Y1103050D03*
X669499Y1116550D03*
X616499Y1115050D03*
X605999Y1102050D03*
X598999Y1114550D03*
X674699Y1080450D03*
X674999Y1134950D03*
X641799Y1137650D03*
X627699Y1143550D03*
X612399Y1066650D03*
X629499Y1090550D03*
Y1071550D03*
X598499Y1091050D03*
Y1072050D03*
X603899Y1157850D03*
X626199Y1183450D03*
X597599Y1196050D03*
X596599Y1215050D03*
X651599Y1203050D03*
X650599Y1182050D03*
X651299Y1174150D03*
X650299Y1153150D03*
X668199Y1173850D03*
X667199Y1152850D03*
X671199Y1213750D03*
X670199Y1192750D03*
X628699Y1164550D03*
X668699Y1227650D03*
X672999Y1303450D03*
X608899Y1305050D03*
X600899Y1238650D03*
X630499Y1243950D03*
X657099Y1272850D03*
X657799Y1288450D03*
X656399Y1307050D03*
X618199Y1296250D03*
Y1268250D03*
Y1287250D03*
X617599Y1246250D03*
Y1260750D03*
X638999Y1286550D03*
Y1295550D03*
Y1267550D03*
X598499Y1280550D03*
X598999Y1292550D03*
X598499Y1261550D03*
X671999Y1324950D03*
X631799Y1322650D03*
X605599Y1326350D03*
X665699Y1337250D03*
X606199Y1338250D03*
X617899Y1360850D03*
X625499Y1383450D03*
X632499Y1347950D03*
X599999Y1382550D03*
X599499Y1351550D03*
Y1370550D03*
X654999Y1385050D03*
X654499Y1373050D03*
Y1354050D03*
X659699Y1445950D03*
X604899Y1407750D03*
X601299Y1447650D03*
X636799Y1461250D03*
X626799Y1432350D03*
X627499Y1406050D03*
X665699Y1462250D03*
X652999Y1435550D03*
Y1418050D03*
Y1403550D03*
X656099Y1479550D03*
X625199Y1489150D03*
X610899Y1496750D03*
X672399Y1508750D03*
X673699Y1535350D03*
X662099Y1549650D03*
X643099Y1541350D03*
X599799Y1544650D03*
X617699Y1530350D03*
X670699Y1603150D03*
X671399Y1625350D03*
X628499Y1636650D03*
X633499Y1615450D03*
X635500Y1603900D03*
X652399Y1575850D03*
X623499Y1564050D03*
X652499Y1618550D03*
Y1609550D03*
X639200Y1576200D03*
X612499Y1615550D03*
X611900Y1577900D03*
X611999Y1603550D03*
X649399Y1644950D03*
X657099Y1668850D03*
X635099Y1691150D03*
X607599Y1716450D03*
X593399Y1668850D03*
X627299Y1659550D03*
X600599Y1645450D03*
X674999Y1676550D03*
X656499Y1697050D03*
X609499Y1692050D03*
Y1675050D03*
X642499Y1709050D03*
X665399Y1752350D03*
X650399Y1771250D03*
X593299Y1760950D03*
X619499Y1803150D03*
X627273Y1793905D03*
X606999Y1745550D03*
X625499Y1725050D03*
X675499Y1757050D03*
X675999Y1769050D03*
X675499Y1738050D03*
X642400Y1800100D03*
X659159Y1792278D03*
X626999Y1800050D03*
X659949Y1803670D03*
X664549Y1797436D03*
X634999Y1803050D03*
X633931Y1795465D03*
X645099Y1877550D03*
X667999Y1870950D03*
X632799Y1820450D03*
X627494Y1829068D03*
X608599Y1810750D03*
X669399Y1855350D03*
X627499Y1855950D03*
X611999D03*
X630699Y1872750D03*
X602799Y1887350D03*
X640999Y1815550D03*
X595199Y1820910D03*
X659549Y1815384D03*
X644049Y1810834D03*
X661549Y1822634D03*
X633837Y1807384D03*
X646799Y1926450D03*
X645399Y1906150D03*
X673899Y1966850D03*
Y1938850D03*
Y1957850D03*
X674899Y1920350D03*
Y1911350D03*
Y1892350D03*
X660299Y1964550D03*
Y1936550D03*
Y1955550D03*
X661299Y1918050D03*
Y1909050D03*
Y1890050D03*
X629699Y1947250D03*
Y1919250D03*
Y1938250D03*
X630699Y1900750D03*
Y1891750D03*
X601799Y1961850D03*
Y1933850D03*
Y1952850D03*
X602799Y1915350D03*
Y1906350D03*
X616499Y1913050D03*
Y1922050D03*
Y1894050D03*
X615499Y1959550D03*
Y1968550D03*
Y1940550D03*
X644999Y1953050D03*
X645499Y1965050D03*
X644999Y1934050D03*
X659299Y1976250D03*
X643799D03*
X622799D03*
X605299Y1975750D03*
X642499Y1987050D03*
X626999D03*
X661999Y1986550D03*
X605999Y1987050D03*
X751499Y48350D03*
X694999Y62650D03*
X757499Y63050D03*
Y44050D03*
X725499Y62050D03*
X725999Y45050D03*
X725499Y23550D03*
X680499Y6550D03*
X697999Y7050D03*
X712499Y6050D03*
X729999Y6550D03*
X749499D03*
X752099Y112150D03*
X738199Y137450D03*
X695999Y102650D03*
X694999Y81650D03*
X699699Y141750D03*
X758499Y84050D03*
X725499Y143550D03*
X725999Y124050D03*
Y106550D03*
Y77550D03*
Y92050D03*
X757999Y154550D03*
Y159050D03*
X753999Y154550D03*
Y159050D03*
X728899Y204550D03*
X688999Y196550D03*
X700699Y181750D03*
X699699Y160750D03*
X749499Y218550D03*
X729499D03*
X711999Y218050D03*
X677999D03*
X726499Y183550D03*
X725499Y162550D03*
X755499Y314550D03*
X751539Y313984D03*
X711999Y307550D03*
Y293050D03*
X723200Y275500D03*
X711499Y252550D03*
X680500Y280700D03*
X682999Y300050D03*
X683499Y263050D03*
Y248550D03*
X746999Y325550D03*
X755346Y319149D03*
X751499Y318050D03*
X748000Y357500D03*
X749899Y398550D03*
X711499Y344550D03*
X711999Y325050D03*
X683999Y340050D03*
X682999Y319050D03*
X752999Y343550D03*
X748000Y333000D03*
X713699Y455450D03*
X713199Y474950D03*
X712699Y434450D03*
X750399Y453550D03*
X750899Y419550D03*
X750399Y439050D03*
X694999Y480550D03*
X737999Y467050D03*
X691399Y548350D03*
X755699Y528650D03*
X756199Y509150D03*
X755199Y488150D03*
X754499Y564650D03*
X713099Y561550D03*
X713599Y542050D03*
X712599Y521050D03*
X713199Y489450D03*
X695499Y521050D03*
X695999Y501550D03*
X737999Y559050D03*
X738499Y539550D03*
Y522050D03*
Y507550D03*
X738999Y488050D03*
X691899Y588850D03*
X692399Y569350D03*
X754999Y605150D03*
X755499Y585650D03*
X717099Y636050D03*
X729699Y640350D03*
X731499Y604050D03*
Y586550D03*
Y572050D03*
X690499Y623050D03*
X744999Y626550D03*
X721499Y617550D03*
X699999Y610050D03*
X745696Y725050D03*
X751499Y679148D03*
X749499Y716050D03*
X744999Y715550D03*
X749999Y720050D03*
X745499D03*
X757400Y686300D03*
X720899Y712250D03*
X732499Y729250D03*
X681899Y713650D03*
X679299Y703050D03*
X727099Y715050D03*
X739399Y688150D03*
X747999Y670750D03*
X723499Y654850D03*
X693999Y648150D03*
X754999Y694050D03*
X702999Y688050D03*
Y670550D03*
Y656050D03*
X678499Y688550D03*
Y671050D03*
X749999Y700050D03*
X750000Y755500D03*
X710899Y751150D03*
X696299Y741850D03*
X685999Y780050D03*
X694599Y763450D03*
X743099Y785350D03*
X733799Y761450D03*
X716599Y736850D03*
X723999Y802350D03*
Y783350D03*
X687099Y804650D03*
X706999Y811550D03*
Y792550D03*
X707499Y773050D03*
X746999Y741050D03*
X747500Y733762D03*
X728499Y841850D03*
X724999Y823350D03*
X688099Y844650D03*
X687099Y823650D03*
X729999Y881850D03*
Y862850D03*
X751599Y887350D03*
X705999Y851050D03*
Y865550D03*
X707999Y832550D03*
X751499Y855550D03*
Y836550D03*
X751999Y817050D03*
X707399Y918550D03*
Y899550D03*
X678299Y978350D03*
X730999Y902850D03*
X688099Y936350D03*
X687099Y915350D03*
Y896350D03*
X724699Y976250D03*
X723699Y955250D03*
Y936250D03*
X752599Y927350D03*
X751599Y906350D03*
X706499Y942550D03*
X749999Y965550D03*
Y946550D03*
X751399Y1023550D03*
Y1004550D03*
X752399Y1052550D03*
X734999Y1030550D03*
Y1045050D03*
X713999Y1049050D03*
Y1031550D03*
Y1017050D03*
X678299Y997350D03*
X694999Y993050D03*
X692999Y1043550D03*
Y1011550D03*
Y1026050D03*
X750999Y986550D03*
X745599Y1129050D03*
X755499Y1119050D03*
X749999Y1119550D03*
X748999Y1115550D03*
X748499Y1111550D03*
X734999Y1062550D03*
X713499Y1068550D03*
X737999Y1119050D03*
X727499Y1106050D03*
X720499Y1118550D03*
X709999Y1105550D03*
X700499Y1118550D03*
X689999Y1105550D03*
X727499Y1132650D03*
X704299D03*
X692499Y1082050D03*
Y1063050D03*
X753999Y1100050D03*
X747000Y1142550D03*
X754151Y1135982D03*
X747000Y1159000D03*
X713599Y1214650D03*
X756799Y1217650D03*
X758799Y1190150D03*
Y1199150D03*
X717999Y1169150D03*
X716999Y1148150D03*
X714399Y1199750D03*
X713399Y1178750D03*
X735999Y1220550D03*
Y1206050D03*
X737999Y1187550D03*
Y1178550D03*
Y1159550D03*
X695999Y1217550D03*
Y1203050D03*
X697999Y1184550D03*
X697499Y1172550D03*
Y1153550D03*
X690999Y1295550D03*
X684299Y1249550D03*
X740799Y1298750D03*
X723499Y1292650D03*
Y1278150D03*
X725499Y1250650D03*
Y1259650D03*
Y1231650D03*
X755399Y1300650D03*
Y1286150D03*
X757399Y1258650D03*
Y1267650D03*
Y1239650D03*
X756799Y1232150D03*
X709699Y1264550D03*
X708699Y1243550D03*
X740499Y1252550D03*
Y1270050D03*
X695999Y1235050D03*
X739199Y1348950D03*
X742099Y1320650D03*
X719199Y1322350D03*
X695999Y1323350D03*
X677999Y1347550D03*
X680299Y1365850D03*
X713899Y1386450D03*
X707899Y1346250D03*
X734199Y1373850D03*
X694999Y1388050D03*
Y1379050D03*
Y1360050D03*
X702299Y1404450D03*
X736199Y1399050D03*
X741099Y1450250D03*
X737799Y1428350D03*
X716899Y1459850D03*
X700899Y1450250D03*
X681299Y1393150D03*
X678299Y1425050D03*
X686999Y1468850D03*
X719499Y1446650D03*
X721899Y1419050D03*
X754999Y1420050D03*
Y1437550D03*
X692999Y1421050D03*
Y1406550D03*
X745600Y1531296D03*
X751000Y1517000D03*
X757500Y1522500D03*
X751000Y1521000D03*
Y1525000D03*
X741099Y1498150D03*
X729199Y1492750D03*
X716199Y1503050D03*
X735799Y1533650D03*
X714599Y1533950D03*
X708899Y1549250D03*
X685299Y1551950D03*
X747199Y1509150D03*
X755499Y1507550D03*
X750000Y1546000D03*
X752099Y1539972D03*
X734499Y1563550D03*
X722199Y1564250D03*
X706700Y1579900D03*
X698599Y1568550D03*
X681299Y1579150D03*
X693599Y1602450D03*
X686699Y1638650D03*
X742000Y1560000D03*
X743400Y1578700D03*
X719999Y1605050D03*
X751300Y1604900D03*
X732999Y1620050D03*
X756299Y1679050D03*
X738799Y1677250D03*
X750099Y1694950D03*
X756499Y1712150D03*
X739199Y1716750D03*
X721199Y1723750D03*
X727399Y1694350D03*
X717099Y1702450D03*
X693099Y1722350D03*
X691999Y1660550D03*
X751999Y1775550D03*
X756617Y1780067D03*
X752657Y1779496D03*
X755999Y1775550D03*
X756900Y1766000D03*
X753558Y1769946D03*
X757518Y1770517D03*
X752900Y1766000D03*
X732549Y1802934D03*
X738049Y1793884D03*
X751899Y1752150D03*
X747799Y1766750D03*
X729499Y1778750D03*
X729999Y1756450D03*
X747499Y1734350D03*
X702599Y1730550D03*
X709099Y1751850D03*
X690499Y1744950D03*
X694599Y1768450D03*
X715999Y1763050D03*
Y1772050D03*
Y1744050D03*
X693549Y1793134D03*
X706549Y1793634D03*
X744049Y1791634D03*
X740549Y1802634D03*
X753949Y1798194D03*
X685549Y1799134D03*
X715549Y1799634D03*
X717564Y1804045D03*
X717000Y1812384D03*
X741549Y1818384D03*
X705000Y1811900D03*
X686999Y1870250D03*
X728099Y1844750D03*
X747599Y1844250D03*
X743799Y1888850D03*
X728299D03*
X753699Y1879250D03*
X732199Y1878750D03*
X744699Y1868450D03*
X758399Y1868350D03*
X723199Y1867950D03*
X743399Y1855850D03*
X725899Y1855350D03*
X690899Y1855850D03*
X706399D03*
X697999Y1844550D03*
X732999Y1868550D03*
X711500Y1817700D03*
X704300Y1828400D03*
X686473Y1818375D03*
X740549Y1810384D03*
X681549Y1825234D03*
X687049Y1822334D03*
X720300Y1808884D03*
X749499Y1933050D03*
X750000Y1965500D03*
X744000Y1965000D03*
X696299Y1898850D03*
X716599Y1918450D03*
X728799Y1933050D03*
X709199Y1962950D03*
X698299Y1948050D03*
X676399Y1901150D03*
X695299Y1926450D03*
X711899Y1944050D03*
X736799Y1919450D03*
X728799Y1908150D03*
X705599Y1891850D03*
X730499Y1954650D03*
X755299Y1902150D03*
X739799D03*
X685499Y1959050D03*
Y1968050D03*
Y1940050D03*
X755500Y1914500D03*
X746000Y1953500D03*
X746149Y1945000D03*
X721499Y1974550D03*
X696299Y1976250D03*
X678799Y1975750D03*
X754999Y1987550D03*
X737499Y1987050D03*
X717999Y1987550D03*
X702499D03*
X679499Y1987050D03*
X774399Y54050D03*
X763399Y24150D03*
X817599Y43750D03*
X824899Y25150D03*
X813299Y68350D03*
Y49350D03*
X796999Y65550D03*
X797499Y48550D03*
X796999Y27050D03*
X764999Y6550D03*
X784499Y6050D03*
X801999Y6550D03*
X818999Y6050D03*
X836499Y6550D03*
X840499Y55050D03*
X839999Y46050D03*
X840999Y62550D03*
X778399Y105250D03*
X775399Y80250D03*
X821199Y137450D03*
X813299Y110850D03*
X805899Y126150D03*
X767399Y140150D03*
X796599Y123450D03*
X814299Y89350D03*
X796999Y147050D03*
X797499Y127550D03*
Y110050D03*
Y81050D03*
Y95550D03*
X837499Y138550D03*
X838499Y145050D03*
X837999Y91050D03*
X838999Y85050D03*
X838499Y99550D03*
Y107050D03*
X839499Y119050D03*
X841499Y71550D03*
X840499Y182550D03*
X817999Y182050D03*
X818013Y173064D03*
X760799Y181950D03*
X779399Y200550D03*
X786499Y219050D03*
X800999Y216550D03*
X766999Y219050D03*
X797999Y187050D03*
X796999Y166050D03*
X827774Y213183D03*
X836499Y213162D03*
X838299Y204800D03*
X829999Y200550D03*
X838999Y313550D03*
X821499Y314050D03*
X830000Y294500D03*
X785999Y285550D03*
X809373Y307571D03*
Y297571D03*
Y292571D03*
X808999Y303050D03*
X796873Y307571D03*
Y303071D03*
Y298571D03*
Y294071D03*
X836600Y261000D03*
X784478Y355424D03*
Y359924D03*
X781478Y363924D03*
X776978D03*
X772478Y359924D03*
Y363924D03*
X839299Y390950D03*
X819299Y394250D03*
X838499Y352050D03*
X806499Y364152D03*
X769000Y347500D03*
X774000Y333500D03*
X761500Y348500D03*
X840299Y430950D03*
X839299Y409950D03*
X820299Y434250D03*
X819299Y413250D03*
X802999Y466050D03*
X774999Y476550D03*
Y462050D03*
X825399Y540950D03*
X825899Y521450D03*
X824899Y500450D03*
X835599Y564050D03*
X834599Y543050D03*
X802999Y558050D03*
X803499Y538550D03*
Y521050D03*
Y506550D03*
X803999Y487050D03*
X775499Y553550D03*
X774499Y532550D03*
X774999Y494050D03*
X774499Y513550D03*
X835099Y583550D03*
X814499Y601550D03*
Y584050D03*
Y569550D03*
X789999Y602050D03*
Y584550D03*
Y570050D03*
X785499Y641050D03*
X777499Y638050D03*
X815000Y687500D03*
X771800Y686600D03*
X786500Y686100D03*
X798000Y686400D03*
X764599Y655750D03*
X777499Y664550D03*
X794999D03*
X806300Y670600D03*
X841000Y671100D03*
X766499Y699050D03*
X782999Y699550D03*
X836149Y714050D03*
X766499Y705550D03*
X776999Y690050D03*
X806831Y701853D03*
Y706853D03*
Y711853D03*
X794331Y698353D03*
Y702853D03*
Y707353D03*
Y711853D03*
X806999Y697050D03*
X835300Y663200D03*
X771196Y764382D03*
Y760382D03*
X775696Y764382D03*
X780196D03*
X783196Y760382D03*
Y755882D03*
X799385Y761436D03*
X778999Y806950D03*
X763099Y796350D03*
X835999Y799050D03*
Y781550D03*
Y767050D03*
X811499Y799550D03*
Y782050D03*
Y767550D03*
X837799Y754150D03*
X779500Y736000D03*
X774500Y733000D03*
X761500Y747500D03*
X825199Y850850D03*
X827699Y892450D03*
Y873450D03*
X776199Y879250D03*
X775199Y858250D03*
Y839250D03*
X800999Y892550D03*
X802999Y874050D03*
X801999Y853050D03*
Y834050D03*
X802499Y814550D03*
X828699Y913450D03*
X826999Y963150D03*
X773199Y960650D03*
X772199Y939650D03*
Y920650D03*
X800499Y944050D03*
Y963050D03*
X800999Y924550D03*
Y907050D03*
Y1037550D03*
Y1005550D03*
Y1020050D03*
X827999Y1003150D03*
X826999Y982150D03*
X777899Y1028050D03*
X776899Y1007050D03*
Y988050D03*
X801499Y984050D03*
X827000Y1102000D03*
X783999Y1096550D03*
X760999Y1095550D03*
X789499Y1099550D03*
X773499Y1101050D03*
X769499D03*
X773499Y1105050D03*
X769499D03*
X836149Y1118550D03*
X781999Y1085050D03*
X811499Y1097050D03*
X807499D03*
X807341Y1116216D03*
Y1111216D03*
Y1101216D03*
X806999Y1106050D03*
X802499Y1097566D03*
X798499D03*
X834500Y1067600D03*
X770000Y1137900D03*
X783333Y1157392D03*
Y1161892D03*
X780333Y1165892D03*
X775833D03*
X771333Y1161892D03*
Y1165892D03*
X808299Y1175850D03*
X806599Y1189750D03*
X803599Y1211050D03*
X831499Y1209550D03*
Y1200550D03*
Y1181550D03*
X789499Y1225050D03*
X791499Y1206550D03*
X790999Y1194550D03*
Y1175550D03*
X839999Y1157550D03*
X770000Y1151000D03*
X761998Y1151400D03*
X826199Y1294450D03*
X828199Y1267850D03*
X788999Y1278150D03*
X791999Y1294450D03*
X808199Y1290350D03*
Y1275850D03*
X810199Y1248350D03*
Y1257350D03*
Y1229350D03*
X829499Y1242550D03*
Y1228050D03*
X789499Y1257050D03*
Y1239550D03*
X825500Y1379000D03*
X831499Y1324950D03*
X795299Y1326650D03*
X822199Y1335250D03*
X819199Y1353550D03*
X798299Y1344250D03*
X779399Y1361850D03*
X762499Y1335550D03*
Y1353050D03*
X799999Y1340550D03*
Y1358050D03*
X806499Y1390550D03*
X803299Y1426650D03*
X773999Y1393450D03*
X763399Y1401450D03*
X781999Y1434650D03*
X805899Y1464250D03*
X771399Y1474550D03*
X806499Y1408050D03*
X834499Y1397550D03*
X836600Y1416500D03*
Y1471100D03*
X822100Y1470700D03*
X829500Y1506000D03*
X769300Y1488100D03*
X779000Y1488400D03*
X786500Y1488600D03*
X801300Y1489000D03*
X770999Y1500050D03*
X780499D03*
X839499Y1523550D03*
X773499Y1509050D03*
X769499D03*
X786999Y1506550D03*
X791499Y1492550D03*
X770500Y1554000D03*
X809245Y1518722D03*
Y1508722D03*
Y1503722D03*
X795999Y1518550D03*
Y1514050D03*
Y1509550D03*
Y1504550D03*
X808999Y1513550D03*
X774214Y1541656D03*
X763000Y1555000D03*
X785827Y1561296D03*
Y1565796D03*
X782827Y1569796D03*
X778327D03*
X773327Y1565796D03*
X773827Y1569796D03*
X813300Y1604100D03*
X827199Y1622750D03*
X841499Y1638950D03*
X803599Y1618350D03*
X826499Y1609050D03*
X825999Y1578050D03*
X839899Y1562050D03*
X829200Y1719800D03*
X824100Y1719900D03*
X819400Y1721900D03*
X837199Y1660550D03*
X814599Y1642650D03*
X776999Y1647650D03*
X797299Y1646650D03*
X802899Y1670550D03*
X839199Y1683550D03*
X808899Y1698450D03*
X779999Y1717050D03*
X770399Y1699650D03*
X765099Y1664950D03*
X823499Y1693050D03*
Y1702050D03*
Y1674050D03*
X782999Y1687050D03*
X783499Y1699050D03*
X782999Y1668050D03*
X768300Y1778000D03*
X829199Y1783750D03*
X819593Y1783807D03*
X817249Y1793050D03*
X819200Y1727100D03*
X808299Y1755250D03*
X794499Y1734550D03*
X770099Y1730350D03*
X779899Y1748150D03*
X787900Y1758800D03*
X765600Y1756800D03*
X827999Y1791550D03*
X785799Y1795634D03*
X767159Y1792364D03*
X768549Y1816634D03*
X840400Y1827100D03*
X829799Y1856350D03*
X809299D03*
X791799Y1855850D03*
X801099Y1844750D03*
X785599D03*
X765099D03*
X780799Y1888850D03*
X763299Y1888350D03*
X833100Y1878500D03*
X806199Y1879250D03*
X788699Y1878750D03*
X769199Y1879250D03*
X833199Y1868450D03*
X818900Y1870800D03*
X797199Y1868450D03*
X779699Y1867950D03*
X779399Y1855850D03*
X763899D03*
X786699Y1808934D03*
X823499Y1825050D03*
X815499Y1817050D03*
X822700Y1875100D03*
X837499Y1876900D03*
X809600Y1887560D03*
X773999Y1923550D03*
X767999Y1923050D03*
X774499Y1930050D03*
X768999D03*
X783814Y1967213D03*
Y1971713D03*
X783499Y1907050D03*
X774499Y1908050D03*
X765999D03*
X838999Y1928550D03*
X790499Y1913050D03*
X775999Y1916050D03*
X840999Y1970550D03*
X768499Y1917550D03*
X790499Y1899550D03*
X770000Y1956500D03*
X829000Y1913000D03*
X795526Y1909696D03*
X795493Y1913696D03*
X795501Y1917696D03*
X795499Y1922050D03*
X807997Y1922865D03*
X808005Y1918865D03*
X807936Y1914865D03*
Y1910365D03*
X773250Y1944000D03*
X776000Y1949000D03*
X784016Y1975708D03*
X775814Y1975699D03*
X771814Y1975713D03*
X780000Y1976000D03*
X813599Y1979950D03*
X789299Y1983850D03*
X829499Y1980250D03*
X829999Y1987550D03*
X812499Y1987050D03*
X792999Y1987550D03*
X777499D03*
X902999Y22050D03*
X917499Y21550D03*
X909499D03*
X902499Y35050D03*
X909999Y35550D03*
X916499Y36050D03*
X844799Y19850D03*
X860799Y24150D03*
X885999Y21150D03*
X855999Y6550D03*
X871499D03*
X890999Y6050D03*
X908499Y6550D03*
X923999Y6050D03*
X854499Y39550D03*
X865499D03*
X883999Y39050D03*
X904999Y61550D03*
Y67550D03*
X905499Y56550D03*
X890700Y132500D03*
X872100Y132700D03*
X854300Y132600D03*
X891999Y146050D03*
X843499Y82550D03*
X855499Y82050D03*
X876999D03*
X867499D03*
X845999Y111050D03*
X886499Y99550D03*
Y104550D03*
X890459Y100116D03*
X890499Y104550D03*
X865499Y125550D03*
X875499D03*
X910499Y98550D03*
X905499Y94550D03*
X856499Y71050D03*
X881499Y70550D03*
X866999D03*
X904499Y74050D03*
X912399Y88150D03*
X916999Y168424D03*
X906999Y224150D03*
X887400Y233555D03*
X871786Y233924D03*
Y218924D03*
Y203924D03*
X907499Y160434D03*
X882999D03*
X885499Y165050D03*
X922999Y158550D03*
X854200Y269500D03*
X907999Y264150D03*
X906999Y243150D03*
X906399Y314250D03*
Y295250D03*
X863999Y313550D03*
X887400Y259700D03*
X879878Y247724D03*
X847577Y272131D03*
X847200Y267200D03*
X907399Y335250D03*
X875799Y386250D03*
X904999Y385050D03*
Y370550D03*
X854499Y387550D03*
Y373050D03*
X858400Y352300D03*
X847999Y352550D03*
X870600Y346700D03*
X876799Y426250D03*
X875799Y405250D03*
X884399Y462450D03*
Y443450D03*
X905499Y462050D03*
X904499Y441050D03*
Y422050D03*
X904999Y402550D03*
X854999Y464550D03*
X853999Y443550D03*
X854499Y405050D03*
X853999Y424550D03*
X873999Y484550D03*
X861199Y546050D03*
X860199Y525050D03*
X885399Y483450D03*
X914699Y524650D03*
X913699Y503650D03*
Y484650D03*
X899685Y559592D03*
X886749Y560500D03*
X894200Y560400D03*
X906999Y557050D03*
X921999D03*
X860699Y565550D03*
X898999Y622050D03*
Y604550D03*
X860499Y607550D03*
X861800Y591200D03*
X918999Y641550D03*
X870719Y609705D03*
X894000Y642400D03*
X870719Y639705D03*
X870773Y624705D03*
X876787Y567743D03*
X903999Y574378D03*
X866499Y724550D03*
X855499Y700550D03*
X847200Y672000D03*
X895999Y720050D03*
Y702550D03*
X900999Y670050D03*
Y652550D03*
X918499Y712050D03*
X918999Y673550D03*
X918499Y693050D03*
X918999Y656050D03*
X887401Y665000D03*
X881200Y652100D03*
X859999Y713050D03*
X871385Y719436D03*
X871786Y709482D03*
X871499Y689436D03*
X871786Y679436D03*
X860796Y678632D03*
X860499Y691050D03*
X852703Y667497D03*
X846400Y665500D03*
X862700Y735300D03*
X921399Y796350D03*
X921899Y776850D03*
Y759350D03*
Y744850D03*
X884499Y799050D03*
Y781550D03*
Y767050D03*
X859999Y799550D03*
Y782050D03*
Y767550D03*
X919499Y733050D03*
X856299Y753150D03*
X846799Y754150D03*
X865000Y752100D03*
X889699Y876050D03*
X847799Y828250D03*
X857099Y873450D03*
X920399Y886850D03*
Y869350D03*
Y854850D03*
X922399Y836350D03*
X921399Y815350D03*
X898499Y862050D03*
Y844550D03*
Y830050D03*
X873999Y862550D03*
Y845050D03*
Y830550D03*
X886999Y947250D03*
Y907350D03*
X867199Y941350D03*
X866199Y920350D03*
Y901350D03*
X850999Y962550D03*
Y943550D03*
X919899Y925350D03*
X920899Y946350D03*
X919899Y906350D03*
X905999Y962050D03*
X886583Y967600D03*
X877499Y977050D03*
X894999Y963050D03*
X922049Y961050D03*
X851999Y983550D03*
X921499Y1031050D03*
X920999Y1050550D03*
X921499Y1013550D03*
Y999050D03*
X870468Y1030227D03*
X880033Y1058592D03*
X886919Y1044478D03*
X870298Y1045227D03*
X870777Y1014948D03*
X855500Y1106500D03*
X863000Y1139000D03*
X851600Y1073300D03*
X846400Y1078700D03*
X921999Y1090550D03*
X920999Y1069550D03*
X887400Y1070600D03*
X859999Y1118550D03*
X841999D03*
X862000Y1094500D03*
X846500Y1073500D03*
X845799Y1190450D03*
X849799Y1199750D03*
X846499Y1170450D03*
X897299Y1182450D03*
X887999Y1209350D03*
X871399Y1201850D03*
Y1210850D03*
Y1182850D03*
X892499Y1224550D03*
X851999Y1218550D03*
X856400Y1157700D03*
X848999Y1158050D03*
X863300Y1153800D03*
X872099Y1268150D03*
X871399Y1291450D03*
X860099Y1295450D03*
X869399Y1243850D03*
Y1229350D03*
X890499Y1285550D03*
Y1271050D03*
X892499Y1252550D03*
Y1243550D03*
X850499Y1300050D03*
Y1282550D03*
Y1268050D03*
X852499Y1249550D03*
X851999Y1237550D03*
X875399Y1322650D03*
X868499Y1392550D03*
X890999Y1336550D03*
Y1354050D03*
X841999Y1341050D03*
Y1358550D03*
X880499Y1367550D03*
X869587Y1354050D03*
X882999Y1374550D03*
X879999Y1380170D03*
X891999Y1363550D03*
X873499Y1356050D03*
X847500Y1367000D03*
X894499Y1423550D03*
Y1441050D03*
X868499Y1410050D03*
X886913Y1449010D03*
X879727Y1463696D03*
X871836Y1450460D03*
Y1435460D03*
Y1420460D03*
X858500Y1511000D03*
X854327Y1481596D03*
X848300Y1483000D03*
X914599Y1521650D03*
X910899Y1549250D03*
X894499Y1522050D03*
Y1539550D03*
X895499Y1488050D03*
X902759Y1509585D03*
X861999Y1522550D03*
X843999Y1523550D03*
X887499Y1476050D03*
X865300Y1557700D03*
X845700Y1477100D03*
X923599Y1634350D03*
X909700Y1576400D03*
X907500Y1604000D03*
X908899Y1630050D03*
X868099Y1635650D03*
X887299Y1620050D03*
X886900Y1604100D03*
X873099Y1572550D03*
X850099Y1572250D03*
X849900Y1605100D03*
X852499Y1621350D03*
X866499Y1603050D03*
Y1612050D03*
X864000Y1578200D03*
X858400Y1561900D03*
X850499Y1562050D03*
X879200Y1698700D03*
X879900Y1709300D03*
X883900Y1709500D03*
X855350Y1703201D03*
X914899Y1657550D03*
X922599Y1682150D03*
X903599Y1686850D03*
X895999Y1661250D03*
X877699Y1646650D03*
X855799Y1658250D03*
X882999Y1678250D03*
X864099Y1683550D03*
X842799Y1701150D03*
X875900Y1709500D03*
X902900Y1709800D03*
X893500Y1694500D03*
X871100Y1690300D03*
X901500Y1716000D03*
X882200Y1744800D03*
X886400Y1744400D03*
X842500Y1799000D03*
X892700Y1727800D03*
X879399Y1798150D03*
X911299Y1800850D03*
X864000Y1748000D03*
X866699Y1770950D03*
X853799Y1790850D03*
X844499Y1788050D03*
X892700Y1736500D03*
X886200Y1776200D03*
X897239Y1771500D03*
X914999Y1791500D03*
X892999Y1776050D03*
X899599Y1776604D03*
X904814Y1789113D03*
X921499Y1770050D03*
X849800Y1888300D03*
X846000Y1811400D03*
X863099Y1813150D03*
X903299Y1814750D03*
X894999Y1829050D03*
X922899Y1853650D03*
X905299Y1852650D03*
X900299Y1876950D03*
X842199Y1879250D03*
X914999Y1887050D03*
Y1868050D03*
X862499Y1823550D03*
X854977Y1818994D03*
X887401Y1881500D03*
X894000Y1868452D03*
X887499Y1855550D03*
X869999Y1855972D03*
X871836Y1840972D03*
X869634Y1826876D03*
X854814Y1887250D03*
X847700Y1881900D03*
X864414Y1940050D03*
X914899Y1912450D03*
X916599Y1942650D03*
X897599Y1938750D03*
X914899Y1972250D03*
X873399Y1963650D03*
X904299Y1954950D03*
X897299Y1904150D03*
X907599Y1930050D03*
X915499Y1899050D03*
X861414Y1928550D03*
X843999D03*
X856999Y1970050D03*
X849999Y1970550D03*
X865200Y1968000D03*
X879399Y1974550D03*
X850499Y1977950D03*
X868699Y1983250D03*
X921499Y1986550D03*
X901999Y1987050D03*
X864999D03*
X849499D03*
X884499Y1986550D03*
X974699Y64650D03*
X977399Y44050D03*
X954799Y17850D03*
X974699Y21450D03*
X991399Y22450D03*
X1002699Y40050D03*
X991999Y56050D03*
X941499Y6550D03*
X960999D03*
X976499D03*
X995999Y6050D03*
X967499Y47050D03*
Y56050D03*
Y64050D03*
X945499Y33550D03*
X940499Y33050D03*
X929999Y32550D03*
X928499Y51550D03*
X943499Y48050D03*
Y55050D03*
X928999Y56050D03*
X928499Y60550D03*
X928999Y65550D03*
X942999Y61550D03*
Y66550D03*
X983099Y83650D03*
X1005299Y71350D03*
X977699Y109150D03*
X994399Y101250D03*
X981099Y123450D03*
X939199Y142050D03*
X968399Y137150D03*
X967999Y73050D03*
Y82050D03*
X943499Y72550D03*
Y78050D03*
X964042Y96050D03*
X954499Y116550D03*
X944499Y95050D03*
X941873Y103050D03*
X935999Y104050D03*
X926499Y103050D03*
X988699Y174350D03*
X967399Y180350D03*
X956099Y181350D03*
X958799Y167350D03*
X1004799Y231450D03*
X1005299Y211950D03*
Y194450D03*
Y179950D03*
X952799Y231150D03*
Y213650D03*
Y199150D03*
X982999Y203550D03*
Y221050D03*
Y189050D03*
X932499Y223550D03*
Y206050D03*
Y191550D03*
X945999Y166550D03*
X937499Y158500D03*
X1005299Y305450D03*
Y290950D03*
X1005799Y271450D03*
X1004799Y250450D03*
X952799Y310150D03*
X953299Y290650D03*
X952299Y269650D03*
Y250650D03*
X983999Y316050D03*
Y301550D03*
X933499Y304050D03*
X983499Y280550D03*
X982499Y259550D03*
Y240550D03*
X932999Y283050D03*
X931999Y262050D03*
Y243050D03*
X1005799Y382450D03*
X1004799Y361450D03*
X1005299Y322950D03*
X1004799Y342450D03*
X952299Y380650D03*
X952799Y342150D03*
X952299Y361650D03*
X952799Y324650D03*
X984499Y393050D03*
X983499Y372050D03*
Y353050D03*
X983999Y333550D03*
X933999Y395550D03*
X932999Y374550D03*
X933499Y336050D03*
X932999Y355550D03*
X933499Y318550D03*
X966199Y473350D03*
X1000699Y482350D03*
Y463350D03*
X954799Y451650D03*
Y434150D03*
Y419650D03*
X953299Y401650D03*
X983499Y464050D03*
X983999Y427050D03*
Y444550D03*
Y412550D03*
X933499Y447050D03*
X932999Y466550D03*
X933499Y429550D03*
Y415050D03*
X967199Y513350D03*
X966199Y492350D03*
X1001699Y503350D03*
X1003499Y546350D03*
X1003999Y526850D03*
X951299Y560150D03*
Y541150D03*
X951799Y521650D03*
Y504150D03*
Y489650D03*
X985999Y536550D03*
Y554050D03*
Y522050D03*
X935499Y556550D03*
Y539050D03*
Y524550D03*
X984499Y504050D03*
X983499Y483050D03*
X933999Y506550D03*
X932999Y485550D03*
X927999Y568550D03*
X967799Y606350D03*
X966799Y585350D03*
Y566350D03*
X1005999Y636350D03*
Y618850D03*
X1004499Y586350D03*
X1005999Y604350D03*
X1003499Y565350D03*
X950299Y631650D03*
Y614150D03*
Y599650D03*
X952299Y581150D03*
X969499Y639050D03*
X986499Y613550D03*
X985499Y592550D03*
Y573550D03*
X935999Y616050D03*
X934999Y595050D03*
Y576050D03*
X949799Y670150D03*
X950799Y691150D03*
X949799Y651150D03*
X969999Y730550D03*
X968999Y709550D03*
Y690550D03*
X969499Y653550D03*
Y671050D03*
Y795750D03*
X969999Y776250D03*
Y758750D03*
Y744250D03*
X994499Y803550D03*
Y784550D03*
X994999Y747550D03*
Y765050D03*
Y733050D03*
X943999Y806050D03*
X944499Y767550D03*
X943999Y787050D03*
X944499Y750050D03*
Y735550D03*
X970499Y879750D03*
Y862250D03*
Y847750D03*
Y835750D03*
X969499Y814750D03*
X992999Y894550D03*
X993499Y857550D03*
Y875050D03*
Y843050D03*
X942999Y877550D03*
Y860050D03*
Y845550D03*
X995499Y824550D03*
X944999Y827050D03*
X929499Y971100D03*
X994499Y973550D03*
Y956050D03*
Y941550D03*
X949299Y977450D03*
X970999Y939250D03*
X969999Y918250D03*
Y899250D03*
X993999Y934550D03*
X992999Y913550D03*
X943499Y937050D03*
X942499Y916050D03*
Y897050D03*
X994999Y1033050D03*
Y1045050D03*
X993999Y1012050D03*
Y993050D03*
X948799Y1047950D03*
Y1028950D03*
X949299Y1009450D03*
Y991950D03*
X971499Y1048050D03*
X971999Y1011050D03*
Y1028550D03*
Y996550D03*
X949799Y1068950D03*
Y1080950D03*
X998599Y1128450D03*
Y1110950D03*
Y1096450D03*
X950699Y1139750D03*
Y1122250D03*
Y1107750D03*
X975999Y1115550D03*
Y1133050D03*
Y1101050D03*
X925499Y1135550D03*
Y1118050D03*
Y1103550D03*
X972499Y1088050D03*
X971499Y1067050D03*
X999099Y1214450D03*
Y1199950D03*
Y1187950D03*
X998099Y1147950D03*
Y1166950D03*
X951199Y1225750D03*
Y1211250D03*
Y1199250D03*
X950199Y1159250D03*
Y1178250D03*
X976499Y1219050D03*
Y1204550D03*
X925999Y1221550D03*
Y1207050D03*
X976499Y1192550D03*
X975499Y1171550D03*
Y1152550D03*
X925999Y1195050D03*
X924999Y1174050D03*
Y1155050D03*
X999599Y1291450D03*
X998599Y1270450D03*
Y1251450D03*
X999099Y1231950D03*
X951699Y1302750D03*
X950699Y1281750D03*
Y1262750D03*
X951199Y1243250D03*
X976999Y1296050D03*
X975999Y1275050D03*
Y1256050D03*
X976499Y1236550D03*
X926499Y1298550D03*
X925499Y1277550D03*
X925999Y1239050D03*
X925499Y1258550D03*
X975100Y1342600D03*
X1000700Y1358100D03*
X996500Y1324800D03*
X952499Y1361850D03*
X944000Y1391900D03*
X943799Y1380850D03*
Y1342950D03*
X965099Y1324350D03*
X928499Y1325350D03*
X976499Y1377050D03*
Y1362550D03*
X925999Y1379550D03*
Y1365050D03*
X973500Y1474000D03*
X971500Y1467500D03*
X971700Y1457800D03*
Y1462300D03*
X972000Y1442000D03*
Y1437500D03*
X971700Y1448300D03*
Y1452800D03*
X962500Y1436500D03*
Y1441000D03*
X952800Y1437500D03*
Y1442000D03*
X962000Y1466500D03*
X966000Y1475000D03*
X952300Y1467500D03*
X958800Y1472500D03*
X962200Y1447300D03*
Y1451800D03*
X952500Y1448300D03*
Y1452800D03*
X962200Y1456800D03*
Y1461300D03*
X952500Y1457800D03*
Y1462300D03*
X992500Y1397300D03*
X964400Y1409700D03*
X946700Y1426500D03*
X994200Y1421500D03*
X924999Y1471050D03*
X926499Y1456550D03*
X925499Y1435550D03*
X925999Y1397050D03*
X925499Y1416550D03*
X972549Y1502300D03*
Y1506800D03*
X973500Y1483000D03*
Y1478500D03*
X973200Y1488300D03*
X972700Y1497300D03*
X966000Y1479500D03*
Y1484000D03*
X958800Y1477000D03*
Y1481500D03*
X965700Y1489300D03*
X960200Y1495300D03*
X958500Y1486800D03*
X951500Y1495300D03*
X960049Y1500300D03*
X951349D03*
X960049Y1504800D03*
X951349D03*
X973200Y1516400D03*
X972500Y1529100D03*
X966600D03*
X961400Y1528700D03*
X961900Y1522400D03*
X967100Y1522800D03*
X973000D03*
X962100Y1516000D03*
X967300Y1516400D03*
X972700Y1534800D03*
X972000Y1547500D03*
X966100D03*
X960900Y1547100D03*
X961400Y1540800D03*
X966600Y1541200D03*
X972500D03*
X961600Y1534400D03*
X966800Y1534800D03*
X972700Y1553300D03*
X961600Y1552900D03*
X966800Y1553300D03*
X944000Y1511300D03*
X943199Y1531650D03*
X924499Y1541550D03*
X924999Y1503050D03*
X924499Y1522550D03*
X924999Y1485550D03*
X972000Y1566000D03*
X966100D03*
X960900Y1565600D03*
X961400Y1559300D03*
X966600Y1559700D03*
X972500D03*
X973000Y1572800D03*
X972300Y1585500D03*
X966400D03*
X961200Y1585100D03*
X961700Y1578800D03*
X966900Y1579200D03*
X972800D03*
X961900Y1572400D03*
X967100Y1572800D03*
X972400Y1592000D03*
X966500D03*
X961300Y1591600D03*
X972200Y1598400D03*
X966300D03*
X961100Y1598000D03*
X960600Y1604300D03*
X971700Y1604700D03*
X965800D03*
X944499Y1632650D03*
X925599Y1612050D03*
X933199Y1577550D03*
X925499Y1562550D03*
X950100Y1626100D03*
X989999Y1718050D03*
X958799Y1715750D03*
X957799Y1646950D03*
X955499Y1690850D03*
X941499Y1679550D03*
X940499Y1656950D03*
X931499Y1702050D03*
X941800Y1787700D03*
X934200Y1793500D03*
X993299Y1734350D03*
X994999Y1748950D03*
X976600Y1757100D03*
X965349Y1742000D03*
X949799Y1756250D03*
X976399Y1772250D03*
X954499Y1783550D03*
X941499Y1776250D03*
X932199Y1801850D03*
X971000Y1803000D03*
X999999Y1775250D03*
X976399Y1791150D03*
X993499Y1805550D03*
X928000Y1818500D03*
X1003599Y1846650D03*
X995699Y1858950D03*
X971500Y1871500D03*
X937199Y1869950D03*
X993499Y1824550D03*
Y1833550D03*
X987999Y1971950D03*
Y1949050D03*
X1000999Y1946350D03*
X991999Y1915750D03*
X966799Y1892150D03*
X974699Y1914450D03*
X945199Y1946350D03*
X955799Y1951950D03*
X954099Y1915450D03*
X938199Y1917150D03*
X1002500Y1953500D03*
X1001599Y1921450D03*
X992299Y1929050D03*
X989999Y1962650D03*
X980999Y1933350D03*
X947499Y1936050D03*
X946199Y1966650D03*
X937499Y1893850D03*
X971499Y1956050D03*
Y1965050D03*
Y1937050D03*
X930999Y1950050D03*
X931499Y1962050D03*
X930999Y1931050D03*
X955499Y1893050D03*
Y1902050D03*
X953799Y1977950D03*
X930199Y1979550D03*
X1005000Y1980500D03*
X994999Y1986550D03*
X973999D03*
X956499Y1986050D03*
X936999Y1986550D03*
X1022000Y15500D03*
X1013499Y6550D03*
X1020499Y50550D03*
X1020999Y33050D03*
X1010599Y115550D03*
X1020499Y122550D03*
X1020999Y105050D03*
Y85550D03*
Y70050D03*
X1021499Y141050D03*
X1020999Y230550D03*
X1021499Y213050D03*
Y193550D03*
Y178050D03*
X1020999Y158550D03*
Y304550D03*
Y289050D03*
X1020499Y269550D03*
X1020999Y252050D03*
X1020499Y341550D03*
X1020999Y324050D03*
X1020499Y391550D03*
X1020999Y374050D03*
X1007299Y432450D03*
Y414950D03*
Y400450D03*
X1020499Y463550D03*
X1020999Y446050D03*
Y426550D03*
Y411050D03*
X1021999Y558550D03*
Y539050D03*
Y523550D03*
X1021499Y504050D03*
X1021999Y486550D03*
X1021499Y576050D03*
X1020999Y642550D03*
X1020499Y623050D03*
X1020999Y605550D03*
X1020499Y695050D03*
X1020999Y677550D03*
Y658050D03*
Y720050D03*
X1020499Y809550D03*
X1020999Y792050D03*
Y772550D03*
Y757050D03*
X1020499Y737550D03*
Y880550D03*
Y865050D03*
X1019999Y845550D03*
X1020499Y828050D03*
X1019999Y917550D03*
X1020499Y900050D03*
X1019999Y971050D03*
X1019499Y951550D03*
X1019999Y934050D03*
Y986550D03*
Y1058550D03*
Y1043050D03*
X1019499Y1023550D03*
X1019999Y1006050D03*
X1020499Y1134050D03*
Y1118550D03*
X1019999Y1099050D03*
X1020499Y1081550D03*
X1019499Y1198550D03*
Y1183050D03*
X1018999Y1163550D03*
X1019499Y1146050D03*
X1016999Y1219050D03*
X1016499Y1301050D03*
Y1236550D03*
X1016999Y1256050D03*
Y1271550D03*
X1023300Y1344400D03*
X1024300Y1365200D03*
X1022599Y1322950D03*
X1024300Y1393600D03*
X1008599Y1716050D03*
X1022299Y1715750D03*
X1008999Y1702450D03*
X1016899Y1731650D03*
X1026899Y1768550D03*
X1020299Y1746650D03*
X1015299Y1765950D03*
X1009999Y1797450D03*
X1022499Y1802050D03*
X1022999Y1784550D03*
X1011299Y1860650D03*
X1007599Y1818450D03*
X1022999Y1821550D03*
Y1837050D03*
X1020499Y1877550D03*
X1020999Y1860050D03*
Y1912550D03*
Y1897050D03*
X1017499Y1954550D03*
X1017999Y1937050D03*
Y1987050D03*
X1023000Y1973000D03*
G54D21*
X28000Y83750D03*
Y102250D03*
X27500Y921250D03*
Y902750D03*
X18500Y1067750D03*
Y1086250D03*
X42600Y1886050D03*
Y1867550D03*
X117999Y1143550D03*
Y1162050D03*
G54D40*
X84999Y1121050D03*
Y1126050D03*
Y1131050D03*
Y1136050D03*
X173999Y430050D03*
Y435050D03*
Y440050D03*
Y445050D03*
X104999Y1136050D03*
Y1131050D03*
Y1126050D03*
Y1121050D03*
X158499Y1226113D03*
Y1221113D03*
Y1216113D03*
X138499D03*
Y1221113D03*
Y1226113D03*
X158499Y1231113D03*
X138499D03*
X168499Y1625613D03*
Y1630613D03*
Y1635613D03*
Y1640613D03*
X253998Y295114D03*
Y300114D03*
Y305114D03*
Y310114D03*
X193999Y445050D03*
Y440050D03*
Y435050D03*
Y430050D03*
X254499Y701550D03*
Y706550D03*
Y711550D03*
Y716550D03*
X218499Y843613D03*
Y838613D03*
Y833613D03*
Y828613D03*
X198499D03*
Y833613D03*
Y838613D03*
Y843613D03*
X252999Y1513050D03*
Y1518050D03*
Y1523050D03*
Y1528050D03*
X188499Y1640613D03*
Y1635613D03*
Y1630613D03*
Y1625613D03*
X255777Y1917191D03*
Y1922191D03*
Y1927191D03*
Y1932191D03*
X273998Y310114D03*
Y305114D03*
Y300114D03*
Y295114D03*
X279999Y351050D03*
Y356050D03*
Y361050D03*
Y366050D03*
X299999D03*
Y361050D03*
Y356050D03*
Y351050D03*
X274499Y716550D03*
Y711550D03*
Y706550D03*
Y701550D03*
X280999Y757550D03*
Y762550D03*
Y767550D03*
Y772550D03*
X300999D03*
Y767550D03*
Y762550D03*
Y757550D03*
X272999Y1528050D03*
Y1523050D03*
Y1518050D03*
Y1513050D03*
X279999Y1568550D03*
Y1573550D03*
Y1578550D03*
Y1583550D03*
X299999D03*
Y1578550D03*
Y1573550D03*
Y1568550D03*
X275777Y1932191D03*
Y1927191D03*
Y1922191D03*
Y1917191D03*
X279777Y1961191D03*
Y1966191D03*
Y1971191D03*
X299777D03*
Y1966191D03*
Y1961191D03*
X279777Y1976191D03*
X299777D03*
X356499Y21550D03*
Y26550D03*
Y31550D03*
Y36550D03*
X376499D03*
Y31550D03*
Y26550D03*
Y21550D03*
X802873Y292471D03*
Y297471D03*
Y302471D03*
Y307471D03*
X822873D03*
Y302471D03*
Y297471D03*
Y292471D03*
X797978Y356924D03*
Y351924D03*
Y346924D03*
Y341924D03*
X777978D03*
Y346924D03*
Y351924D03*
Y356924D03*
X800831Y696853D03*
Y701853D03*
Y706853D03*
Y711853D03*
X820831D03*
Y706853D03*
Y701853D03*
Y696853D03*
X796696Y757382D03*
Y752382D03*
Y747382D03*
Y742382D03*
X776696D03*
Y747382D03*
Y752382D03*
Y757382D03*
X800841Y1101216D03*
Y1106216D03*
Y1111216D03*
Y1116216D03*
X820841D03*
Y1111216D03*
Y1106216D03*
Y1101216D03*
X796833Y1143892D03*
X776833D03*
X796833Y1158892D03*
Y1153892D03*
Y1148892D03*
X776833D03*
Y1153892D03*
Y1158892D03*
X802245Y1503722D03*
Y1508722D03*
Y1513722D03*
Y1518722D03*
X822245D03*
Y1513722D03*
Y1508722D03*
Y1503722D03*
X799327Y1553796D03*
Y1548796D03*
X779327D03*
Y1553796D03*
X799327Y1563796D03*
Y1558796D03*
X779327D03*
Y1563796D03*
X801436Y1910365D03*
Y1915365D03*
Y1920365D03*
Y1925365D03*
X821436D03*
Y1920365D03*
Y1915365D03*
Y1910365D03*
X796814Y1969713D03*
Y1964713D03*
Y1959713D03*
Y1954713D03*
X776814D03*
Y1959713D03*
Y1964713D03*
Y1969713D03*
G54D22*
X77166Y114212D03*
Y117362D03*
Y120511D03*
Y123661D03*
Y126811D03*
Y129960D03*
Y133110D03*
Y519724D03*
Y522874D03*
Y526023D03*
Y529173D03*
Y532323D03*
Y535472D03*
Y538622D03*
Y925236D03*
Y928386D03*
Y931535D03*
Y934685D03*
Y937835D03*
Y940984D03*
Y944134D03*
Y1330748D03*
Y1333898D03*
Y1337047D03*
Y1340197D03*
Y1343347D03*
Y1346496D03*
Y1349646D03*
Y1736260D03*
Y1739410D03*
Y1742559D03*
Y1745709D03*
Y1748859D03*
Y1752008D03*
Y1755158D03*
X159055Y255866D03*
Y252716D03*
Y249567D03*
Y246417D03*
Y243267D03*
Y240118D03*
Y236968D03*
Y645630D03*
Y642480D03*
Y661378D03*
Y658228D03*
Y655079D03*
Y651929D03*
Y648779D03*
Y1060591D03*
Y1057441D03*
Y1054291D03*
Y1051142D03*
Y1047992D03*
Y1066890D03*
Y1063740D03*
Y1472402D03*
Y1469252D03*
Y1466103D03*
Y1462953D03*
Y1459803D03*
Y1456654D03*
Y1453504D03*
Y1877914D03*
Y1874764D03*
Y1871615D03*
Y1868465D03*
Y1865315D03*
Y1862166D03*
Y1859016D03*
X887401Y255866D03*
Y252716D03*
Y249567D03*
Y246417D03*
Y243267D03*
Y240118D03*
Y236968D03*
Y645630D03*
Y642480D03*
Y661378D03*
Y658228D03*
Y655079D03*
Y651929D03*
Y648779D03*
Y1060591D03*
Y1057441D03*
Y1054291D03*
Y1051142D03*
Y1047992D03*
Y1066890D03*
Y1063740D03*
Y1472402D03*
Y1469252D03*
Y1466103D03*
Y1462953D03*
Y1459803D03*
Y1456654D03*
Y1453504D03*
Y1877914D03*
Y1874764D03*
Y1871615D03*
Y1868465D03*
Y1865315D03*
Y1862166D03*
Y1859016D03*
G54D31*
X46800Y408900D03*
X42900Y601400D03*
X30499Y1588660D03*
X23999Y1964850D03*
X31999Y1918850D03*
X27999Y1964850D03*
X174999Y71350D03*
X141499Y440413D03*
X146499D03*
X159199Y517150D03*
X167199D03*
X174199D03*
X136000Y528800D03*
X170499Y808913D03*
X166499D03*
X167499Y833413D03*
X172499D03*
X119000Y1133300D03*
X119499Y1106350D03*
X100500Y1103800D03*
X106999Y1223913D03*
X111999D03*
X109499Y1198413D03*
X105499D03*
X103999Y1468600D03*
X111499D03*
X115599Y1468550D03*
X152600Y1681200D03*
X135999Y1703350D03*
X131999D03*
X209499Y97850D03*
X217499D03*
X201499D03*
X185499Y117350D03*
X188000Y420800D03*
X211500Y819300D03*
X203500D03*
X184600Y1373100D03*
X180500D03*
X192800Y1651100D03*
X223436Y1893665D03*
X315000Y370300D03*
X313500Y1970300D03*
X644049Y1803934D03*
Y1792934D03*
X752978Y335724D03*
X751196Y735182D03*
X751499Y1140350D03*
X753827Y1543596D03*
X710549Y1797934D03*
X708549Y1808634D03*
X751000Y1947300D03*
X816499Y159350D03*
X823999D03*
X831499D03*
X765000Y352300D03*
X771500Y337800D03*
X826100Y666700D03*
X766000Y751300D03*
X770000Y738800D03*
X769500Y1141800D03*
X763000Y1155300D03*
X772000Y1545800D03*
X766500Y1558300D03*
X833499Y1780350D03*
X814999D03*
X824499D03*
X828000Y1881300D03*
X765000Y1960800D03*
X770000Y1949300D03*
X916499Y108350D03*
X900499Y84850D03*
X903499Y128350D03*
X940499Y108350D03*
X944499D03*
X924499D03*
X932499D03*
X952499D03*
G54D13*
X12560Y231121D03*
Y227184D03*
Y223247D03*
Y211435D03*
Y207498D03*
Y203561D03*
Y199624D03*
Y195687D03*
Y191750D03*
Y187813D03*
Y183876D03*
Y179939D03*
Y176002D03*
Y172065D03*
Y246869D03*
Y242932D03*
Y238995D03*
Y235058D03*
X12569Y372041D03*
Y375978D03*
Y379915D03*
Y383852D03*
Y387789D03*
Y391726D03*
Y395663D03*
Y399600D03*
Y403537D03*
Y407474D03*
Y411411D03*
Y431098D03*
Y427161D03*
Y423223D03*
Y435035D03*
Y438972D03*
Y442909D03*
Y446846D03*
Y450783D03*
Y454720D03*
Y458657D03*
Y462594D03*
Y466531D03*
Y470468D03*
Y474405D03*
Y478342D03*
Y482279D03*
Y486216D03*
Y490153D03*
Y494090D03*
Y498027D03*
Y501964D03*
Y505901D03*
Y509838D03*
Y513775D03*
Y517712D03*
Y521649D03*
Y525586D03*
Y529523D03*
Y533460D03*
Y537397D03*
Y541334D03*
Y545271D03*
Y549208D03*
Y553145D03*
Y557082D03*
Y561019D03*
Y564956D03*
Y568893D03*
Y572830D03*
Y576767D03*
Y580704D03*
Y584641D03*
Y588578D03*
Y592515D03*
Y596452D03*
Y600389D03*
Y604326D03*
Y608263D03*
Y612200D03*
Y616137D03*
Y620074D03*
Y624011D03*
Y627948D03*
Y631885D03*
Y635822D03*
Y639759D03*
Y643696D03*
Y647633D03*
Y651570D03*
Y655507D03*
Y659444D03*
Y671255D03*
Y667318D03*
Y663381D03*
Y675192D03*
Y679129D03*
Y683066D03*
Y690940D03*
Y687003D03*
Y694877D03*
Y698814D03*
X12560Y813010D03*
Y809073D03*
Y805136D03*
Y801199D03*
Y797262D03*
Y793325D03*
Y789388D03*
Y785451D03*
Y781514D03*
Y856318D03*
Y852381D03*
Y848444D03*
Y844507D03*
Y840570D03*
Y836633D03*
Y832696D03*
Y820884D03*
Y816947D03*
Y1223247D03*
Y1219310D03*
Y1215373D03*
Y1211436D03*
Y1207499D03*
Y1195687D03*
Y1191750D03*
Y1187813D03*
Y1183876D03*
Y1179939D03*
Y1176002D03*
Y1172065D03*
Y1168128D03*
Y1164191D03*
Y1160254D03*
Y1156317D03*
Y1231121D03*
Y1227184D03*
X12569Y1356293D03*
Y1360230D03*
Y1364167D03*
Y1368104D03*
Y1372041D03*
Y1375978D03*
Y1379915D03*
Y1383852D03*
Y1387789D03*
Y1391726D03*
Y1395663D03*
Y1415350D03*
Y1411413D03*
Y1407475D03*
Y1419287D03*
Y1423224D03*
Y1427161D03*
Y1431098D03*
Y1435035D03*
Y1438972D03*
Y1442909D03*
Y1446846D03*
Y1450783D03*
Y1454720D03*
Y1458657D03*
Y1462594D03*
Y1466531D03*
Y1470468D03*
Y1474405D03*
Y1478342D03*
Y1482279D03*
Y1486216D03*
Y1490153D03*
Y1494090D03*
Y1498027D03*
Y1501964D03*
Y1505901D03*
Y1509838D03*
Y1513775D03*
Y1517712D03*
Y1521649D03*
Y1525586D03*
Y1529523D03*
Y1533460D03*
Y1537397D03*
Y1541334D03*
Y1545271D03*
Y1549208D03*
Y1553145D03*
Y1557082D03*
Y1561019D03*
Y1564956D03*
Y1568893D03*
Y1572830D03*
Y1576767D03*
Y1580704D03*
Y1584641D03*
Y1588578D03*
Y1592515D03*
Y1596452D03*
Y1600389D03*
Y1604326D03*
Y1608263D03*
Y1612200D03*
Y1616137D03*
Y1620074D03*
Y1624011D03*
Y1627948D03*
Y1631885D03*
Y1635822D03*
Y1639759D03*
Y1643696D03*
Y1655507D03*
Y1651570D03*
Y1647633D03*
Y1659444D03*
Y1663381D03*
Y1667318D03*
Y1675192D03*
Y1671255D03*
Y1679129D03*
Y1683066D03*
X12560Y1805136D03*
Y1801199D03*
Y1797262D03*
Y1793325D03*
Y1789388D03*
Y1785451D03*
Y1781514D03*
Y1777577D03*
Y1773640D03*
Y1769703D03*
Y1765766D03*
Y1840570D03*
Y1836633D03*
Y1832696D03*
Y1828759D03*
Y1824822D03*
Y1820885D03*
Y1816948D03*
G54D32*
X42700Y408900D03*
X34000Y1058300D03*
X83000Y1548300D03*
X79000D03*
X34599Y1588650D03*
X75000Y1565200D03*
X79000D03*
X31999Y1964850D03*
X19999D03*
X27030Y1925238D03*
X49499Y1901850D03*
X23030Y1925238D03*
X31999Y1972350D03*
X162999Y443913D03*
X150999Y440413D03*
X176499Y833413D03*
X127000Y1133300D03*
X100500Y1111800D03*
X97499Y1086850D03*
X101999D03*
X127499Y1224413D03*
X116499Y1223913D03*
Y1321413D03*
X120507Y1321496D03*
X116749Y1510150D03*
X112599D03*
X174499Y1649663D03*
X205499Y97850D03*
X197499D03*
X185999Y496450D03*
X181899D03*
X185999Y842413D03*
X190499D03*
X205999Y898313D03*
X209999D03*
X226800Y1086600D03*
X247500Y1078550D03*
X225499Y1499350D03*
X203000Y1637800D03*
X231000Y1880500D03*
X236100Y1893900D03*
X307000Y370300D03*
X280499Y341850D03*
X284999D03*
X311000Y771300D03*
X281499Y748350D03*
X285499D03*
X310500Y1582800D03*
X278499Y1559350D03*
X282499D03*
X330000Y1969800D03*
X284358Y1951628D03*
X288358D03*
X363000Y42800D03*
X399999Y39350D03*
X640049Y1803934D03*
Y1792934D03*
X649049Y1810934D03*
X655549Y1815434D03*
X749500Y348300D03*
X750500Y747800D03*
X747500Y1151800D03*
X751000Y1553800D03*
X744049Y1802934D03*
Y1795434D03*
X706549Y1797934D03*
X744049Y1810434D03*
X712549Y1808634D03*
X749500Y1958300D03*
X833999Y204850D03*
X829499D03*
X827500Y267500D03*
X825700Y1075800D03*
X827700Y1480700D03*
X912499Y108350D03*
X920499D03*
X889700Y1704700D03*
X936499Y108350D03*
X948499D03*
G54D50*
X37999Y1968750D03*
X65768Y1966462D03*
X74568D03*
X83568D03*
X57068D03*
X92568D03*
X37999Y1976350D03*
X65768Y1974062D03*
X74568D03*
X83568D03*
X57068D03*
X92568D03*
X240999Y89850D03*
Y82250D03*
G54D14*
X13700Y1117000D03*
Y1109000D03*
X27300Y134000D03*
X19700D03*
X27300Y126000D03*
X19700D03*
X51700Y739000D03*
X59300D03*
X21300Y1117000D03*
Y1109000D03*
X104099Y1597150D03*
X111699D03*
X232199Y33550D03*
X239799D03*
X232199Y51550D03*
X239799D03*
X232199Y42550D03*
X239799D03*
X232199Y60550D03*
X239799D03*
X232199Y69550D03*
X239799D03*
X951199Y46050D03*
X958799D03*
X951199Y64050D03*
X958799D03*
X951199Y55050D03*
X958799D03*
X949199Y101550D03*
X956799D03*
X951199Y73050D03*
X958799D03*
X951199Y82050D03*
X958799D03*
G54D41*
X72999Y1871550D03*
Y1882550D03*
X63999Y1871050D03*
Y1882050D03*
X169999Y123550D03*
Y112550D03*
X178999Y123550D03*
Y112550D03*
X158999Y453113D03*
Y464113D03*
X149999Y453113D03*
Y464113D03*
X140999Y453113D03*
Y464113D03*
X167900Y453100D03*
Y464100D03*
X146499Y486613D03*
Y497613D03*
X178999Y851613D03*
Y862613D03*
X169999Y851613D03*
Y862613D03*
X169499Y885113D03*
Y896113D03*
X129900Y1182500D03*
Y1171500D03*
X102999Y1182550D03*
Y1171550D03*
X111999Y1182550D03*
Y1171550D03*
X120999Y1182550D03*
Y1171550D03*
X132700Y1265400D03*
Y1254400D03*
X129499Y1233613D03*
Y1244613D03*
X120499Y1233613D03*
Y1244613D03*
X111499Y1233613D03*
Y1244613D03*
Y1266613D03*
Y1277613D03*
X126199Y1638013D03*
X117500Y1638000D03*
X108799Y1638013D03*
X133999Y1670613D03*
Y1659613D03*
X126199Y1649013D03*
X117500Y1649000D03*
X108799Y1649013D03*
X112499Y1671613D03*
Y1682613D03*
X225900Y307400D03*
X246498Y319114D03*
Y330114D03*
X237698Y351614D03*
Y340614D03*
X228998Y351614D03*
Y340614D03*
X220298Y351614D03*
Y340614D03*
X225900Y318400D03*
X246499Y726050D03*
X225499D03*
Y715050D03*
X246499Y737050D03*
X238699Y760550D03*
Y749550D03*
X229999Y760550D03*
Y749550D03*
X221299Y760550D03*
Y749550D03*
X191499Y884113D03*
Y873113D03*
X187999Y851613D03*
Y862613D03*
X224300Y1130200D03*
Y1119200D03*
X246499Y1535550D03*
Y1546550D03*
X237700Y1557100D03*
X229000D03*
X220300D03*
X224999Y1535550D03*
Y1524550D03*
X237700Y1568100D03*
X229000D03*
X220300D03*
X246314Y1934113D03*
Y1945113D03*
X220300Y1964600D03*
Y1953600D03*
X229000Y1964600D03*
Y1953600D03*
X237700Y1964600D03*
Y1953600D03*
X225814Y1931113D03*
Y1920113D03*
X322499Y54613D03*
Y43613D03*
X314099Y22113D03*
Y33113D03*
X305099Y22113D03*
Y33113D03*
X296099Y22113D03*
Y33113D03*
X300999Y55613D03*
Y66613D03*
X832978Y313424D03*
Y324424D03*
X840800Y346800D03*
Y335800D03*
X830499Y715550D03*
Y726550D03*
X838796Y747582D03*
Y736582D03*
X830499Y1119550D03*
Y1130550D03*
X838833Y1141392D03*
Y1152392D03*
X833827Y1523796D03*
Y1534796D03*
X841500Y1556300D03*
Y1545300D03*
X840400Y1965000D03*
Y1954000D03*
X832499Y1930050D03*
Y1941050D03*
X846999Y135550D03*
Y124550D03*
X896999Y136550D03*
Y125550D03*
X850999Y312550D03*
Y301550D03*
X849500Y346800D03*
Y335800D03*
X858200Y346800D03*
Y335800D03*
X848696Y713882D03*
Y702882D03*
X847496Y747582D03*
Y736582D03*
X856196Y747582D03*
Y736582D03*
X847533Y1141392D03*
X856233D03*
X848413Y1118613D03*
Y1107613D03*
X847533Y1152392D03*
X856233D03*
X850200Y1556300D03*
Y1545300D03*
X858900Y1556300D03*
Y1545300D03*
X850827Y1523296D03*
Y1512296D03*
X849100Y1965000D03*
Y1954000D03*
X857800Y1965000D03*
Y1954000D03*
X850314Y1929113D03*
Y1918113D03*
G54D23*
X71773Y209631D03*
Y206431D03*
X66023Y209631D03*
Y206431D03*
X71773Y615143D03*
Y611943D03*
X66023Y615143D03*
Y611943D03*
X71773Y1020655D03*
Y1017455D03*
X66023Y1020655D03*
Y1017455D03*
X71773Y1426167D03*
Y1422967D03*
X66023Y1426167D03*
Y1422967D03*
X71773Y1831679D03*
Y1828479D03*
X66023Y1831679D03*
Y1828479D03*
X164448Y160447D03*
Y163647D03*
X170198Y160447D03*
Y163647D03*
X164448Y565959D03*
Y569159D03*
X170198Y565959D03*
Y569159D03*
X164448Y971471D03*
Y974671D03*
X170198Y971471D03*
Y974671D03*
X164448Y1376983D03*
Y1380183D03*
X170198Y1376983D03*
Y1380183D03*
X164448Y1782494D03*
Y1785694D03*
X170198Y1782494D03*
Y1785694D03*
X892794Y160447D03*
Y163647D03*
X898544Y160447D03*
Y163647D03*
X892794Y565959D03*
Y569159D03*
X898544Y565959D03*
Y569159D03*
X892794Y971471D03*
Y974671D03*
X898544Y971471D03*
Y974671D03*
X892794Y1376983D03*
Y1380183D03*
X898544Y1376983D03*
Y1380183D03*
X892794Y1782494D03*
Y1785694D03*
X898544Y1782494D03*
Y1785694D03*
G54D33*
X42700Y412300D03*
X34000Y1061700D03*
X83000Y1551700D03*
X79000D03*
X34599Y1592050D03*
X75000Y1568600D03*
X79000D03*
X31999Y1968250D03*
X19999D03*
X27030Y1928638D03*
X49499Y1905250D03*
X23030Y1928638D03*
X31999Y1975750D03*
X162999Y447313D03*
X150999Y443813D03*
X176499Y836813D03*
X127000Y1136700D03*
X100500Y1115200D03*
X97499Y1090250D03*
X101999D03*
X127499Y1227813D03*
X116499Y1227313D03*
Y1324813D03*
X120507Y1324896D03*
X116749Y1513550D03*
X112599D03*
X174499Y1653063D03*
X205499Y101250D03*
X197499D03*
X185999Y499850D03*
X181899D03*
X185999Y845813D03*
X190499D03*
X205999Y901713D03*
X209999D03*
X226800Y1090000D03*
X247500Y1081950D03*
X225499Y1502750D03*
X203000Y1641200D03*
X231000Y1883900D03*
X236100Y1897300D03*
X307000Y373700D03*
X280499Y345250D03*
X284999D03*
X311000Y774700D03*
X281499Y751750D03*
X285499D03*
X310500Y1586200D03*
X278499Y1562750D03*
X282499D03*
X284358Y1955028D03*
X288358D03*
X330000Y1973200D03*
X363000Y46200D03*
X399999Y42750D03*
X640049Y1796334D03*
X649049Y1814334D03*
X655549Y1818834D03*
X640049Y1807334D03*
X749500Y351700D03*
X750500Y751200D03*
X747500Y1155200D03*
X751000Y1557200D03*
X744049Y1798834D03*
X706549Y1801334D03*
X744049Y1813834D03*
Y1806334D03*
X712549Y1812034D03*
X749500Y1961700D03*
X833999Y208250D03*
X829499D03*
X827500Y270900D03*
X825700Y1079200D03*
X827700Y1484100D03*
X912499Y111750D03*
X920499D03*
X889700Y1708100D03*
X936499Y111750D03*
X948499D03*
G54D42*
X43999Y1964750D03*
X138999Y517313D03*
X161999Y915813D03*
X123000Y1133200D03*
X142667Y1306460D03*
X132999Y1306813D03*
X103499Y1297813D03*
X178500Y1697700D03*
X104999Y1702063D03*
X137504Y1735523D03*
X123999Y1734813D03*
X182499Y71250D03*
X194500Y499200D03*
X236000Y908200D03*
X215900Y896900D03*
X199000Y1637700D03*
X292999Y86313D03*
X311000Y370200D03*
X295500Y329200D03*
X307000Y771200D03*
X298000Y735700D03*
X297000Y1549800D03*
X327000Y1570700D03*
X306500Y1582700D03*
X309300Y1970276D03*
X296858Y1944028D03*
X367000Y42700D03*
X389500Y72200D03*
X369300Y72300D03*
X693549Y1813334D03*
X770000Y751200D03*
X907999Y84750D03*
X870201Y1709850D03*
G54D51*
X44368Y1946712D03*
G54D60*
X158299Y438173D03*
Y435613D03*
Y433053D03*
X165699D03*
Y435613D03*
Y438173D03*
X113499Y1106640D03*
Y1109200D03*
Y1111760D03*
X106099D03*
Y1109200D03*
Y1106640D03*
X123299Y1218673D03*
Y1216113D03*
Y1213553D03*
X130699D03*
Y1216113D03*
Y1218673D03*
X147400Y1324540D03*
Y1327100D03*
Y1329660D03*
X140000D03*
Y1327100D03*
Y1324540D03*
X181799Y836673D03*
Y834113D03*
Y831553D03*
X189199D03*
Y834113D03*
Y836673D03*
X242000Y1069000D03*
Y1071560D03*
Y1074120D03*
X234600D03*
Y1071560D03*
Y1069000D03*
X233600Y1473240D03*
X241000D03*
X233600Y1478360D03*
Y1475800D03*
X241000D03*
Y1478360D03*
X179999Y1652987D03*
Y1650427D03*
Y1647867D03*
X187399D03*
Y1650427D03*
Y1652987D03*
X218100Y1882960D03*
Y1880400D03*
Y1877840D03*
X225500D03*
Y1880400D03*
Y1882960D03*
X324800Y92340D03*
Y94900D03*
Y97460D03*
X317400D03*
Y94900D03*
Y92340D03*
X394199Y36490D03*
Y39050D03*
Y41610D03*
X386799D03*
Y39050D03*
Y36490D03*
X758778Y341984D03*
Y339424D03*
Y336864D03*
X756996Y742442D03*
Y739882D03*
Y737322D03*
X756799Y1141490D03*
Y1146610D03*
Y1144050D03*
X757114Y1954773D03*
Y1952213D03*
Y1949653D03*
X814700Y270060D03*
Y267500D03*
Y264940D03*
X822100D03*
Y267500D03*
Y270060D03*
X766178Y336864D03*
Y339424D03*
Y341984D03*
X813200Y672660D03*
Y670100D03*
Y667540D03*
X820600D03*
Y670100D03*
Y672660D03*
X764396Y737322D03*
Y739882D03*
Y742442D03*
X764199Y1141490D03*
X812900Y1075460D03*
Y1072900D03*
Y1070340D03*
X820300D03*
Y1072900D03*
Y1075460D03*
X764199Y1144050D03*
Y1146610D03*
X759127Y1549356D03*
Y1546796D03*
Y1544236D03*
X766527D03*
Y1546796D03*
Y1549356D03*
X814700Y1483160D03*
Y1480600D03*
Y1478040D03*
X822100D03*
Y1480600D03*
Y1483160D03*
X815300Y1887560D03*
Y1885000D03*
Y1882440D03*
X822700D03*
Y1885000D03*
Y1887560D03*
X764514Y1949653D03*
Y1952213D03*
Y1954773D03*
G54D24*
X55799Y203550D03*
X77799Y204550D03*
X55799Y207550D03*
X77799Y208550D03*
X55799Y211550D03*
X77801Y611450D03*
Y615450D03*
X31299Y611550D03*
X56299Y1017050D03*
X81300Y1008500D03*
X56236Y1021050D03*
Y1025050D03*
X73799Y1837550D03*
X82549Y1828613D03*
X74049Y1843113D03*
X82549Y1832613D03*
X73799Y1849050D03*
X18299Y1948050D03*
Y1952050D03*
Y1940050D03*
X52299Y1897050D03*
X148299Y517613D03*
X155999Y524850D03*
X163499D03*
X170999D03*
X143800Y545000D03*
X171299Y916113D03*
X105550Y972000D03*
X105499Y967850D03*
X124780Y1098482D03*
Y1094482D03*
X112799Y1298113D03*
X128300Y1361000D03*
X138700Y1335800D03*
X127799Y1342050D03*
X100549Y1476050D03*
X108049D03*
X114049Y1702613D03*
X170800Y1691200D03*
X230299Y105050D03*
X238299Y95550D03*
X230172Y92572D03*
X179472Y90572D03*
Y86572D03*
X183199Y152000D03*
X226298Y287114D03*
X240600Y269700D03*
X183199Y559300D03*
X226299Y693550D03*
X240000Y677100D03*
X183699Y963100D03*
X199199Y1367400D03*
X182699Y1773200D03*
X302299Y86613D03*
X316200Y105200D03*
X305299Y334050D03*
Y339050D03*
X329798Y337114D03*
Y333114D03*
X315000Y365200D03*
X312300Y779000D03*
X306799Y742050D03*
Y746050D03*
X331299Y745050D03*
Y741050D03*
X316000Y772200D03*
X303299Y1554550D03*
X327799Y1557550D03*
Y1553550D03*
X312800Y1591000D03*
X314800Y1587000D03*
X303299Y1558550D03*
X315000Y1582600D03*
X310521Y1944909D03*
Y1948909D03*
X336021Y1947409D03*
Y1943409D03*
X318200Y1971900D03*
X370800Y46500D03*
X375400Y42300D03*
X751278Y323924D03*
Y328924D03*
X749996Y724882D03*
Y729882D03*
X750633Y1126392D03*
Y1131392D03*
X753627Y1531296D03*
Y1536296D03*
X697349Y1801634D03*
Y1808634D03*
X750114Y1937713D03*
Y1942213D03*
X813299Y167050D03*
X820799D03*
X828299D03*
X797299Y336050D03*
Y332050D03*
X776299Y326550D03*
Y322550D03*
X774299Y724050D03*
Y728550D03*
X795799Y736050D03*
Y732050D03*
Y1133050D03*
Y1137050D03*
X775299Y1127550D03*
Y1123550D03*
X798481Y1538893D03*
Y1542893D03*
X777481Y1527893D03*
Y1531893D03*
X813799Y1788050D03*
X821299D03*
X828799D03*
X796981Y1944393D03*
Y1948393D03*
X774799Y1935050D03*
Y1939050D03*
X902299Y103050D03*
Y107050D03*
X845800Y276800D03*
X912699Y557800D03*
X844500Y677700D03*
X913199Y962100D03*
X844100Y1083200D03*
X869799Y1359550D03*
Y1367550D03*
Y1363550D03*
X846100Y1488100D03*
X912699Y1771700D03*
X846599Y1893850D03*
X927699Y158500D03*
G54D15*
G01X176749Y572050D02*
Y575550D01*
X198499Y597300D01*
X350499D01*
G01X176499Y976550D02*
Y995999D01*
X176691D01*
X254307Y1073615D01*
Y1090808D01*
X268499Y1105000D01*
Y1120999D01*
X282500Y1135000D01*
X8750Y1086250D03*
X8499Y1937550D03*
X5303Y1947050D03*
X11703Y1951946D03*
X93999Y58550D03*
X92900Y66128D03*
X89800Y132400D03*
X92999Y86128D03*
Y96128D03*
X74499Y84050D03*
Y80650D03*
X86899Y130567D03*
X86599Y126750D03*
X74999Y74050D03*
Y70550D03*
X78700Y70700D03*
Y74200D03*
X15750Y102250D03*
X41999Y200050D03*
X65999Y216050D03*
X95350Y204550D03*
X89800Y208550D03*
X24300Y247300D03*
X29699Y388484D03*
X29599Y382884D03*
X29999Y398684D03*
X23499Y397579D03*
X23399Y373931D03*
Y389679D03*
X23499Y381831D03*
X26299Y383854D03*
Y387629D03*
X28100Y374000D03*
X26492Y439350D03*
X26599Y442749D03*
X26299Y399601D03*
Y403376D03*
Y478404D03*
X26899Y454850D03*
X26515Y481798D03*
X45800Y405200D03*
X26799Y458497D03*
X26486Y462648D03*
X26499Y466250D03*
X64403Y471046D03*
X64397Y474446D03*
X26524Y426720D03*
X26399Y423322D03*
X29899Y404384D03*
X28900Y429200D03*
X29365Y421169D03*
X29500Y460800D03*
X28700Y451900D03*
X28800Y436700D03*
X28700Y445700D03*
X68000Y475600D03*
X67800Y469900D03*
X23499Y468447D03*
X23399Y476295D03*
Y444799D03*
X23499Y452699D03*
X23399Y460547D03*
Y429051D03*
X23499Y436951D03*
X23600Y405700D03*
X77499Y469550D03*
X61400Y452600D03*
X35900Y412600D03*
X65000Y455500D03*
X28900Y417800D03*
X39217Y554750D03*
X42867Y548450D03*
X43099Y555850D03*
X33699Y561850D03*
X46299Y552950D03*
X36499Y517775D03*
Y521550D03*
X26399Y501966D03*
Y505741D03*
X64600Y486300D03*
X64700Y489700D03*
X33307Y557938D03*
X26199Y547176D03*
X93200Y510500D03*
X83700Y529500D03*
X28600Y508500D03*
X35300Y524800D03*
X38400Y514900D03*
X88999Y538050D03*
X68900Y490600D03*
X68700Y485200D03*
X28600Y499300D03*
X26900Y532800D03*
X63499Y538550D03*
Y533050D03*
X22800Y539600D03*
X23499Y515691D03*
X23399Y523539D03*
X23499Y531439D03*
X23399Y492043D03*
X23499Y499943D03*
X23399Y507791D03*
X23499Y484195D03*
X77999Y493050D03*
X77499Y502550D03*
X29999Y557150D03*
X26599Y525648D03*
X95500Y513400D03*
X26599Y529302D03*
X60003Y534150D03*
X86199Y536025D03*
X59999Y537550D03*
X86199Y532250D03*
X65599Y514250D03*
X49799Y559150D03*
X68000Y546500D03*
X72500Y545000D03*
X27199Y539600D03*
X42202Y608195D03*
X39600Y626984D03*
X41400Y611500D03*
X42709Y625607D03*
X38300Y633800D03*
X41500Y642800D03*
X27499Y620203D03*
Y623857D03*
X36499Y566350D03*
X37999Y611550D03*
X42599Y567850D03*
X32800Y578200D03*
X47543Y578340D03*
X44959Y575756D03*
X30712Y624971D03*
X29999Y640550D03*
X60076Y595777D03*
X55499Y595650D03*
X29819Y634951D03*
X26869Y616861D03*
X23399Y641649D03*
X23499Y618053D03*
X23799Y625950D03*
X23499Y633801D03*
X23999Y609250D03*
X22978Y588571D03*
X22699Y577950D03*
X22999Y565550D03*
X57800Y634300D03*
X34976Y619250D03*
X44900Y642800D03*
X26568Y635950D03*
Y639604D03*
X47101Y632355D03*
X28000Y578500D03*
X25581Y567763D03*
X47626Y611300D03*
X45701Y607700D03*
X27699Y573750D03*
X82499Y627050D03*
X26800Y611500D03*
X41500Y635000D03*
X52500D03*
X48999Y642900D03*
X81251Y607249D03*
Y619251D03*
X28808Y593150D03*
X28700Y596549D03*
X32200Y603710D03*
X31598Y607102D03*
X80499Y664550D03*
X30999Y656250D03*
X29999Y694550D03*
X30999Y650550D03*
X81999Y668050D03*
X74499Y662050D03*
X25999Y694870D03*
X23999Y689050D03*
X23499Y665297D03*
X23699Y673150D03*
X23499Y681045D03*
Y649549D03*
X23725Y657471D03*
X78499Y654050D03*
X26737Y651957D03*
X26999Y656550D03*
X27687Y667447D03*
Y671101D03*
X76999Y664550D03*
X27700Y682700D03*
X50410Y695801D03*
X50300Y699200D03*
X44046Y799554D03*
X32800Y803050D03*
X46887Y803413D03*
X37416Y799033D03*
X37099Y811350D03*
X51100Y806300D03*
X49900Y813200D03*
X56281Y801350D03*
X27299Y783550D03*
X35300Y789375D03*
X90700Y792900D03*
X35559Y795112D03*
X45100Y793100D03*
X37216Y807951D03*
X76540Y850938D03*
X29299Y836901D03*
X75500Y847700D03*
X49300Y836500D03*
X46700Y820100D03*
X40400Y840792D03*
X89000Y816500D03*
X48346Y844529D03*
X58699Y837250D03*
X26299Y815050D03*
X92999Y868550D03*
X92499Y876550D03*
X68860Y838706D03*
X90000Y826000D03*
X54074Y815750D03*
X69499Y842950D03*
X62405Y820300D03*
X63499Y843050D03*
X90500Y831500D03*
X31699Y814350D03*
X65500Y817700D03*
X23299Y863050D03*
X26662Y861550D03*
X39649Y822000D03*
X80500Y817000D03*
X74220Y854150D03*
X72362Y849550D03*
X25000Y858100D03*
X46576Y832951D03*
X29600Y854000D03*
X24000Y853500D03*
X89400Y935400D03*
X89499Y942850D03*
X94999Y901550D03*
X85999Y940429D03*
X86399Y937050D03*
X29000Y896500D03*
X72000Y1013400D03*
X63273Y1023974D03*
X90000Y993100D03*
X92600Y996100D03*
X80699Y1004450D03*
Y1000450D03*
X20400Y1048300D03*
X66499Y1025050D03*
X75900Y1019100D03*
X63500Y1029600D03*
X88000Y1008500D03*
X75500Y1012261D03*
X80000Y1090500D03*
X80500Y1097550D03*
Y1104500D03*
X76999Y1196550D03*
X21817Y1156317D03*
X78499Y1273550D03*
X78613Y1282664D03*
X78779Y1302664D03*
X91279Y1340642D03*
X89999Y1348050D03*
X27499Y1387550D03*
X24499Y1389663D03*
X22851Y1374169D03*
X22999Y1366050D03*
X23700Y1354600D03*
X23499Y1381500D03*
X78779Y1312664D03*
X86165Y1339050D03*
X25507Y1372045D03*
X25558Y1368447D03*
X86890Y1346635D03*
Y1342860D03*
X28499Y1391050D03*
X32333Y1389383D03*
X20999Y1352050D03*
Y1320550D03*
X77758Y1357742D03*
X25000D03*
X30378Y1462518D03*
X33915Y1462681D03*
X32094Y1448448D03*
X28697Y1448296D03*
X33000Y1393000D03*
X33400Y1408100D03*
X36198Y1446749D03*
X26800Y1443800D03*
X30600Y1415100D03*
X30999Y1438050D03*
X27999Y1430050D03*
X29100Y1459200D03*
X34200Y1466200D03*
X23028Y1468579D03*
X23499Y1460550D03*
X22999Y1453050D03*
X23499Y1445050D03*
X22999Y1437050D03*
X23999Y1429050D03*
X23499Y1421550D03*
X23999Y1413550D03*
X32451Y1411468D03*
X28999Y1411550D03*
X33206Y1432352D03*
X30499Y1434550D03*
X30500Y1395500D03*
X76000Y1431100D03*
X34896Y1555730D03*
X34099Y1497550D03*
X30499D03*
X80043Y1544691D03*
X83932Y1544705D03*
X29631Y1533063D03*
X31999Y1517846D03*
Y1521500D03*
X46700Y1546793D03*
X34465Y1481683D03*
X30999Y1482050D03*
X44299Y1550950D03*
X96200Y1550100D03*
X32700Y1485200D03*
X28999Y1478050D03*
X27100Y1494300D03*
X34900Y1501000D03*
X35400Y1522200D03*
X35999Y1514550D03*
X29600Y1515300D03*
X24423Y1527123D03*
X22999Y1500050D03*
Y1515550D03*
X23799Y1508050D03*
X24499Y1492050D03*
X23599Y1476350D03*
X23277Y1484050D03*
X25247Y1546912D03*
X37999Y1530900D03*
X38500Y1534600D03*
X32099Y1535550D03*
X30115Y1511900D03*
X33512Y1512051D03*
X90324Y1538800D03*
X26705Y1534795D03*
X30199Y1545450D03*
X24199Y1523700D03*
X79000Y1555500D03*
X82429D03*
X36340Y1558809D03*
X78600Y1561900D03*
X29499Y1630050D03*
X75000Y1561800D03*
X28899Y1613524D03*
X42199Y1601050D03*
X38208Y1569841D03*
X25521Y1563350D03*
X30520Y1572049D03*
X32299Y1613524D03*
X34599Y1595300D03*
X24900Y1569500D03*
X31149Y1568300D03*
X26999Y1610550D03*
X34884Y1615734D03*
X32199Y1633124D03*
X34816Y1630953D03*
X22999Y1626050D03*
X23499Y1634050D03*
Y1618050D03*
X22699Y1594224D03*
X23499Y1610050D03*
Y1602050D03*
X23608Y1572653D03*
X24323Y1559950D03*
X31099Y1595350D03*
X32663Y1628181D03*
X27123Y1572205D03*
X33599Y1600200D03*
X74800Y1584700D03*
X74700Y1574600D03*
X39000Y1573500D03*
X89373Y1561073D03*
X85600Y1561500D03*
X80400Y1571766D03*
X82329Y1568117D03*
X31999Y1661127D03*
X28600Y1661039D03*
X29626Y1645002D03*
X33026Y1645051D03*
X95499Y1665418D03*
X33100Y1648500D03*
X47400Y1721700D03*
X34699Y1663300D03*
X27499Y1657050D03*
X26785Y1642089D03*
X22999Y1665550D03*
X92873Y1708176D03*
X24244Y1681868D03*
X22864Y1673550D03*
X23499Y1657050D03*
X23999Y1649550D03*
X23415Y1641634D03*
X92479Y1718176D03*
X78100Y1688189D03*
X92900Y1678176D03*
X93999Y1703050D03*
X74500Y1692000D03*
X21600Y1702900D03*
X32700Y1673300D03*
X32494Y1669706D03*
X29100Y1669500D03*
X30274Y1787238D03*
X85599Y1797350D03*
X38878Y1799571D03*
X47899Y1798650D03*
X36300Y1805123D03*
X35675Y1783450D03*
X39324Y1780623D03*
X39000Y1750800D03*
X43751Y1780559D03*
X42275Y1754000D03*
X48049Y1791450D03*
X40400Y1735600D03*
X47900Y1731300D03*
X47800Y1740500D03*
X89306Y1746856D03*
X89499Y1753575D03*
X85341Y1752245D03*
X85194Y1748848D03*
X46999Y1779550D03*
X37699Y1789850D03*
X46199Y1783050D03*
X74400Y1778100D03*
X38094Y1785840D03*
X41200Y1747050D03*
X42199Y1792250D03*
X37574Y1794050D03*
X45799Y1757650D03*
X46799Y1794900D03*
X47440Y1761391D03*
X31811Y1790271D03*
X47400Y1765250D03*
X43559Y1767884D03*
X40478Y1795820D03*
X32099Y1797150D03*
X47604Y1769005D03*
X45782Y1771877D03*
X47499Y1775350D03*
X45877Y1728477D03*
Y1724823D03*
X47000Y1737100D03*
X43600D03*
X28550Y1828153D03*
X29599Y1844350D03*
X29899Y1821050D03*
X34099Y1822850D03*
X60449Y1842550D03*
X80099Y1817250D03*
X28123Y1831527D03*
X35876Y1812350D03*
X34129Y1815267D03*
X86649Y1817100D03*
X61009Y1822340D03*
X36532Y1825352D03*
X36399Y1828750D03*
X26099Y1824950D03*
X25999Y1842550D03*
X46499Y1836550D03*
X47166Y1839884D03*
X80999Y1836550D03*
X90000Y1827900D03*
X43099Y1833850D03*
X39699D03*
X93500Y1827900D03*
X40500Y1863000D03*
X22367Y1836633D03*
X50299Y1946650D03*
X53999D03*
X42532Y1946783D03*
X44399Y1942250D03*
X38703Y1946754D03*
X34799Y1946750D03*
X46565Y1946703D03*
X44368Y1951450D03*
X45999Y1971450D03*
X28799Y1919060D03*
X14999Y1940050D03*
X15099Y1944050D03*
X50499Y1961550D03*
X14999Y1936050D03*
X17499Y1961050D03*
X43462Y1961160D03*
X32999Y1960555D03*
X23030Y1922038D03*
X25499Y1956050D03*
X42499Y1902550D03*
X48499Y1897050D03*
X26765Y1921945D03*
X57999Y1891050D03*
X31799Y1979050D03*
X112999Y124050D03*
X111790Y132259D03*
X152499Y149550D03*
X173499Y149050D03*
X175999Y82428D03*
X97499Y90050D03*
X115876Y125973D03*
Y130050D03*
X174999Y79050D03*
X175499Y86572D03*
X178999Y79050D03*
X176399Y94872D03*
X127999Y157050D03*
X114900Y177900D03*
X173500Y166315D03*
X154200Y168500D03*
X149400Y166400D03*
X149999Y243504D03*
Y239729D03*
X122397Y252688D03*
X122799Y249150D03*
X147099Y245350D03*
X124999Y246050D03*
X123300Y256000D03*
X157440Y283924D03*
Y303924D03*
Y313924D03*
X141499Y427550D03*
X165500Y416500D03*
X166500Y428500D03*
X153459Y427494D03*
X154101Y445550D03*
X141499Y423050D03*
X159600Y446399D03*
X152000Y520813D03*
X171722Y513827D03*
X163549Y517100D03*
X140940Y561800D03*
X150500Y545000D03*
X102100Y514900D03*
X163449Y521650D03*
X107526Y528996D03*
X104502Y530552D03*
X138999Y524213D03*
X173100Y483100D03*
X168453Y527949D03*
X160932Y549468D03*
X135499Y517550D03*
X107499Y497050D03*
X98900Y513400D03*
X172499Y491053D03*
X137899Y545451D03*
X176799Y493850D03*
X150750Y540416D03*
X109400Y543200D03*
X149000Y537500D03*
X106000Y543200D03*
X156500Y554000D03*
X138416Y553500D03*
X125499Y635550D03*
Y638950D03*
X127999Y645550D03*
X131400Y644600D03*
X144238Y645356D03*
X161000Y639100D03*
X124999Y643050D03*
X129000Y636600D03*
X128600Y640500D03*
X140900Y644000D03*
X134300Y646400D03*
X107000Y604800D03*
X105100Y600000D03*
X157000Y573851D03*
X141300Y565900D03*
X160824Y577000D03*
X144238Y649131D03*
X140400Y649800D03*
X158885Y679436D03*
Y689436D03*
X141500Y711000D03*
X158385Y719436D03*
X111200Y799450D03*
X110195Y809979D03*
X110500Y790200D03*
X110700Y795700D03*
X109831Y806598D03*
X109700Y803200D03*
X110202Y813379D03*
X154799Y838050D03*
X165499Y815550D03*
X110499Y834550D03*
X172660Y815731D03*
X174199Y841050D03*
X159500Y814700D03*
X169106Y815865D03*
X153900Y832200D03*
X98700Y842600D03*
Y822550D03*
X98000Y833500D03*
X163500Y937100D03*
X172500Y919294D03*
X108200Y963600D03*
X172000Y931600D03*
X106749Y934367D03*
X108441Y924705D03*
X160399Y922850D03*
X153499Y918550D03*
X108845Y931657D03*
X109099Y928250D03*
X171100Y935000D03*
X102100Y968500D03*
X99000Y965000D03*
X172000Y961000D03*
X152500Y960000D03*
X170250Y948500D03*
X154749Y968249D03*
X171000Y939500D03*
X123999Y1054050D03*
Y1050650D03*
X120100Y1053200D03*
X124100Y1047100D03*
X112699Y1058974D03*
X104600Y980500D03*
X154749Y979149D03*
X103200Y985364D03*
X104700Y989900D03*
X120749Y1093990D03*
X164700Y1085400D03*
X105499Y1080550D03*
X106718Y1076050D03*
X105999Y1085800D03*
X101499Y1072550D03*
X125900Y1091282D03*
X132499Y1094550D03*
X137100Y1084800D03*
X140800Y1076300D03*
X121500Y1083600D03*
X121100Y1075300D03*
X116249Y1102550D03*
X112999Y1103740D03*
X117499Y1079300D03*
X157700Y1114948D03*
X157600Y1124948D03*
X159000Y1083000D03*
X127000Y1113500D03*
X123999Y1102550D03*
X138600Y1124600D03*
X116700Y1063500D03*
X105600Y1069500D03*
X108999Y1102050D03*
X137481Y1077557D03*
X137477Y1081177D03*
X124423Y1077523D03*
Y1081177D03*
X106999Y1194550D03*
X102900Y1196050D03*
X103686Y1223863D03*
X103999Y1216863D03*
X127000Y1202000D03*
X148000Y1206000D03*
X106162Y1205702D03*
X114999Y1210363D03*
X130699Y1210653D03*
X118999Y1219050D03*
X123970Y1221573D03*
X119399Y1298113D03*
X101541Y1262607D03*
X116999Y1288050D03*
X101399Y1292550D03*
X107999Y1307713D03*
X120507Y1317050D03*
X116499Y1328013D03*
X120507Y1328096D03*
X135850Y1322250D03*
X143700Y1332500D03*
X101500Y1352000D03*
X113500D03*
X113000Y1341000D03*
X102000D03*
X107228Y1330552D03*
X107500Y1340500D03*
X110499Y1365050D03*
X109999Y1355050D03*
X138000Y1359025D03*
X111499Y1311800D03*
X125999Y1315550D03*
X132999Y1319550D03*
X142667Y1319218D03*
X149562Y1315987D03*
X133475Y1331200D03*
X112440Y1358196D03*
X112999Y1361550D03*
X97229Y1373337D03*
X97000Y1377600D03*
X109228Y1337090D03*
Y1333315D03*
X102700Y1321363D03*
X119499Y1339050D03*
X121000Y1364000D03*
X148024Y1333525D03*
X140000Y1332600D03*
X129000Y1356500D03*
X113500Y1344500D03*
Y1348154D03*
X102350Y1344500D03*
Y1348154D03*
X147400Y1321600D03*
X125100Y1366000D03*
X124290Y1469241D03*
X123808Y1465050D03*
X117390Y1426201D03*
Y1429976D03*
X104935Y1440634D03*
X142999Y1456373D03*
X104999Y1444941D03*
X106999Y1454450D03*
X100699Y1471050D03*
X139815Y1454438D03*
X139235Y1460973D03*
X123999Y1473050D03*
X127898Y1462441D03*
X107300Y1438100D03*
X114499Y1432050D03*
X114000Y1425400D03*
X107999Y1448050D03*
X150338Y1453958D03*
X152499Y1462940D03*
X105099Y1459150D03*
X142900Y1460000D03*
X100800Y1536450D03*
X98599Y1491350D03*
X157440Y1490460D03*
Y1500460D03*
Y1520460D03*
Y1530460D03*
X100499Y1479650D03*
X122199Y1476050D03*
X99899Y1539850D03*
X100000Y1546650D03*
X97499Y1554550D03*
X96999Y1558050D03*
X98144Y1534309D03*
X157400Y1596550D03*
X160200Y1598500D03*
X150999Y1713550D03*
X171999Y1662250D03*
X131999Y1710050D03*
X117499Y1706050D03*
X128749Y1703300D03*
X169100Y1685800D03*
X133090Y1699959D03*
X174250Y1694500D03*
X109499Y1712213D03*
X104999Y1708963D03*
X141500Y1715500D03*
X117249Y1712090D03*
X165575Y1676975D03*
X112753Y1716613D03*
X152633Y1677967D03*
X122642Y1704243D03*
X112562Y1720613D03*
X135499Y1710150D03*
X118499Y1694050D03*
X123749Y1711550D03*
X177900Y1690400D03*
X169600Y1682300D03*
X109499Y1743550D03*
X107300Y1746300D03*
X107100Y1736000D03*
X109399Y1739550D03*
X99199Y1761899D03*
X99999Y1753575D03*
X141999Y1764550D03*
X110099Y1759875D03*
X101399Y1784700D03*
X165900Y1790500D03*
X161900Y1793400D03*
X123393Y1870859D03*
X137999Y1861497D03*
Y1865151D03*
X123592Y1874254D03*
X96600Y1826000D03*
X135999Y1881550D03*
X141300Y1866400D03*
X141800Y1860500D03*
X97999Y1843050D03*
X159421Y1925972D03*
X210638Y62959D03*
X210634Y66863D03*
X201499Y104550D03*
X245499Y100550D03*
X246499Y86050D03*
Y80550D03*
X215138Y72559D03*
X210685Y74725D03*
X210605Y70692D03*
X205938Y72528D03*
X210738Y78459D03*
Y82159D03*
X186999Y99050D03*
X213499Y104650D03*
X223499Y108150D03*
X188999Y120800D03*
X205499Y105550D03*
X225499Y68550D03*
X233749Y110800D03*
X230749Y76300D03*
X207999Y109550D03*
X237899Y107050D03*
X197899Y165075D03*
X218499Y190550D03*
X247800Y269700D03*
X225298Y281114D03*
X213499Y283864D03*
X253871Y291410D03*
X250300Y275100D03*
X250400Y283100D03*
X239600Y278600D03*
X213400Y355300D03*
X224998Y357049D03*
X233998Y357549D03*
X239400Y357400D03*
X252935Y319114D03*
X214063Y318114D03*
X231800Y318414D03*
X179700Y425800D03*
X187699Y492850D03*
X199900Y554050D03*
X182499Y532550D03*
X220000Y516400D03*
X183499Y556100D03*
X188000Y484500D03*
X193549Y575875D03*
X246800Y677100D03*
X216999Y686550D03*
X213999Y725050D03*
X230849Y726050D03*
X252499D03*
X254499Y697700D03*
X249700Y682500D03*
X249800Y689900D03*
X238500Y680800D03*
X228999Y765550D03*
X218224Y765325D03*
X241600Y765700D03*
X236800Y765800D03*
X199000Y815000D03*
X200539Y890300D03*
X211750Y894600D03*
X198924Y975975D03*
X229562Y904113D03*
X215499Y905550D03*
X200799Y896600D03*
X233500Y1066100D03*
X226800Y1093400D03*
X221800Y1069300D03*
X247500Y1085500D03*
X256000Y1133000D03*
X255000Y1125700D03*
X221300Y1083238D03*
X251500Y1136700D03*
X229800Y1073600D03*
X242000Y1066000D03*
X182500Y1275500D03*
X199149Y1362900D03*
X194700Y1385700D03*
X181000Y1365500D03*
X180500Y1369900D03*
X229025Y1471576D03*
X241000Y1469600D03*
X224750Y1483950D03*
X232650Y1493450D03*
X233700Y1481600D03*
X199500Y1627000D03*
X195000Y1645500D03*
X179999Y1655887D03*
X186000Y1644000D03*
X179999Y1644500D03*
X181100Y1682700D03*
X194049Y1792600D03*
X201499Y1781050D03*
X227814Y1887513D03*
X231800Y1887100D03*
X236225Y1883125D03*
X229800Y1875700D03*
X218100Y1886400D03*
X213138Y1952703D03*
X249499Y1928050D03*
X231999Y1914050D03*
X210999Y1942050D03*
X223436Y1890465D03*
X232314Y1890513D03*
X213562Y1926113D03*
X220062Y1931113D03*
X240964Y1934113D03*
X214999Y1909550D03*
X257499Y1911050D03*
X249600Y1896800D03*
X343499Y60150D03*
X296099Y17100D03*
X305099Y17000D03*
X311400Y17100D03*
X317000Y17300D03*
X341499Y63050D03*
Y67110D03*
X343499Y31650D03*
X308999Y87050D03*
X323400Y105200D03*
X291999Y94050D03*
X282800Y87500D03*
X297499Y97550D03*
X315800Y100500D03*
X324800Y89400D03*
X293999Y293550D03*
X326499Y334054D03*
X284999Y338650D03*
X281499Y338550D03*
X313039Y352350D03*
X321900Y364600D03*
X298800Y333000D03*
X294500Y339000D03*
X326499Y337454D03*
X301249Y346050D03*
X344520Y406329D03*
X308999Y716450D03*
X315999Y718950D03*
X279939Y728610D03*
X329499Y801550D03*
X330540Y795509D03*
X327999Y740550D03*
X320499Y798050D03*
X285499Y745050D03*
X282099D03*
X292999Y743650D03*
X298000Y743500D03*
X323249Y749010D03*
X324959Y766750D03*
X277039Y740300D03*
X327749Y744050D03*
X306500Y753550D03*
X340699Y1046086D03*
X269500Y1135500D03*
X282500Y1135000D03*
X283499Y1556050D03*
X279999D03*
X289999Y1554650D03*
X293700Y1553351D03*
X276039Y1551300D03*
X314999Y1527550D03*
X326500Y1550200D03*
X261999Y1516050D03*
X295000Y1513000D03*
X333000Y1578000D03*
X297800Y1561600D03*
X291400Y1561500D03*
X324000Y1562500D03*
X312999Y1566050D03*
X323999Y1577250D03*
X330300Y1561200D03*
X310249Y1569800D03*
X264499Y1964050D03*
X331622Y1944767D03*
X288709Y1948042D03*
X284999Y1947691D03*
X342999Y1947409D03*
X342621Y1943409D03*
X330500Y1966500D03*
X280689Y1942710D03*
X315999Y1958550D03*
X327100Y1966472D03*
X329999Y1952273D03*
X325221Y1927272D03*
X313499Y1919050D03*
X332103Y1948133D03*
X310499Y1957050D03*
X285499Y1930050D03*
X381999Y57050D03*
X398799Y36152D03*
X381999Y50150D03*
X386799Y45000D03*
X381999Y53550D03*
X394199Y45050D03*
X358999Y61550D03*
X354999Y72050D03*
X426000Y93500D03*
X357503Y77043D03*
X374499Y77550D03*
X385999Y78050D03*
X401499Y80550D03*
X371700Y85500D03*
X400499Y406329D03*
X371999Y549300D03*
X394649Y630600D03*
X350499Y597300D03*
X375999Y698550D03*
X350499Y715050D03*
X371500Y880600D03*
X364499Y1099050D03*
X372999Y1123550D03*
X345499Y1096550D03*
X370149Y1320050D03*
X345424Y1310050D03*
X347324Y1524000D03*
X366149Y1554050D03*
X402499Y1476850D03*
X390999Y1514398D03*
Y1517798D03*
X349774Y1582900D03*
X354500Y1559500D03*
X400999Y1575550D03*
X354000Y1584900D03*
X353499Y1710450D03*
X377900Y1703800D03*
X348499Y1762050D03*
X385499Y1735050D03*
X367000Y1810000D03*
X360000Y1967500D03*
X645549Y1815134D03*
X644360Y1819137D03*
X659549Y1810634D03*
X757499Y745342D03*
Y1079550D03*
X755600Y1149800D03*
X758499Y1371050D03*
X757999Y1484050D03*
X754000Y1551000D03*
X750000Y1560500D03*
X732549Y1806634D03*
X733149Y1798634D03*
X690249Y1805634D03*
X707600Y1815600D03*
X733049Y1814134D03*
X755000Y1825000D03*
X711652Y1822109D03*
X711848Y1825504D03*
X758499Y1893550D03*
X752500Y1954500D03*
X821999Y193116D03*
X827499Y163550D03*
X820749Y163850D03*
X813249Y163800D03*
X839249Y164050D03*
X829917Y216200D03*
X833576Y215432D03*
X837999Y219550D03*
X822100Y279500D03*
X827500Y274500D03*
X770999Y302050D03*
X785499Y291050D03*
X770999Y290050D03*
Y295550D03*
X827499Y313424D03*
X763571Y295622D03*
X777999Y296050D03*
X786978Y298529D03*
X836500Y274950D03*
X812500Y282750D03*
X809940Y264940D03*
X822100Y261700D03*
X816700Y274300D03*
X791499Y333050D03*
X789999Y336550D03*
X772499Y323050D03*
X758778Y345000D03*
X768178Y333964D03*
X784499Y334050D03*
X772873Y326924D03*
X780499Y330050D03*
X771105Y722789D03*
X829800Y666650D03*
X835150Y677650D03*
X806500Y687250D03*
X781999Y725550D03*
X808660Y667540D03*
X820600Y664300D03*
X813200Y675900D03*
X788999Y736050D03*
X791999Y733050D03*
X766499Y732842D03*
X762500Y734000D03*
X784939Y733550D03*
X769999Y733050D03*
X792154Y1135926D03*
X825700Y1083100D03*
X771999Y1124550D03*
X767083Y1134550D03*
X764549Y1138500D03*
X784439Y1136550D03*
X814000Y1087000D03*
X772499Y1130050D03*
X789499Y1138050D03*
X779499Y1131050D03*
X807000Y1072900D03*
X825800Y1072300D03*
X815400Y1078800D03*
X803199Y1151850D03*
X822100Y1466800D03*
X774542Y1530050D03*
X804899Y1556950D03*
X827700Y1487600D03*
X836625Y1487400D03*
X771225Y1539474D03*
X767936Y1540336D03*
X784577Y1535628D03*
X812550Y1494050D03*
X774577Y1533796D03*
X791499Y1543550D03*
X793999Y1541050D03*
X784499Y1529050D03*
X809960Y1478040D03*
X814700Y1486300D03*
X788000Y1788000D03*
X774500D03*
X812000Y1799500D03*
X821249Y1791250D03*
X811000Y1793000D03*
X793000Y1803500D03*
X795849Y1805500D03*
X828500Y1877800D03*
X770999Y1820550D03*
X822499Y1815164D03*
X791999Y1819050D03*
X783499Y1827050D03*
X807000Y1822300D03*
X803500Y1822708D03*
X810900Y1882440D03*
X822700Y1871100D03*
X805900Y1887560D03*
X771499Y1936550D03*
X802499Y1951550D03*
X800431Y1941193D03*
X767999Y1945173D03*
X764908Y1946592D03*
X785939Y1946800D03*
X812500Y1898500D03*
X771499Y1940050D03*
X802099Y1961950D03*
X834799Y1946950D03*
X792499Y1949050D03*
X794499Y1941050D03*
X782999Y1937050D03*
X919800Y54600D03*
X924200Y69800D03*
X898800Y96000D03*
X855500Y149500D03*
X873000Y148500D03*
X846500Y149500D03*
X841499Y135550D03*
X861999Y146550D03*
X882499Y147050D03*
X896999Y141550D03*
X916499Y115050D03*
X923761Y85550D03*
X907499Y131800D03*
X902499Y110550D03*
X901499Y92050D03*
X898999Y110550D03*
X897555Y90494D03*
X910999Y124550D03*
X916499Y172550D03*
X867500Y163924D03*
X867576Y159924D03*
X878078Y240103D03*
Y243878D03*
X854400Y264600D03*
X847878Y250040D03*
X851278Y249974D03*
X842499Y280924D03*
X847500Y246600D03*
X850999Y246550D03*
X874700Y244900D03*
X874900Y238600D03*
X871999Y283924D03*
X886200Y313924D03*
X886600Y303924D03*
X872136Y273924D03*
X858478Y274050D03*
X868799Y294750D03*
X865499Y288050D03*
X867899Y321550D03*
X868299Y336150D03*
X902999Y556050D03*
X878596Y645573D03*
X875100Y644400D03*
X922049Y574375D03*
X879750Y570550D03*
X879950Y565050D03*
X851172Y655432D03*
X878596Y649348D03*
X847772Y655370D03*
X875300Y650500D03*
X851300Y651700D03*
X847600Y651600D03*
X852696Y671197D03*
X922049Y978575D03*
X900499Y962100D03*
X879708Y971892D03*
X878233Y1051095D03*
X877964Y1054485D03*
X850833Y1061441D03*
X847233Y1061492D03*
X847500Y1057800D03*
X851000Y1058000D03*
X874733Y1055792D03*
X874999Y1049550D03*
X900999Y979050D03*
X883083Y979183D03*
X864499Y1128750D03*
X852333Y1077716D03*
X871499Y1124948D03*
X872086Y1114948D03*
X871999Y1094948D03*
X872086Y1084948D03*
X860133Y1084142D03*
X860799Y1358925D03*
X861849Y1376050D03*
X866700Y1379796D03*
X866596Y1375796D03*
X848888Y1466402D03*
X852288Y1466346D03*
X878054Y1456450D03*
X877853Y1459991D03*
X874100Y1461600D03*
X874900Y1454000D03*
X848861Y1462463D03*
X852500Y1462600D03*
X867523Y1542821D03*
X867199Y1535150D03*
X854327Y1477550D03*
X858827Y1485696D03*
X872086Y1490460D03*
X871999Y1500460D03*
Y1520460D03*
X872086Y1530460D03*
X863699Y1501250D03*
X900500Y1721500D03*
X886439Y1717600D03*
X862800Y1712700D03*
X889800Y1711500D03*
X921549Y1788475D03*
X917499Y1796550D03*
X879700Y1786300D03*
X873300Y1740100D03*
X879664Y1782213D03*
X866914Y1861840D03*
X853499Y1871036D03*
X866914Y1865615D03*
X850099Y1871056D03*
X851500Y1821400D03*
X849375Y1824982D03*
X854905Y1825583D03*
X854480Y1867578D03*
X849999Y1867550D03*
X863700Y1867300D03*
X865300Y1858700D03*
X854814Y1883550D03*
X859314Y1891365D03*
X871921Y1905972D03*
X871421Y1895972D03*
X872086Y1925972D03*
Y1935972D03*
X863699Y1906450D03*
X857099Y1917650D03*
X961499Y100050D03*
X946899Y122550D03*
X932961Y85581D03*
X928461Y75981D03*
X928561Y91481D03*
X928508Y87747D03*
X928428Y83714D03*
X928561Y95181D03*
X928457Y79885D03*
X958999Y96050D03*
X930999Y115550D03*
X937999Y122050D03*
X938499Y115550D03*
X961499Y93350D03*
X926999Y122050D03*
X943499Y82550D03*
X934499Y118750D03*
X926999Y115050D03*
X939549Y175175D03*
X966499Y552050D03*
X965999Y954550D03*
X986400Y1639302D03*
X987100Y1624900D03*
X981200Y1625800D03*
X990425Y1633898D03*
X987029Y1634075D03*
X981200Y1618002D03*
X964000Y1639200D03*
X960900Y1636400D03*
X969600Y1638300D03*
X977500Y1660500D03*
X978000Y1668000D03*
X967600Y1651100D03*
X989502Y1646000D03*
X988800Y1658300D03*
X989000Y1663802D03*
X987200Y1675600D03*
X989900Y1678800D03*
X974000Y1670700D03*
X984211Y1667500D03*
X971558Y1646500D03*
X981500Y1653000D03*
X980800Y1659600D03*
X982050Y1649302D03*
G54D43*
X43999Y1968350D03*
X138999Y520913D03*
X161999Y919413D03*
X123000Y1136800D03*
X103499Y1301413D03*
X142667Y1310060D03*
X132999Y1310413D03*
X178500Y1701300D03*
X104999Y1705663D03*
X137504Y1739123D03*
X123999Y1738413D03*
X182499Y74850D03*
X194500Y502800D03*
X236000Y911800D03*
X215900Y900500D03*
X199000Y1641300D03*
X292999Y89913D03*
X311000Y373800D03*
X295500Y332800D03*
X307000Y774800D03*
X298000Y739300D03*
X297000Y1553400D03*
X327000Y1574300D03*
X306500Y1586300D03*
X296858Y1947628D03*
X309300Y1973876D03*
X367000Y46300D03*
X389500Y75800D03*
X369300Y75900D03*
X693549Y1816934D03*
X770000Y754800D03*
X907999Y88350D03*
X870201Y1713450D03*
G54D34*
X69400Y719500D03*
X44600D03*
X91099Y1890550D03*
Y1870050D03*
X125300Y1582500D03*
X100500D03*
X115899Y1890550D03*
Y1870050D03*
G54D16*
X17720Y1903144D03*
X29532Y309561D03*
Y1029522D03*
X129920Y17716D03*
X271657Y267711D03*
Y673223D03*
Y1078734D03*
Y1484246D03*
Y1889758D03*
X994098Y149601D03*
Y673223D03*
X994099Y1068892D03*
X994093Y1889751D03*
G54D52*
X34525Y1956355D03*
X36494D03*
X38462D03*
X40431D03*
X42399D03*
X44368D03*
X46337D03*
X48305D03*
X50274D03*
X52242D03*
X54211D03*
Y1937069D03*
X52242D03*
X50274D03*
X48305D03*
X46337D03*
X44368D03*
X42399D03*
X40431D03*
X38462D03*
X36494D03*
X34525D03*
G54D70*
X220319Y66622D03*
Y64654D03*
Y62685D03*
X201033D03*
Y64654D03*
Y66622D03*
X220319Y82371D03*
Y80402D03*
Y78434D03*
Y76465D03*
Y74497D03*
Y72528D03*
Y70559D03*
Y68591D03*
X201033D03*
Y70559D03*
Y72528D03*
Y74497D03*
Y76465D03*
Y78434D03*
Y80402D03*
Y82371D03*
X918856Y75707D03*
Y77676D03*
Y79644D03*
Y81613D03*
Y83581D03*
Y85550D03*
Y87519D03*
Y89487D03*
Y91456D03*
Y93424D03*
Y95393D03*
X938142D03*
Y93424D03*
Y91456D03*
Y89487D03*
Y87519D03*
Y85550D03*
Y83581D03*
Y81613D03*
Y79644D03*
Y77676D03*
Y75707D03*
G54D25*
X59199Y203550D03*
X81199Y204550D03*
X59199Y207550D03*
X81199Y208550D03*
X59199Y211550D03*
X81201Y611450D03*
Y615450D03*
X34699Y611550D03*
X59699Y1017050D03*
X84700Y1008500D03*
X59636Y1021050D03*
Y1025050D03*
X77199Y1837550D03*
X85949Y1828613D03*
X77449Y1843113D03*
X85949Y1832613D03*
X77199Y1849050D03*
X21699Y1948050D03*
Y1952050D03*
Y1940050D03*
X55699Y1897050D03*
X151699Y517613D03*
X159399Y524850D03*
X166899D03*
X174399D03*
X147200Y545000D03*
X174699Y916113D03*
X108950Y972000D03*
X108899Y967850D03*
X128180Y1098482D03*
Y1094482D03*
X116199Y1298113D03*
X131700Y1361000D03*
X142100Y1335800D03*
X131199Y1342050D03*
X103949Y1476050D03*
X111449D03*
X117449Y1702613D03*
X174200Y1691200D03*
X233699Y105050D03*
X241699Y95550D03*
X233572Y92572D03*
X182872Y90572D03*
Y86572D03*
X186599Y152000D03*
X229698Y287114D03*
X244000Y269700D03*
X186599Y559300D03*
X229699Y693550D03*
X243400Y677100D03*
X187099Y963100D03*
X202599Y1367400D03*
X186099Y1773200D03*
X305699Y86613D03*
X319600Y105200D03*
X308699Y334050D03*
Y339050D03*
X333198Y337114D03*
Y333114D03*
X318400Y365200D03*
X315700Y779000D03*
X310199Y742050D03*
Y746050D03*
X334699Y745050D03*
Y741050D03*
X319400Y772200D03*
X306699Y1554550D03*
X331199Y1557550D03*
Y1553550D03*
X316200Y1591000D03*
X318200Y1587000D03*
X306699Y1558550D03*
X318400Y1582600D03*
X313921Y1944909D03*
Y1948909D03*
X339421Y1947409D03*
Y1943409D03*
X321600Y1971900D03*
X374200Y46500D03*
X378800Y42300D03*
X754678Y323924D03*
Y328924D03*
X753396Y724882D03*
Y729882D03*
X754033Y1126392D03*
Y1131392D03*
X757027Y1531296D03*
Y1536296D03*
X700749Y1801634D03*
Y1808634D03*
X753514Y1937713D03*
Y1942213D03*
X816699Y167050D03*
X824199D03*
X831699D03*
X800699Y336050D03*
Y332050D03*
X779699Y326550D03*
Y322550D03*
X777699Y724050D03*
Y728550D03*
X799199Y736050D03*
Y732050D03*
Y1133050D03*
Y1137050D03*
X778699Y1127550D03*
Y1123550D03*
X801881Y1538893D03*
Y1542893D03*
X780881Y1527893D03*
Y1531893D03*
X817199Y1788050D03*
X824699D03*
X832199D03*
X800381Y1944393D03*
Y1948393D03*
X778199Y1935050D03*
Y1939050D03*
X905699Y103050D03*
Y107050D03*
X849200Y276800D03*
X916099Y557800D03*
X847900Y677700D03*
X916599Y962100D03*
X847500Y1083200D03*
X873199Y1359550D03*
Y1367550D03*
Y1363550D03*
X849500Y1488100D03*
X916099Y1771700D03*
X849999Y1893850D03*
X931099Y158500D03*
G54D61*
X140749Y474550D03*
X159249D03*
X140999Y508113D03*
X159499D03*
X164249Y873113D03*
Y906613D03*
X105749Y1288613D03*
X124249D03*
X105749Y1255113D03*
X124249D03*
X107249Y1693113D03*
X125749D03*
X106749Y1659613D03*
X125249D03*
X219248Y296614D03*
X237748D03*
X219248Y329614D03*
X237748D03*
X219749Y703050D03*
X238249D03*
X219249Y737050D03*
X237749D03*
X182749Y873113D03*
Y906613D03*
X219250Y1103100D03*
X237750D03*
X218050Y1513400D03*
X236550D03*
X219249Y1546050D03*
X237749D03*
X219684Y1906687D03*
X238184D03*
X218184Y1942987D03*
X236684D03*
X295249Y43613D03*
X313749D03*
X295249Y77113D03*
X313749D03*
X837978Y290124D03*
X841478Y323924D03*
X836196Y691182D03*
X839249Y724550D03*
X836333Y1096692D03*
X839749Y1129550D03*
X838077Y1501596D03*
X838314Y1907313D03*
X841249Y1940550D03*
X856478Y290124D03*
X859978Y323924D03*
X854696Y691182D03*
X857749Y724550D03*
X854833Y1096692D03*
X858249Y1129550D03*
X856577Y1501596D03*
X861077Y1534296D03*
X842577D03*
X856814Y1907313D03*
X859749Y1940550D03*
G54D71*
X238249Y102050D03*
G54D26*
X51799Y217100D03*
X48400Y635500D03*
X34699Y616050D03*
X48400Y639600D03*
X79199Y642550D03*
X38800Y607326D03*
Y603200D03*
X35500Y597400D03*
Y593300D03*
X43100Y597400D03*
X60449Y656487D03*
Y652487D03*
Y648487D03*
X82700Y1013000D03*
X87299Y1000450D03*
Y1004450D03*
X92700Y1557500D03*
Y1553500D03*
X41699Y1838050D03*
Y1842050D03*
X67299Y1851900D03*
X21699Y1944050D03*
Y1936050D03*
X158199Y165050D03*
Y161050D03*
X170300Y420300D03*
X137699Y423113D03*
Y427113D03*
X170300Y424300D03*
X157499Y540050D03*
Y544250D03*
X157699Y570050D03*
Y566050D03*
X158199Y975550D03*
Y971550D03*
X174700Y922700D03*
X122199Y1125050D03*
X101299Y1081700D03*
Y1077400D03*
X143200Y1202000D03*
X139700Y1210000D03*
X134700Y1202000D03*
Y1206000D03*
X123199Y1356050D03*
Y1352050D03*
X131700Y1365000D03*
X123699Y1343050D03*
X128000Y1319900D03*
X118949Y1476050D03*
X147699Y1722550D03*
Y1718550D03*
X109199Y1716613D03*
Y1720613D03*
X158171Y1786909D03*
Y1782909D03*
X233699Y101050D03*
X182826Y82428D03*
X233699Y97050D03*
X180199Y165050D03*
Y161050D03*
Y156550D03*
X232100Y283000D03*
X179700Y420500D03*
X180199Y564050D03*
Y572050D03*
Y568050D03*
X229700Y689500D03*
X198800Y823000D03*
X179949Y976550D03*
Y972550D03*
X180199Y967550D03*
X183800Y931600D03*
X227950Y1082500D03*
X194699Y1381050D03*
Y1377050D03*
Y1373050D03*
X228200Y1480100D03*
X233100Y1499300D03*
X198749Y1630613D03*
X206700Y1649500D03*
X202200Y1645500D03*
X180764Y1786613D03*
Y1782613D03*
Y1778613D03*
X337699Y63050D03*
Y67050D03*
X305700Y90700D03*
X310199Y360050D03*
Y356050D03*
X308699Y343550D03*
X311199Y767050D03*
Y762550D03*
X310199Y750050D03*
Y1573050D03*
X306699Y1562550D03*
X313477Y1966191D03*
Y1962191D03*
X313558Y1953328D03*
X404199Y56050D03*
X386699Y30550D03*
Y26050D03*
X404199Y51050D03*
X378699Y53050D03*
Y57050D03*
X651749Y1803634D03*
Y1796134D03*
X651249Y1818634D03*
X757200Y351500D03*
X755200Y1154500D03*
X739749Y1798634D03*
Y1814134D03*
Y1806634D03*
X697249Y1821634D03*
Y1825634D03*
X757200Y1961000D03*
X760700Y355500D03*
X761700Y755000D03*
X758200Y751000D03*
X758700Y1158500D03*
Y1556500D03*
X762200Y1561000D03*
X789249Y1804634D03*
Y1800634D03*
X817199Y1825550D03*
Y1821550D03*
X777749Y1817634D03*
X760700Y1965000D03*
X905699Y99050D03*
X874928Y163924D03*
Y159924D03*
X849178Y280924D03*
X908646Y562882D03*
Y570882D03*
X886699Y570550D03*
X908646Y566882D03*
X886699Y565050D03*
X847896Y681882D03*
X908533Y974392D03*
X886533Y975892D03*
X908533Y970392D03*
X886533Y971892D03*
X908533Y966392D03*
X847533Y1087392D03*
X873527Y1379796D03*
Y1375796D03*
X861799Y1372200D03*
X849527Y1492296D03*
X908264Y1785613D03*
X886300Y1786300D03*
X908264Y1781613D03*
X886264Y1782213D03*
X908264Y1777613D03*
X881301Y1727450D03*
X888801D03*
X850014Y1898113D03*
X925928Y168424D03*
Y164424D03*
X925699Y172550D03*
G54D62*
X145439Y426863D03*
X147999D03*
X150559D03*
Y433363D03*
X145439D03*
X167439Y820363D03*
X169999D03*
X172559D03*
Y826863D03*
X167439D03*
X109439Y1079300D03*
X111999D03*
X114559D03*
Y1085800D03*
X109439D03*
X106939Y1210363D03*
X109499D03*
X112059D03*
Y1216863D03*
X106939D03*
X114939Y1305300D03*
X120059D03*
Y1311800D03*
X117499D03*
X114939D03*
X132939Y1714800D03*
X135499D03*
X138059D03*
Y1721300D03*
X132939D03*
X208559Y891800D03*
X205999D03*
X203439D03*
Y885300D03*
X208559D03*
X284059Y333800D03*
X281499D03*
X278939D03*
Y327300D03*
X284059D03*
X285059Y740300D03*
X282499D03*
X279939D03*
Y733800D03*
X285059D03*
X284059Y1551300D03*
X281499D03*
X278939D03*
Y1544800D03*
X284059D03*
X288709Y1942700D03*
X286149D03*
X283589D03*
Y1936200D03*
X288709D03*
X790559Y327800D03*
X787999D03*
X785439D03*
Y321300D03*
X790559D03*
X790059Y728800D03*
X787499D03*
X784939D03*
Y722300D03*
X790059D03*
X789559Y1131800D03*
X786999D03*
X784439D03*
Y1125300D03*
X789559D03*
X792813Y1535628D03*
X790253D03*
X787693D03*
Y1529128D03*
X792813D03*
X791059Y1942300D03*
X788499D03*
X785939D03*
Y1935800D03*
X791059D03*
G54D80*
X825300Y1726200D03*
X836300D03*
X887700Y1733800D03*
X876700D03*
X940400Y1486900D03*
X951400D03*
X940500Y1477500D03*
X951500D03*
G54D53*
X76038Y1929550D03*
X110960D03*
G54D35*
X95000Y1113000D03*
X86000D03*
X176500Y414500D03*
X133000Y1196000D03*
X142000D03*
X185500Y414500D03*
X203500Y812500D03*
X212500D03*
X201000Y1655500D03*
X210000D03*
X326000Y380000D03*
X317000D03*
X319500Y785500D03*
X310500D03*
X319500Y1597000D03*
X310500D03*
X369000Y53000D03*
X360000D03*
X753000Y362500D03*
X756000Y761500D03*
X752900Y1164800D03*
X755500Y1568000D03*
X756000Y1972000D03*
X762000Y362500D03*
X765000Y761500D03*
X761900Y1164800D03*
X764500Y1568000D03*
X765000Y1972000D03*
X877500Y1721500D03*
X883500D03*
G54D44*
X18199Y1956050D03*
X36199Y1918050D03*
X100699Y145050D03*
Y141550D03*
X105199Y129550D03*
Y126050D03*
X100645Y550988D03*
Y547488D03*
X101145Y525988D03*
Y522488D03*
X178399Y524850D03*
X102745Y956489D03*
Y952989D03*
X99745Y931489D03*
Y927989D03*
X119200Y1113500D03*
X129150Y1081100D03*
Y1077600D03*
X104028Y1361952D03*
Y1358452D03*
X100528Y1336952D03*
Y1333452D03*
X103699Y1767550D03*
Y1764050D03*
X101699Y1743050D03*
Y1739550D03*
X179699Y99050D03*
X697749Y1813134D03*
X835699Y167550D03*
X836199Y1788050D03*
X903699Y124550D03*
X951199Y96050D03*
G54D17*
X68898Y17047D03*
Y190275D03*
Y422559D03*
Y595787D03*
Y828071D03*
Y1001299D03*
Y1233583D03*
Y1406811D03*
Y1639095D03*
Y1812323D03*
X167323Y179803D03*
Y353031D03*
Y585315D03*
Y758543D03*
Y990827D03*
Y1164055D03*
Y1396339D03*
Y1569567D03*
Y1801851D03*
Y1975079D03*
X895669Y179803D03*
Y353031D03*
Y585315D03*
Y758543D03*
Y990827D03*
Y1164055D03*
Y1396339D03*
Y1569567D03*
Y1801851D03*
Y1975079D03*
G54D90*
G01X105749Y1716613D02*
Y1712749D01*
G01X832825Y274950D02*
X836500D01*
G01X950100Y1626100D02*
X955098Y1621102D01*
X1005807D01*
G54D27*
X48399Y217100D03*
X45000Y635500D03*
X31299Y616050D03*
X45000Y639600D03*
X75799Y642550D03*
X35400Y607326D03*
Y603200D03*
X32100Y597400D03*
Y593300D03*
X39700Y597400D03*
X57049Y656487D03*
Y652487D03*
Y648487D03*
X79300Y1013000D03*
X83899Y1000450D03*
Y1004450D03*
X89300Y1557500D03*
Y1553500D03*
X38299Y1838050D03*
Y1842050D03*
X63899Y1851900D03*
X18299Y1944050D03*
Y1936050D03*
X176799Y165050D03*
X154799D03*
X176799Y161050D03*
X154799D03*
X176799Y156550D03*
X176300Y420500D03*
X166900Y420300D03*
X134299Y423113D03*
Y427113D03*
X166900Y424300D03*
X176799Y564050D03*
X154099Y540050D03*
Y544250D03*
X176799Y572050D03*
X154299Y570050D03*
X176799Y568050D03*
X154299Y566050D03*
X176549Y976550D03*
X154799Y975550D03*
X176549Y972550D03*
X154799Y971550D03*
X176799Y967550D03*
X171300Y922700D03*
X118799Y1125050D03*
X97899Y1081700D03*
Y1077400D03*
X139800Y1202000D03*
X136300Y1210000D03*
X131300Y1202000D03*
Y1206000D03*
X119799Y1356050D03*
Y1352050D03*
X128300Y1365000D03*
X120299Y1343050D03*
X124600Y1319900D03*
X115549Y1476050D03*
X144299Y1722550D03*
Y1718550D03*
X105799Y1716613D03*
Y1720613D03*
X177364Y1786613D03*
X154771Y1786909D03*
X177364Y1782613D03*
X154771Y1782909D03*
X177364Y1778613D03*
X230299Y101050D03*
X179426Y82428D03*
X230299Y97050D03*
X228700Y283000D03*
X226300Y689500D03*
X195400Y823000D03*
X180400Y931600D03*
X224550Y1082500D03*
X191299Y1381050D03*
Y1377050D03*
Y1373050D03*
X224800Y1480100D03*
X229700Y1499300D03*
X195349Y1630613D03*
X203300Y1649500D03*
X198800Y1645500D03*
X334299Y63050D03*
Y67050D03*
X302300Y90700D03*
X306799Y360050D03*
Y356050D03*
X305299Y343550D03*
X307799Y767050D03*
Y762550D03*
X306799Y750050D03*
Y1573050D03*
X303299Y1562550D03*
X310077Y1966191D03*
Y1962191D03*
X310158Y1953328D03*
X400799Y56050D03*
X383299Y30550D03*
Y26050D03*
X400799Y51050D03*
X375299Y53050D03*
Y57050D03*
X648349Y1803634D03*
Y1796134D03*
X647849Y1818634D03*
X757300Y355500D03*
X753800Y351500D03*
X754800Y751000D03*
X755300Y1158500D03*
X751800Y1154500D03*
X755300Y1556500D03*
X736349Y1798634D03*
Y1814134D03*
Y1806634D03*
X693849Y1821634D03*
Y1825634D03*
X757300Y1965000D03*
X753800Y1961000D03*
X758300Y755000D03*
X758800Y1561000D03*
X785849Y1804634D03*
Y1800634D03*
X813799Y1825550D03*
Y1821550D03*
X774349Y1817634D03*
X902299Y99050D03*
X871528Y163924D03*
X922528Y168424D03*
X871528Y159924D03*
X922528Y164424D03*
X922299Y172550D03*
X845778Y280924D03*
X905246Y562882D03*
Y570882D03*
X883299Y570550D03*
X905246Y566882D03*
X883299Y565050D03*
X844496Y681882D03*
X905133Y974392D03*
X883133Y975892D03*
X905133Y970392D03*
X883133Y971892D03*
X905133Y966392D03*
X844133Y1087392D03*
X870127Y1379796D03*
Y1375796D03*
X858399Y1372200D03*
X846127Y1492296D03*
X904864Y1785613D03*
X882900Y1786300D03*
X904864Y1781613D03*
X882864Y1782213D03*
X904864Y1777613D03*
X877901Y1727450D03*
X885401D03*
X846614Y1898113D03*
G54D36*
X88300Y1097500D03*
Y1104500D03*
X57299Y1901550D03*
X39799Y1921550D03*
X131799Y224550D03*
Y228050D03*
Y249050D03*
Y252550D03*
X135238Y630065D03*
Y633565D03*
Y654565D03*
Y658065D03*
X132799Y1035550D03*
Y1039050D03*
Y1060050D03*
Y1063550D03*
X143300Y1206000D03*
X109250Y1348100D03*
Y1344600D03*
X131190Y1441241D03*
Y1444741D03*
Y1465741D03*
Y1469241D03*
X131892Y1846254D03*
Y1849754D03*
Y1870754D03*
Y1874254D03*
X859278Y224924D03*
Y228424D03*
Y249424D03*
Y252924D03*
X859496Y630382D03*
Y633882D03*
Y654882D03*
Y658382D03*
X859133Y1035892D03*
Y1039392D03*
Y1060892D03*
Y1064392D03*
X860627Y1440796D03*
Y1444296D03*
Y1465796D03*
Y1469296D03*
X862614Y1846613D03*
Y1850113D03*
Y1871113D03*
Y1874613D03*
G54D18*
X85630Y41141D03*
Y46141D03*
Y51141D03*
Y56141D03*
Y61141D03*
Y66141D03*
Y136141D03*
Y141141D03*
Y146141D03*
Y71141D03*
Y76141D03*
Y81141D03*
Y86141D03*
Y91141D03*
Y96141D03*
Y101141D03*
Y106141D03*
Y111141D03*
Y151141D03*
Y156141D03*
Y161141D03*
Y166141D03*
Y446653D03*
Y451653D03*
Y456653D03*
Y461653D03*
Y466653D03*
Y471653D03*
Y476653D03*
Y481653D03*
Y541653D03*
Y546653D03*
Y551653D03*
Y556653D03*
Y561653D03*
Y486653D03*
Y491653D03*
Y496653D03*
Y501653D03*
Y506653D03*
Y511653D03*
Y516653D03*
Y566653D03*
Y571653D03*
Y852165D03*
Y857165D03*
Y862165D03*
Y867165D03*
Y872165D03*
Y877165D03*
Y882165D03*
Y887165D03*
Y892165D03*
Y947165D03*
Y952165D03*
Y957165D03*
Y962165D03*
Y967165D03*
Y972165D03*
Y977165D03*
Y897165D03*
Y902165D03*
Y907165D03*
Y912165D03*
Y917165D03*
Y922165D03*
Y1257677D03*
Y1262677D03*
Y1267677D03*
Y1272677D03*
Y1277677D03*
Y1282677D03*
Y1287677D03*
Y1292677D03*
Y1297677D03*
Y1302677D03*
Y1307677D03*
Y1352677D03*
Y1357677D03*
Y1362677D03*
Y1367677D03*
Y1372677D03*
Y1377677D03*
Y1382677D03*
Y1312677D03*
Y1317677D03*
Y1322677D03*
Y1327677D03*
Y1663189D03*
Y1668189D03*
Y1673189D03*
Y1678189D03*
Y1683189D03*
Y1688189D03*
Y1693189D03*
Y1698189D03*
Y1703189D03*
Y1708189D03*
Y1713189D03*
Y1718189D03*
Y1723189D03*
Y1758189D03*
Y1763189D03*
Y1768189D03*
Y1773189D03*
Y1778189D03*
Y1783189D03*
Y1788189D03*
Y1728189D03*
Y1733189D03*
X150591Y228937D03*
Y223937D03*
Y218937D03*
Y213937D03*
Y208937D03*
Y203937D03*
Y233937D03*
Y313937D03*
Y308937D03*
Y303937D03*
Y298937D03*
Y293937D03*
Y288937D03*
Y283937D03*
Y278937D03*
Y273937D03*
Y268937D03*
Y263937D03*
Y258937D03*
Y328937D03*
Y323937D03*
Y318937D03*
Y639449D03*
Y634449D03*
Y629449D03*
Y624449D03*
Y619449D03*
Y614449D03*
Y609449D03*
Y729449D03*
Y724449D03*
Y719449D03*
Y714449D03*
Y709449D03*
Y704449D03*
Y699449D03*
Y694449D03*
Y689449D03*
Y684449D03*
Y679449D03*
Y674449D03*
Y669449D03*
Y664449D03*
Y734449D03*
Y1044961D03*
Y1039961D03*
Y1034961D03*
Y1029961D03*
Y1024961D03*
Y1019961D03*
Y1014961D03*
Y1139961D03*
Y1134961D03*
Y1129961D03*
Y1124961D03*
Y1119961D03*
Y1114961D03*
Y1109961D03*
Y1104961D03*
Y1099961D03*
Y1094961D03*
Y1089961D03*
Y1084961D03*
Y1079961D03*
Y1074961D03*
Y1069961D03*
Y1450473D03*
Y1445473D03*
Y1440473D03*
Y1435473D03*
Y1430473D03*
Y1425473D03*
Y1420473D03*
Y1545473D03*
Y1540473D03*
Y1535473D03*
Y1530473D03*
Y1525473D03*
Y1520473D03*
Y1515473D03*
Y1510473D03*
Y1505473D03*
Y1500473D03*
Y1495473D03*
Y1490473D03*
Y1485473D03*
Y1480473D03*
Y1475473D03*
Y1855985D03*
Y1850985D03*
Y1845985D03*
Y1840985D03*
Y1835985D03*
Y1830985D03*
Y1825985D03*
Y1885985D03*
Y1880985D03*
Y1950985D03*
Y1945985D03*
Y1940985D03*
Y1935985D03*
Y1930985D03*
Y1925985D03*
Y1920985D03*
Y1915985D03*
Y1910985D03*
Y1905985D03*
Y1900985D03*
Y1895985D03*
Y1890985D03*
X878937Y228937D03*
Y223937D03*
Y218937D03*
Y213937D03*
Y208937D03*
Y203937D03*
Y233937D03*
Y313937D03*
Y308937D03*
Y303937D03*
Y298937D03*
Y293937D03*
Y288937D03*
Y283937D03*
Y278937D03*
Y273937D03*
Y268937D03*
Y263937D03*
Y258937D03*
Y328937D03*
Y323937D03*
Y318937D03*
Y639449D03*
Y634449D03*
Y629449D03*
Y624449D03*
Y619449D03*
Y614449D03*
Y609449D03*
Y729449D03*
Y724449D03*
Y719449D03*
Y714449D03*
Y709449D03*
Y704449D03*
Y699449D03*
Y694449D03*
Y689449D03*
Y684449D03*
Y679449D03*
Y674449D03*
Y669449D03*
Y664449D03*
Y734449D03*
Y1044961D03*
Y1039961D03*
Y1034961D03*
Y1029961D03*
Y1024961D03*
Y1019961D03*
Y1014961D03*
Y1139961D03*
Y1134961D03*
Y1129961D03*
Y1124961D03*
Y1119961D03*
Y1114961D03*
Y1109961D03*
Y1104961D03*
Y1099961D03*
Y1094961D03*
Y1089961D03*
Y1084961D03*
Y1079961D03*
Y1074961D03*
Y1069961D03*
Y1450473D03*
Y1445473D03*
Y1440473D03*
Y1435473D03*
Y1430473D03*
Y1425473D03*
Y1420473D03*
Y1545473D03*
Y1540473D03*
Y1535473D03*
Y1530473D03*
Y1525473D03*
Y1520473D03*
Y1515473D03*
Y1510473D03*
Y1505473D03*
Y1500473D03*
Y1495473D03*
Y1490473D03*
Y1485473D03*
Y1480473D03*
Y1475473D03*
Y1855985D03*
Y1850985D03*
Y1845985D03*
Y1840985D03*
Y1835985D03*
Y1830985D03*
Y1825985D03*
Y1885985D03*
Y1880985D03*
Y1950985D03*
Y1945985D03*
Y1940985D03*
Y1935985D03*
Y1930985D03*
Y1925985D03*
Y1920985D03*
Y1915985D03*
Y1910985D03*
Y1905985D03*
Y1900985D03*
Y1895985D03*
Y1890985D03*
G54D63*
X140940Y550300D03*
X143500D03*
X146060D03*
Y557700D03*
X143500D03*
X140940D03*
X172240Y1678400D03*
X174800D03*
X177360D03*
Y1685800D03*
X174800D03*
X172240D03*
X242040Y275100D03*
X244600D03*
X247160D03*
Y282500D03*
X244600D03*
X242040D03*
X241440Y682500D03*
X244000D03*
X246560D03*
Y689900D03*
X244000D03*
X241440D03*
X181340Y937100D03*
X183900D03*
X186460D03*
Y944500D03*
X183900D03*
X181340D03*
X315939Y352350D03*
X318499D03*
X321059D03*
Y359750D03*
X318499D03*
X315939D03*
X316939Y759350D03*
X319499D03*
X322059D03*
Y766750D03*
X319499D03*
X316939D03*
X315939Y1569850D03*
X318499D03*
X321059D03*
Y1577250D03*
X318499D03*
X315939D03*
X319080Y1959072D03*
X321640D03*
X324200D03*
Y1966472D03*
X321640D03*
X319080D03*
G54D81*
X876000Y1703899D03*
X879750D03*
X883500D03*
Y1714499D03*
X879750D03*
X876000D03*
G54D54*
X20087Y1973700D03*
X946999Y116300D03*
G54D72*
X240749Y102050D03*
G54D45*
X21799Y1956050D03*
X39799Y1918050D03*
X104299Y145050D03*
Y141550D03*
X108799Y129550D03*
Y126050D03*
X104245Y550988D03*
Y547488D03*
X104745Y525988D03*
Y522488D03*
X106345Y956489D03*
Y952989D03*
X103345Y931489D03*
Y927989D03*
X122800Y1113500D03*
X132750Y1081100D03*
Y1077600D03*
X107628Y1361952D03*
Y1358452D03*
X104128Y1336952D03*
Y1333452D03*
X107299Y1767550D03*
Y1764050D03*
X105299Y1743050D03*
Y1739550D03*
X183299Y99050D03*
X181999Y524850D03*
X701349Y1813134D03*
X839299Y167550D03*
X839799Y1788050D03*
X907299Y124550D03*
X954799Y96050D03*
G54D91*
G01X31999Y1918800D02*
X29059D01*
X28799Y1919060D01*
G01X174099Y533350D02*
X174024Y533275D01*
G01X666399Y1808664D02*
X662296D01*
X660519Y1806887D01*
G01X666399Y1806699D02*
X669984D01*
X671050Y1805633D01*
Y1803937D01*
X669001Y1801888D01*
G01X666399Y1810634D02*
X659549D01*
G01X682699Y1806699D02*
Y1803784D01*
X682549Y1803634D01*
G01X687536Y1811647D02*
X686523Y1810634D01*
X682699D01*
G01X689731Y1808664D02*
X682699D01*
G01X833013Y176949D02*
Y170286D01*
X835749Y167550D01*
G54D19*
X20700Y119500D03*
Y114500D03*
X180199Y95050D03*
X900699Y115050D03*
X890600Y1716200D03*
X878601Y1693850D03*
X965400Y1665500D03*
Y1660500D03*
G54D46*
X49999Y1971850D03*
X143499Y523413D03*
X166499Y921913D03*
X136600Y1180200D03*
X107999Y1303913D03*
X109499Y1708413D03*
X218998Y317914D03*
X213598Y350914D03*
X218499Y724850D03*
X214599Y757850D03*
X217600Y1127800D03*
X217999Y1534850D03*
X218814Y1925913D03*
X213600Y1962400D03*
X297499Y92413D03*
X783049Y1819434D03*
X788049D03*
X858999Y311850D03*
X864900Y344900D03*
X855696Y712182D03*
X862896Y746382D03*
X855333Y1117692D03*
X862933Y1149192D03*
X857827Y1522596D03*
X865700Y1552400D03*
X857314Y1928413D03*
X864500Y1962200D03*
G54D55*
X20087Y1976200D03*
X946999Y118800D03*
G54D37*
X84700Y1097500D03*
Y1104500D03*
X53699Y1901550D03*
X36199Y1921550D03*
X128199Y224550D03*
Y228050D03*
Y249050D03*
Y252550D03*
X131638Y630065D03*
Y633565D03*
Y654565D03*
Y658065D03*
X129199Y1035550D03*
Y1039050D03*
Y1060050D03*
Y1063550D03*
X139700Y1206000D03*
X105650Y1348100D03*
Y1344600D03*
X127590Y1441241D03*
Y1444741D03*
Y1465741D03*
Y1469241D03*
X128292Y1846254D03*
Y1849754D03*
Y1870754D03*
Y1874254D03*
X855678Y224924D03*
Y228424D03*
Y249424D03*
Y252924D03*
X855896Y630382D03*
Y633882D03*
Y654882D03*
Y658382D03*
X855533Y1035892D03*
Y1039392D03*
Y1060892D03*
Y1064392D03*
X857027Y1440796D03*
Y1444296D03*
Y1465796D03*
Y1469296D03*
X859014Y1846613D03*
Y1850113D03*
Y1871113D03*
Y1874613D03*
G54D82*
X854101Y1710351D03*
Y1733149D03*
G54D73*
X231500Y269350D03*
X235375Y276850D03*
X227625D03*
X230900Y676250D03*
X234775Y683750D03*
X227025D03*
X232700Y1485950D03*
X236575Y1493450D03*
X228825D03*
X240100Y1880450D03*
X243975Y1887950D03*
X236225D03*
X836700Y267450D03*
X840575Y274950D03*
X832825D03*
X835300Y670150D03*
X839175Y677650D03*
X831425D03*
X835000Y1075750D03*
X838875Y1083250D03*
X831125D03*
X836900Y1479050D03*
X840775Y1486550D03*
X833025D03*
X837499Y1884800D03*
X833624Y1892300D03*
X841374D03*
G54D64*
X176999Y490913D03*
Y488353D03*
Y485793D03*
X116249Y1093990D03*
Y1096550D03*
Y1099110D03*
X109749D03*
Y1093990D03*
X117249Y1720110D03*
Y1717550D03*
Y1714990D03*
X123749D03*
Y1720110D03*
X183499Y485793D03*
Y490913D03*
X321748Y334054D03*
Y336614D03*
Y339174D03*
X315248D03*
Y334054D03*
X323249Y740990D03*
Y743550D03*
Y746110D03*
X316749D03*
Y740990D03*
X319749Y1554490D03*
Y1557050D03*
X313249Y1554490D03*
X319749Y1559610D03*
X313249D03*
X326971Y1944349D03*
Y1946909D03*
Y1949469D03*
X320471D03*
Y1944349D03*
X347749Y67110D03*
Y64550D03*
Y61990D03*
X354249D03*
Y67110D03*
X387749Y56110D03*
Y53550D03*
Y50990D03*
X394249D03*
Y56110D03*
X767728Y323864D03*
Y326424D03*
Y328984D03*
X761228D03*
Y323864D03*
X766946Y724822D03*
Y727382D03*
X760446Y724822D03*
X766946Y729942D03*
X760446D03*
X767083Y1126332D03*
Y1128892D03*
Y1131452D03*
X760583D03*
Y1126332D03*
X770077Y1531236D03*
Y1533796D03*
Y1536356D03*
X763577D03*
Y1531236D03*
X766564Y1937153D03*
Y1939713D03*
Y1942273D03*
X760064D03*
Y1937153D03*
G54D28*
X42449Y211775D03*
Y204025D03*
X49949Y207900D03*
X74049Y648025D03*
Y655775D03*
X66549Y651900D03*
X20849Y1059925D03*
Y1052175D03*
X28349Y1056050D03*
X60449Y1846475D03*
Y1838725D03*
X67949Y1842600D03*
X137249Y1347675D03*
Y1355425D03*
X129749Y1351550D03*
X193549Y157325D03*
Y165075D03*
X186049Y161200D03*
X193549Y564525D03*
Y572275D03*
X186049Y568400D03*
X193549Y968225D03*
Y975975D03*
X186049Y972100D03*
X208049Y1372925D03*
Y1380675D03*
X200549Y1376800D03*
X194049Y1778625D03*
Y1786375D03*
X186549Y1782500D03*
X922049Y563025D03*
Y570775D03*
X914549Y566900D03*
X922049Y967225D03*
Y974975D03*
X914549Y971100D03*
X856449Y1366675D03*
Y1358925D03*
X863949Y1362800D03*
X921549Y1777125D03*
Y1784875D03*
X914049Y1781000D03*
X939549Y163825D03*
Y171575D03*
X932049Y167700D03*
G54D92*
G01X60749Y199550D02*
X97499D01*
X97999Y199050D01*
G01X800890Y1780148D02*
X804076Y1783334D01*
Y1808873D01*
X799315Y1813634D01*
X788049D01*
G01D02*
X783049D01*
G54D83*
X877700Y1740700D03*
G54D74*
X241500Y1085625D03*
X234000Y1089500D03*
Y1081750D03*
G54D56*
X143999Y54089D03*
Y89011D03*
X862999Y60089D03*
Y95011D03*
G54D65*
X171557Y533288D03*
X168997D03*
X166437D03*
X163877D03*
Y549468D03*
X166437D03*
X168997D03*
X171557D03*
X116045Y1484981D03*
X113485D03*
X110925D03*
X108365D03*
Y1501161D03*
X110925D03*
X113485D03*
X116045D03*
X833013Y176949D03*
X830453D03*
X827893D03*
X825333D03*
Y193129D03*
X827893D03*
X830453D03*
X833013D03*
Y1798997D03*
X830453D03*
X827893D03*
X825333D03*
Y1815177D03*
X827893D03*
X830453D03*
X833013D03*
G54D38*
X20300Y1097500D03*
Y1102500D03*
X242299Y76550D03*
X895300Y1721500D03*
X958299Y89550D03*
G54D29*
X38999Y372160D03*
X57400Y610900D03*
X29999Y849660D03*
X20499Y1315050D03*
X34999Y1572550D03*
X35900Y1832700D03*
X26499Y1935550D03*
X26999Y1941550D03*
X102999Y29050D03*
X100999Y468550D03*
X162500Y557500D03*
X109999Y872550D03*
X126999Y1119050D03*
X141499Y1267050D03*
X107699Y1510950D03*
X118999Y1525550D03*
X96999Y1632050D03*
X197226Y90428D03*
X202999Y90550D03*
X233100Y1929800D03*
X276500Y319500D03*
X288999Y723550D03*
X655049Y1810634D03*
X824499Y205050D03*
X807499Y1089550D03*
X803499Y1496050D03*
X814499Y1809050D03*
X806499Y1903550D03*
X914999Y103050D03*
X920999D03*
X843700Y312200D03*
X841500Y713000D03*
G54D47*
X49999Y1966250D03*
X143499Y517813D03*
X166499Y916313D03*
X136600Y1174600D03*
X107999Y1298313D03*
X109499Y1702813D03*
X218998Y312314D03*
X213598Y345314D03*
X218499Y719250D03*
X214599Y752250D03*
X217600Y1122200D03*
X217999Y1529250D03*
X218814Y1920313D03*
X213600Y1956800D03*
X297499Y86813D03*
X783049Y1813834D03*
X788049D03*
X858999Y306250D03*
X864900Y339300D03*
X855696Y706582D03*
X862896Y740782D03*
X855333Y1112092D03*
X862933Y1143592D03*
X857827Y1516996D03*
X865700Y1546800D03*
X857314Y1922813D03*
X864500Y1956600D03*
G54D93*
G01X174024Y533275D02*
X171570D01*
X171557Y533288D01*
G01X163877Y549468D02*
X160932D01*
G01X118549Y1485300D02*
X118217Y1484968D01*
X116058D01*
X116045Y1484981D01*
G01X241599Y102050D02*
X243999D01*
X245499Y100550D01*
G01X836249Y1788050D02*
Y1789350D01*
X833012Y1792587D01*
Y1798996D01*
X833013Y1798997D01*
G01X822512Y1815177D02*
X822499Y1815164D01*
G54D57*
X154521Y132477D03*
Y107677D03*
X133521Y132477D03*
Y107677D03*
X861999Y139450D03*
Y114650D03*
X882499Y139450D03*
Y114650D03*
G54D75*
X336000Y1962500D03*
Y1971500D03*
G54D39*
X14700Y1097500D03*
Y1102500D03*
X236699Y76550D03*
X889700Y1721500D03*
X952699Y89550D03*
G54D48*
X18499Y1923750D03*
X134300Y455000D03*
X139499Y488813D03*
X162499Y886313D03*
X162999Y852813D03*
X104499Y1267813D03*
X103999Y1235250D03*
X102100Y1638700D03*
X105499Y1673313D03*
X221498Y281314D03*
X221499Y687750D03*
X217500Y1084200D03*
X253200Y1534900D03*
X220999Y1497750D03*
X227814Y1891313D03*
X293999Y56313D03*
X289099Y23313D03*
X853978Y275124D03*
X852696Y676082D03*
X852333Y1081592D03*
X854327Y1486496D03*
X894800Y1704200D03*
X854814Y1892313D03*
G54D66*
X145000Y539050D03*
X141125Y531550D03*
X148875D03*
X129600Y1334250D03*
X125725Y1326750D03*
X133475D03*
X161700Y1689550D03*
X157825Y1682050D03*
X165575D03*
X183900Y925750D03*
X180025Y918250D03*
X187775D03*
X307000Y105150D03*
X303125Y97650D03*
X310875D03*
G54D84*
X882100Y1740700D03*
G54D94*
G01X77166Y934685D02*
X83331D01*
X83988Y934028D01*
G01X77166Y1736260D02*
X83209D01*
X84099Y1737150D01*
G01X159055Y1462953D02*
X152512D01*
X152499Y1462940D01*
G01X159055Y1868465D02*
X166735D01*
G01D02*
X167200Y1868000D01*
G01X893917Y246417D02*
X887401D01*
G01D02*
X881185D01*
X879878Y247724D01*
G54D67*
X156499Y1297113D03*
X161499D03*
X166499D03*
X171499D03*
Y1277113D03*
X166499D03*
X161499D03*
X156499D03*
X157499Y1720113D03*
X162499D03*
X167499D03*
X172499D03*
Y1700113D03*
X167499D03*
X162499D03*
X157499D03*
X191499Y534113D03*
X196499D03*
X201499D03*
X206499D03*
Y514113D03*
X201499D03*
X196499D03*
X191499D03*
X214999Y932613D03*
X219999D03*
X224999D03*
X229999D03*
Y912613D03*
X224999D03*
X219999D03*
X214999D03*
X247299Y1136650D03*
X242299D03*
X237299D03*
X232299D03*
Y1156650D03*
X237299D03*
X242299D03*
X247299D03*
X345999Y106550D03*
X350999D03*
X355999D03*
X360999D03*
Y86550D03*
X355999D03*
X350999D03*
X345999D03*
G54D76*
X666399Y1806699D03*
Y1808664D03*
Y1810634D03*
Y1812604D03*
Y1814569D03*
X682699D03*
Y1812604D03*
Y1810634D03*
Y1808664D03*
Y1806699D03*
G54D85*
X984808Y1447976D03*
Y1456976D03*
Y1460976D03*
Y1487976D03*
Y1496976D03*
Y1500976D03*
Y1526976D03*
Y1536976D03*
Y1540976D03*
X997607Y1605976D03*
X984808Y1566976D03*
Y1577976D03*
Y1582976D03*
G54D49*
X18499Y1929350D03*
X134300Y460600D03*
X139499Y494413D03*
X162499Y891913D03*
X162999Y858413D03*
X104499Y1273413D03*
X103999Y1240850D03*
X105499Y1678913D03*
X102100Y1644300D03*
X221498Y286914D03*
X221499Y693350D03*
X217500Y1089800D03*
X253200Y1540500D03*
X220999Y1503350D03*
X227814Y1896913D03*
X293999Y61913D03*
X289099Y28913D03*
X853978Y280724D03*
X852696Y681682D03*
X852333Y1087192D03*
X854327Y1492096D03*
X894800Y1709800D03*
X854814Y1897913D03*
G54D58*
X130400Y420900D03*
X159500Y821800D03*
X177500Y1276800D03*
X122799Y1485350D03*
X178999Y74850D03*
X235499Y84850D03*
X213499Y101350D03*
X216998Y287414D03*
X184000Y424300D03*
X212000Y513300D03*
X216999Y693850D03*
X207500Y822800D03*
X222900Y1090100D03*
X216999Y1503850D03*
X253500Y1911300D03*
X232314Y1897413D03*
X327500Y354800D03*
X312800Y321100D03*
X308999Y728350D03*
X311000Y758300D03*
X309299Y1536750D03*
X313499Y1931850D03*
X366500Y86300D03*
X655549Y1796434D03*
Y1803934D03*
X755500Y709800D03*
X693549Y1801934D03*
Y1809434D03*
X816500Y286300D03*
X764500Y308300D03*
X779978Y308224D03*
X769000Y355800D03*
X810000Y690800D03*
X777500Y709800D03*
X816000Y1094300D03*
X760500Y1110800D03*
X778500D03*
X767000Y1158800D03*
X816000Y1497800D03*
X783200Y1516500D03*
X762000Y1516800D03*
X770500Y1561800D03*
X815500Y1904300D03*
X769000Y1964300D03*
X759500Y1922800D03*
X784500D03*
X904499Y88350D03*
X858478Y281224D03*
X857196Y682182D03*
X856833Y1087692D03*
X858827Y1492596D03*
X859314Y1898413D03*
X928499Y111850D03*
G54D95*
G01X140940Y557700D02*
Y561800D01*
G01X173100Y483100D02*
X175793Y485793D01*
X176999D01*
G01X156500Y554000D02*
X152500D01*
X148800Y550300D01*
X146060D01*
G01X141300Y565900D02*
X142100D01*
X146060Y561940D01*
Y557700D01*
G01X138416Y553500D02*
X140940Y550976D01*
Y550300D01*
G01X172660Y815731D02*
X172559Y815832D01*
Y820363D01*
G01X163500Y937100D02*
X170900Y944500D01*
X181340D01*
G01X170250Y948500D02*
X171250Y949500D01*
X185500D01*
X186500Y948500D01*
Y944540D01*
X186460Y944500D01*
G01X171000Y939500D02*
X173400Y937100D01*
X181340D01*
G01X106999Y1114960D02*
Y1114550D01*
X106099Y1113650D01*
Y1111760D01*
G01X135850Y1322250D02*
X138140Y1324540D01*
X140000D01*
G01X148024Y1333525D02*
X147400Y1332901D01*
Y1329660D01*
G01X140000D02*
Y1332600D01*
G01X147400Y1324540D02*
Y1321600D01*
G01X172240Y1685800D02*
X169100D01*
G01X117249Y1714990D02*
Y1712090D01*
G01X141500Y1715500D02*
X140800Y1714800D01*
X138059D01*
G01X181100Y1682700D02*
Y1680100D01*
X179400Y1678400D01*
X177360D01*
G01X177900Y1690400D02*
X177360Y1689860D01*
Y1685800D01*
G01X169600Y1682300D02*
X172240Y1679660D01*
Y1678400D01*
G01X242040Y282500D02*
Y287074D01*
X242000Y287114D01*
G01X247160Y275100D02*
X250300D01*
G01X250400Y283100D02*
X249800Y282500D01*
X247160D01*
G01X239600Y278600D02*
X242040Y276160D01*
Y275100D01*
G01X241440Y689900D02*
Y693510D01*
X241400Y693550D01*
G01X246560Y682500D02*
X249700D01*
G01X246560Y689900D02*
X249800D01*
G01X199000Y815000D02*
X196000D01*
X189199Y821801D01*
Y831553D01*
G01X200539Y890300D02*
X202039Y891800D01*
X203439D01*
G01X212486Y937100D02*
X214999Y939613D01*
G01X186460Y937100D02*
X212486D01*
G01X233500Y1066100D02*
X234600Y1067200D01*
Y1069000D01*
G01X269500Y1135500D02*
Y1132332D01*
X264300Y1127132D01*
Y1107481D01*
X246319Y1089500D01*
X239786D01*
X237950Y1087664D01*
Y1081050D01*
X242000Y1077000D01*
Y1074120D01*
G01X229800Y1073600D02*
X230320Y1074120D01*
X234600D01*
G01X242000Y1069000D02*
Y1066000D01*
G01X229025Y1471576D02*
X230689Y1473240D01*
X233600D01*
G01X241000Y1469600D02*
Y1473240D01*
G01Y1478360D02*
Y1485100D01*
X251000Y1495100D01*
Y1504400D01*
G01X233700Y1481600D02*
X233600Y1481500D01*
Y1478360D01*
G01X179999Y1652987D02*
Y1655887D01*
G01X186000Y1644000D02*
Y1646468D01*
X187399Y1647867D01*
G01X223436Y1890465D02*
X223300Y1890329D01*
Y1886200D01*
X225500Y1884000D01*
Y1882960D01*
G01X249600Y1896800D02*
Y1879781D01*
X241919Y1872100D01*
X220400D01*
X218100Y1874400D01*
Y1877840D01*
G01X229800Y1875700D02*
X227660Y1877840D01*
X225500D01*
G01X218100Y1882960D02*
Y1886400D01*
G01X343499Y60150D02*
X345339Y61990D01*
X347749D01*
G01X308999Y87050D02*
X314289Y92340D01*
X317400D01*
G01X344450Y100550D02*
X341360Y97460D01*
X324800D01*
G01X315800Y100500D02*
X317400Y98900D01*
Y97460D01*
G01X324800Y92340D02*
Y89400D01*
G01X315939Y352350D02*
X313039D01*
G01X278939Y333800D02*
Y337459D01*
X277799Y338599D01*
G01X315000Y754500D02*
Y755051D01*
X316939Y756990D01*
Y759350D01*
G01X324200Y1966472D02*
X327100D01*
G01X329999Y1952273D02*
Y1951550D01*
X327918Y1949469D01*
X326971D01*
G01X315999Y1958550D02*
X316521Y1959072D01*
X319080D01*
G01X280689Y1942710D02*
X280699Y1942700D01*
X283589D01*
G01X386799Y41610D02*
Y45000D01*
G01X398799Y36152D02*
X398461Y36490D01*
X394199D01*
G01X381999Y50150D02*
X382839Y50990D01*
X387749D01*
G01X345999Y100550D02*
X344450D01*
G01X756996Y742442D02*
Y744839D01*
X757499Y745342D01*
G01X754000Y1551000D02*
X755644Y1549356D01*
X759127D01*
G01X757114Y1954773D02*
X752773D01*
X752500Y1954500D01*
G01X822100Y270060D02*
Y279500D01*
G01X814700Y264940D02*
X809940D01*
G01X822100D02*
Y261700D01*
G01X816700Y274300D02*
X814700Y272300D01*
Y270060D01*
G01X790559Y316110D02*
Y321300D01*
G01X784499Y334050D02*
X785439Y333110D01*
Y327800D01*
G01X820600Y682050D02*
Y672660D01*
G01X784939Y728800D02*
Y733550D01*
G01X813200Y667540D02*
X808660D01*
G01X820600D02*
Y664300D01*
G01X813200Y672660D02*
Y675900D01*
G01X764396Y737322D02*
Y735896D01*
X762500Y734000D01*
G01X766946Y729942D02*
Y732395D01*
X766499Y732842D01*
G01X820300Y1075460D02*
Y1079100D01*
X816000Y1083400D01*
G01X789559Y1119110D02*
Y1125300D01*
G01X767083Y1131452D02*
Y1134550D01*
G01X764549Y1138500D02*
X764500Y1138549D01*
Y1141189D01*
X764199Y1141490D01*
G01X807000Y1072900D02*
X809560Y1070340D01*
X812900D01*
G01X825800Y1072300D02*
X823840Y1070340D01*
X820300D01*
G01X822100Y1478040D02*
Y1470700D01*
G01D02*
Y1466800D01*
G01Y1490900D02*
Y1483160D01*
G01X814700Y1478040D02*
X809960D01*
G01X814700Y1483160D02*
Y1486300D01*
G01X822700Y1887560D02*
Y1888800D01*
X817386Y1894114D01*
Y1895000D01*
G01X815300Y1882440D02*
X810900D01*
G01X822700Y1871100D02*
Y1875100D01*
G01D02*
Y1882440D01*
G01X815300Y1887560D02*
X809600D01*
G01D02*
X805900D01*
G54D68*
X105749Y1964050D03*
X121249D03*
X221749Y39550D03*
X206249D03*
X915749Y44550D03*
X931249D03*
G54D77*
X753949Y1801294D03*
Y1803854D03*
Y1806414D03*
Y1808974D03*
X776149Y1803854D03*
Y1801294D03*
Y1808974D03*
Y1806414D03*
G54D59*
X130400Y417300D03*
X159500Y818200D03*
X177500Y1273200D03*
X122799Y1481750D03*
X178999Y71250D03*
X235499Y81250D03*
X213499Y97750D03*
X216998Y283814D03*
X184000Y420700D03*
X212000Y509700D03*
X216999Y690250D03*
X207500Y819200D03*
X222900Y1086500D03*
X216999Y1500250D03*
X253500Y1907700D03*
X232314Y1893813D03*
X327500Y351200D03*
X312800Y317500D03*
X308999Y724750D03*
X311000Y754700D03*
X309299Y1533150D03*
X313499Y1928250D03*
X366500Y82700D03*
X655549Y1792834D03*
Y1800334D03*
X755500Y706200D03*
X693549Y1798334D03*
Y1805834D03*
X816500Y282700D03*
X764500Y304700D03*
X779978Y304624D03*
X769000Y352200D03*
X810000Y687200D03*
X777500Y706200D03*
X816000Y1090700D03*
X760500Y1107200D03*
X778500D03*
X767000Y1155200D03*
X816000Y1494200D03*
X783200Y1512900D03*
X762000Y1513200D03*
X770500Y1558200D03*
X815500Y1900700D03*
X769000Y1960700D03*
X759500Y1919200D03*
X784500D03*
X904499Y84750D03*
X858478Y277624D03*
X857196Y678582D03*
X856833Y1084092D03*
X858827Y1488996D03*
X859314Y1894813D03*
X928499Y108250D03*
G54D86*
X997608Y1492322D03*
Y1452322D03*
Y1572322D03*
Y1532322D03*
G54D96*
G01X12380Y309561D02*
X29532D01*
G01X12380Y1029522D02*
X29532D01*
G01X68898Y12645D02*
Y17047D01*
G01D02*
Y21449D01*
G01X62346Y17047D02*
X68898D01*
G01D02*
X75450D01*
G01X68898Y185873D02*
Y190275D01*
G01D02*
Y194677D01*
G01X62346Y190275D02*
X68898D01*
G01D02*
X75450D01*
G01X29532Y292409D02*
Y309561D01*
G01D02*
Y326713D01*
G01Y309561D02*
X46684D01*
G01X68898Y418157D02*
Y422559D01*
G01D02*
Y426961D01*
G01X62346Y422559D02*
X68898D01*
G01D02*
X75450D01*
G01X68898Y591385D02*
Y595787D01*
G01D02*
Y600189D01*
G01X62346Y595787D02*
X68898D01*
G01D02*
X75450D01*
G01X29532Y1012370D02*
Y1029522D01*
G01D02*
Y1046674D01*
G01Y1029522D02*
X46684D01*
G01X68898Y996897D02*
Y1001299D01*
G01D02*
Y1005701D01*
G01X62346Y1001299D02*
X68898D01*
G01D02*
X75450D01*
G01X96100Y1384650D02*
X94114Y1382664D01*
X85643D01*
X85630Y1382677D01*
G01X68898Y1634693D02*
Y1639095D01*
G01D02*
Y1643497D01*
G01X62346Y1639095D02*
X68898D01*
G01X17720Y1885992D02*
Y1903144D01*
G01D02*
X34872D01*
G01X112768Y17716D02*
X129920D01*
G01D02*
X147072D01*
G01X167323Y175401D02*
Y179803D01*
G01D02*
Y184205D01*
G01X160771Y179803D02*
X167323D01*
G01D02*
X173875D01*
G01X167323Y348629D02*
Y353031D01*
G01D02*
Y357433D01*
G01X160771Y353031D02*
X167323D01*
G01D02*
X173875D01*
G01X167323Y580913D02*
Y585315D01*
G01D02*
Y589717D01*
G01X160771Y585315D02*
X167323D01*
G01D02*
X173875D01*
G01X167323Y754141D02*
Y758543D01*
G01D02*
Y762945D01*
G01X160771Y758543D02*
X167323D01*
G01D02*
X173875D01*
G01X167323Y1159653D02*
Y1164055D01*
G01D02*
Y1168457D01*
G01X160771Y1164055D02*
X167323D01*
G01D02*
X173875D01*
G01X167323Y1391937D02*
Y1396339D01*
G01D02*
Y1400741D01*
G01X160771Y1396339D02*
X167323D01*
G01D02*
X173875D01*
G01X167323Y1565165D02*
Y1569567D01*
G01D02*
Y1573969D01*
G01X160771Y1569567D02*
X167323D01*
G01D02*
X173875D01*
G01X167323Y1797449D02*
Y1801851D01*
G01X160771D02*
X167323D01*
G01D02*
X173875D01*
G01X167323Y1970677D02*
Y1975079D01*
G01D02*
Y1979481D01*
G01X160771Y1975079D02*
X167323D01*
G01D02*
X173875D01*
G01X254505Y267711D02*
X271657D01*
G01X254505Y673223D02*
X271657D01*
G01X254505Y1484246D02*
X271657D01*
G01X254505Y1889758D02*
X271657D01*
G01Y250559D02*
Y267711D01*
G01D02*
X288809D01*
G01X271657Y656071D02*
Y673223D01*
G01D02*
X288809D01*
G01X271657Y1061582D02*
Y1078734D01*
G01D02*
Y1095886D01*
G01Y1078734D02*
X288809D01*
G01X271657Y1484246D02*
X288809D01*
G01X271657Y1872606D02*
Y1889758D01*
G01D02*
Y1906910D01*
G01Y1889758D02*
X288809D01*
G01X895669Y175401D02*
Y179803D01*
G01D02*
Y184205D01*
G01X889117Y179803D02*
X895669D01*
G01D02*
X902221D01*
G01X895669Y348629D02*
Y353031D01*
G01D02*
Y357433D01*
G01X889117Y353031D02*
X895669D01*
G01D02*
X902221D01*
G01X895669Y580913D02*
Y585315D01*
G01D02*
Y589717D01*
G01X889117Y585315D02*
X895669D01*
G01D02*
X902221D01*
G01X895669Y754141D02*
Y758543D01*
G01D02*
Y762945D01*
G01X889117Y758543D02*
X895669D01*
G01D02*
X902221D01*
G01X895669Y986425D02*
Y990827D01*
G01D02*
Y995229D01*
G01X889117Y990827D02*
X895669D01*
G01D02*
X902221D01*
G01X895669Y1159653D02*
Y1164055D01*
G01D02*
Y1168457D01*
G01X889117Y1164055D02*
X895669D01*
G01D02*
X902221D01*
G01X895669Y1391937D02*
Y1396339D01*
G01D02*
Y1400741D01*
G01X889117Y1396339D02*
X895669D01*
G01D02*
X902221D01*
G01X895669Y1565165D02*
Y1569567D01*
G01D02*
Y1573969D01*
G01X889117Y1569567D02*
X895669D01*
G01D02*
X902221D01*
G01X895669Y1797449D02*
Y1801851D01*
G01D02*
Y1806253D01*
G01X889117Y1801851D02*
X895669D01*
G01D02*
X902221D01*
G01X895669Y1970677D02*
Y1975079D01*
G01D02*
Y1979481D01*
G01X889117Y1975079D02*
X895669D01*
G01D02*
X902221D01*
G01X994098Y132449D02*
Y149601D01*
G01D02*
Y166753D01*
G01X976946Y149601D02*
X994098D01*
G01D02*
X1011250D01*
G01X994098Y656071D02*
Y673223D01*
G01D02*
Y690375D01*
G01X976946Y673223D02*
X994098D01*
G01D02*
X1011250D01*
G01X994099Y1051740D02*
Y1068892D01*
G01D02*
Y1086044D01*
G01X976947Y1068892D02*
X994099D01*
G01D02*
X1011251D01*
G01X994093Y1872599D02*
Y1889751D01*
G01D02*
Y1906903D01*
G01X976941Y1889751D02*
X994093D01*
G01D02*
X1011245D01*
G54D78*
X829112Y1734500D03*
G54D87*
X997607Y1602322D03*
G54D69*
X210676Y72528D03*
X928499Y85550D03*
G54D97*
G01X-89222Y-207897D02*
Y-190397D01*
G01X-80052D02*
Y-207897D01*
G01Y-199147D02*
X-89222D01*
G01X-67137Y-207897D02*
X-68447Y-207605D01*
X-69757Y-206439D01*
X-70631Y-204397D01*
X-71067Y-202064D01*
X-70631Y-199730D01*
X-69757Y-197689D01*
X-68447Y-196522D01*
X-67137Y-196231D01*
X-65827Y-196522D01*
X-64517Y-197689D01*
X-63644Y-199730D01*
X-63425Y-202064D01*
X-63644Y-204397D01*
X-64517Y-206439D01*
X-65827Y-207605D01*
X-67137Y-207897D01*
G01X-53349D02*
Y-196231D01*
G01Y-199147D02*
X-52475Y-197689D01*
X-51165Y-196522D01*
X-49419Y-196231D01*
X-47891Y-196522D01*
X-46580Y-197689D01*
X-45925Y-199730D01*
Y-207897D01*
G01X-35412Y-200022D02*
X-28425D01*
X-29080Y-197980D01*
X-30172Y-196814D01*
X-31700Y-196231D01*
X-33229Y-196522D01*
X-34539Y-197397D01*
X-35412Y-199439D01*
X-35849Y-201189D01*
Y-202939D01*
X-35412Y-204689D01*
X-34320Y-206439D01*
X-33010Y-207605D01*
X-31482Y-207897D01*
X-29954Y-207314D01*
X-28425Y-205564D01*
G01X-19222Y-213147D02*
X-17912Y-213730D01*
X-16165Y-213147D01*
X-15074Y-211981D01*
X-14200Y-210522D01*
X-12891Y-205856D01*
X-10052Y-196231D01*
G01X-17039D02*
X-12891Y-205856D01*
G01X22109Y-198564D02*
X22983Y-197689D01*
X23638Y-196231D01*
X24075Y-194188D01*
X23638Y-192439D01*
X22765Y-191272D01*
X21236Y-190397D01*
X15341D01*
Y-207897D01*
X22546D01*
X24075Y-206731D01*
X24948Y-204980D01*
X25385Y-202939D01*
X24948Y-200897D01*
X23638Y-199147D01*
X22109Y-198564D01*
X15341D01*
G01X41793Y-207897D02*
Y-196231D01*
G01Y-198272D02*
X40920Y-197106D01*
X39609Y-196522D01*
X38081Y-196231D01*
X36553Y-196814D01*
X35243Y-197980D01*
X34369Y-199730D01*
X33933Y-202064D01*
X34369Y-204397D01*
X35243Y-206147D01*
X36553Y-207314D01*
X38081Y-207897D01*
X39609Y-207605D01*
X40920Y-206731D01*
X41793Y-205564D01*
G01X59293Y-190397D02*
Y-207897D01*
G01Y-205273D02*
X58420Y-206731D01*
X57109Y-207605D01*
X55581Y-207897D01*
X53835Y-207314D01*
X52525Y-205856D01*
X51651Y-204106D01*
X51433Y-202064D01*
X51651Y-200022D01*
X52525Y-198272D01*
X53835Y-196814D01*
X55581Y-196231D01*
X57109Y-196522D01*
X58201Y-197106D01*
X59293Y-198272D01*
G01X69806Y-212272D02*
X71335Y-213439D01*
X73081Y-213730D01*
X74609Y-213439D01*
X75920Y-211981D01*
X76793Y-209939D01*
Y-196231D01*
G01Y-198564D02*
X75920Y-197397D01*
X74609Y-196522D01*
X73081Y-196231D01*
X71335Y-196814D01*
X70243Y-197980D01*
X69369Y-200022D01*
X68933Y-202064D01*
X69151Y-203814D01*
X70025Y-205856D01*
X71335Y-207314D01*
X73081Y-207897D01*
X74391Y-207605D01*
X75920Y-206439D01*
X76793Y-205273D01*
G01X87088Y-200022D02*
X94075D01*
X93420Y-197980D01*
X92328Y-196814D01*
X90800Y-196231D01*
X89271Y-196522D01*
X87961Y-197397D01*
X87088Y-199439D01*
X86651Y-201189D01*
Y-202939D01*
X87088Y-204689D01*
X88180Y-206439D01*
X89490Y-207605D01*
X91018Y-207897D01*
X92546Y-207314D01*
X94075Y-205564D01*
G01X104806Y-207897D02*
Y-196231D01*
G01Y-198564D02*
X105898Y-197397D01*
X106990Y-196522D01*
X108518Y-196231D01*
X109609Y-196522D01*
X110920Y-197397D01*
G01X138060Y-207897D02*
Y-190397D01*
X142426D01*
X144173Y-191272D01*
X145483Y-192439D01*
X146575Y-194188D01*
X147448Y-196231D01*
X147666Y-199147D01*
X147448Y-202064D01*
X146575Y-204106D01*
X145483Y-205856D01*
X144173Y-207022D01*
X142426Y-207897D01*
X138060D01*
G01X155996D02*
Y-190397D01*
X161236D01*
X162983Y-191272D01*
X164293Y-193314D01*
X164730Y-195647D01*
X164293Y-197980D01*
X163201Y-199730D01*
X161236Y-200606D01*
X155996D01*
G01X179609Y-198564D02*
X180483Y-197689D01*
X181138Y-196231D01*
X181575Y-194188D01*
X181138Y-192439D01*
X180265Y-191272D01*
X178736Y-190397D01*
X172841D01*
Y-207897D01*
X180046D01*
X181575Y-206731D01*
X182448Y-204980D01*
X182885Y-202939D01*
X182448Y-200897D01*
X181138Y-199147D01*
X179609Y-198564D01*
X172841D01*
G01X208496Y-190397D02*
Y-207897D01*
X217230D01*
G01X230363D02*
X229053Y-207605D01*
X227743Y-206439D01*
X226869Y-204397D01*
X226433Y-202064D01*
X226869Y-199730D01*
X227743Y-197689D01*
X229053Y-196522D01*
X230363Y-196231D01*
X231673Y-196522D01*
X232983Y-197689D01*
X233856Y-199730D01*
X234075Y-202064D01*
X233856Y-204397D01*
X232983Y-206439D01*
X231673Y-207605D01*
X230363Y-207897D01*
G01X242404Y-196231D02*
X245025Y-207897D01*
X247863Y-196231D01*
X250701Y-207897D01*
X253322Y-196231D01*
G01X278496Y-190397D02*
Y-207897D01*
X287230D01*
G01X300363D02*
X299053Y-207605D01*
X297743Y-206439D01*
X296869Y-204397D01*
X296433Y-202064D01*
X296869Y-199730D01*
X297743Y-197689D01*
X299053Y-196522D01*
X300363Y-196231D01*
X301673Y-196522D01*
X302983Y-197689D01*
X303856Y-199730D01*
X304075Y-202064D01*
X303856Y-204397D01*
X302983Y-206439D01*
X301673Y-207605D01*
X300363Y-207897D01*
G01X314588Y-205856D02*
X315680Y-207022D01*
X317208Y-207897D01*
X318518D01*
X319828Y-207314D01*
X320701Y-206439D01*
X321138Y-205273D01*
X320920Y-203522D01*
X320046Y-202647D01*
X316116Y-200897D01*
X315243Y-198855D01*
X315680Y-197397D01*
X316553Y-196522D01*
X317863Y-196231D01*
X319173Y-196522D01*
X320483Y-197397D01*
G01X332088Y-205856D02*
X333180Y-207022D01*
X334708Y-207897D01*
X336018D01*
X337328Y-207314D01*
X338201Y-206439D01*
X338638Y-205273D01*
X338420Y-203522D01*
X337546Y-202647D01*
X333616Y-200897D01*
X332743Y-198855D01*
X333180Y-197397D01*
X334053Y-196522D01*
X335363Y-196231D01*
X336673Y-196522D01*
X337983Y-197397D01*
G01X94686Y-164897D02*
Y-147397D01*
X100363Y-161980D01*
X106040Y-147397D01*
Y-164897D01*
G01X117863D02*
X116553Y-164605D01*
X115243Y-163439D01*
X114369Y-161397D01*
X113933Y-159064D01*
X114369Y-156730D01*
X115243Y-154689D01*
X116553Y-153522D01*
X117863Y-153231D01*
X119173Y-153522D01*
X120483Y-154689D01*
X121356Y-156730D01*
X121575Y-159064D01*
X121356Y-161397D01*
X120483Y-163439D01*
X119173Y-164605D01*
X117863Y-164897D01*
G01X139293Y-147397D02*
Y-164897D01*
G01Y-162273D02*
X138420Y-163731D01*
X137109Y-164605D01*
X135581Y-164897D01*
X133835Y-164314D01*
X132525Y-162856D01*
X131651Y-161106D01*
X131433Y-159064D01*
X131651Y-157022D01*
X132525Y-155272D01*
X133835Y-153814D01*
X135581Y-153231D01*
X137109Y-153522D01*
X138201Y-154106D01*
X139293Y-155272D01*
G01X149588Y-157022D02*
X156575D01*
X155920Y-154980D01*
X154828Y-153814D01*
X153300Y-153231D01*
X151771Y-153522D01*
X150461Y-154397D01*
X149588Y-156439D01*
X149151Y-158189D01*
Y-159939D01*
X149588Y-161689D01*
X150680Y-163439D01*
X151990Y-164605D01*
X153518Y-164897D01*
X155046Y-164314D01*
X156575Y-162564D01*
G01X170363Y-164897D02*
Y-147397D01*
G01X376163Y-209897D02*
Y-192397D01*
X373543Y-195897D01*
G01Y-209897D02*
X378783D01*
G01X396283D02*
Y-192397D01*
X388204Y-204939D01*
X399122D01*
G01X406360Y-207273D02*
X407669Y-208731D01*
X409198Y-209605D01*
X411163Y-209897D01*
X413128Y-209314D01*
X414656Y-208147D01*
X415748Y-206106D01*
X415966Y-203772D01*
X415530Y-201439D01*
X414438Y-199980D01*
X412909Y-198814D01*
X411381Y-198522D01*
X409853Y-198814D01*
X407888Y-199980D01*
X408543Y-192397D01*
X414438D01*
G01X431283Y-209897D02*
Y-192397D01*
X423204Y-204939D01*
X434122D01*
G01X441360Y-207273D02*
X442669Y-208731D01*
X444198Y-209605D01*
X446163Y-209897D01*
X448128Y-209314D01*
X449656Y-208147D01*
X450748Y-206106D01*
X450966Y-203772D01*
X450530Y-201439D01*
X449438Y-199980D01*
X447909Y-198814D01*
X446381Y-198522D01*
X444853Y-198814D01*
X442888Y-199980D01*
X443543Y-192397D01*
X449438D01*
G01X363046Y-164897D02*
Y-147397D01*
X368286D01*
X370033Y-148272D01*
X371343Y-150314D01*
X371780Y-152647D01*
X371343Y-154980D01*
X370251Y-156730D01*
X368286Y-157606D01*
X363046D01*
G01X389716Y-148856D02*
X388406Y-147980D01*
X386878Y-147397D01*
X385131D01*
X383166Y-148272D01*
X381638Y-149730D01*
X380546Y-151481D01*
X379673Y-154397D01*
X379454Y-157022D01*
X379891Y-159647D01*
X380546Y-161397D01*
X381856Y-163147D01*
X383385Y-164314D01*
X384913Y-164897D01*
X386441D01*
X387970Y-164314D01*
X389280Y-163439D01*
X390372Y-162273D01*
G01X404159Y-155564D02*
X405033Y-154689D01*
X405688Y-153231D01*
X406125Y-151188D01*
X405688Y-149439D01*
X404815Y-148272D01*
X403286Y-147397D01*
X397391D01*
Y-164897D01*
X404596D01*
X406125Y-163731D01*
X406998Y-161980D01*
X407435Y-159939D01*
X406998Y-157897D01*
X405688Y-156147D01*
X404159Y-155564D01*
X397391D01*
G01X413363Y-170730D02*
X426463D01*
G01X432391Y-164897D02*
Y-147397D01*
X442435Y-164897D01*
Y-147397D01*
G01X454913Y-164897D02*
X453166Y-164605D01*
X451638Y-163439D01*
X450328Y-161689D01*
X449454Y-159647D01*
X449018Y-157314D01*
Y-154980D01*
X449454Y-152647D01*
X450328Y-150605D01*
X451638Y-148856D01*
X453166Y-147689D01*
X454913Y-147397D01*
X456659Y-147689D01*
X458188Y-148856D01*
X459498Y-150605D01*
X460372Y-152647D01*
X460808Y-154980D01*
Y-157314D01*
X460372Y-159647D01*
X459498Y-161689D01*
X458188Y-163439D01*
X456659Y-164605D01*
X454913Y-164897D01*
G01X505754Y-147397D02*
X511213Y-164897D01*
X516672Y-147397D01*
G01X533080Y-164897D02*
X524346D01*
Y-147397D01*
X533080D01*
G01X529586Y-155855D02*
X524346D01*
G01X541846Y-164897D02*
Y-147397D01*
X547305D01*
X549051Y-148272D01*
X550143Y-149439D01*
X550580Y-151772D01*
X550143Y-154106D01*
X548833Y-155564D01*
X547305Y-156439D01*
X541846D01*
G01X547305D02*
X550580Y-164897D01*
G01X563713Y-165480D02*
X563276Y-165189D01*
Y-164605D01*
X563713Y-164314D01*
X564150Y-164605D01*
Y-165189D01*
X563713Y-165480D01*
G01X524128Y-207564D02*
X525875Y-209022D01*
X527840Y-209897D01*
X529586D01*
X531333Y-209022D01*
X532643Y-207564D01*
X533298Y-205522D01*
X532861Y-203481D01*
X531770Y-201730D01*
X529805Y-200564D01*
X527185Y-199980D01*
X525656Y-198814D01*
X525001Y-196772D01*
X525438Y-194730D01*
X526530Y-193272D01*
X528058Y-192397D01*
X529586D01*
X531115Y-192980D01*
X532425Y-194439D01*
G01X540754Y-209897D02*
X546213Y-192397D01*
X551672Y-209897D01*
G01X549706Y-203772D02*
X542719D01*
G01X665546Y-192397D02*
Y-209897D01*
X674280D01*
G01X687413D02*
Y-192397D01*
X684793Y-195897D01*
G01Y-209897D02*
X690033D01*
G01X630546Y-147397D02*
Y-164897D01*
X639280D01*
G01X656343D02*
Y-153231D01*
G01Y-155272D02*
X655470Y-154106D01*
X654159Y-153522D01*
X652631Y-153231D01*
X651103Y-153814D01*
X649793Y-154980D01*
X648919Y-156730D01*
X648483Y-159064D01*
X648919Y-161397D01*
X649793Y-163147D01*
X651103Y-164314D01*
X652631Y-164897D01*
X654159Y-164605D01*
X655470Y-163731D01*
X656343Y-162564D01*
G01X665328Y-170147D02*
X666638Y-170730D01*
X668385Y-170147D01*
X669476Y-168981D01*
X670350Y-167522D01*
X671659Y-162856D01*
X674498Y-153231D01*
G01X667511D02*
X671659Y-162856D01*
G01X684138Y-157022D02*
X691125D01*
X690470Y-154980D01*
X689378Y-153814D01*
X687850Y-153231D01*
X686321Y-153522D01*
X685011Y-154397D01*
X684138Y-156439D01*
X683701Y-158189D01*
Y-159939D01*
X684138Y-161689D01*
X685230Y-163439D01*
X686540Y-164605D01*
X688068Y-164897D01*
X689596Y-164314D01*
X691125Y-162564D01*
G01X701856Y-164897D02*
Y-153231D01*
G01Y-155564D02*
X702948Y-154397D01*
X704040Y-153522D01*
X705568Y-153231D01*
X706659Y-153522D01*
X707970Y-154397D01*
G01X719138Y-162856D02*
X720230Y-164022D01*
X721758Y-164897D01*
X723068D01*
X724378Y-164314D01*
X725251Y-163439D01*
X725688Y-162273D01*
X725470Y-160522D01*
X724596Y-159647D01*
X720666Y-157897D01*
X719793Y-155855D01*
X720230Y-154397D01*
X721103Y-153522D01*
X722413Y-153231D01*
X723723Y-153522D01*
X725033Y-154397D01*
G01X790596Y-209897D02*
Y-192397D01*
X796055D01*
X797801Y-193272D01*
X798893Y-194439D01*
X799330Y-196772D01*
X798893Y-199106D01*
X797583Y-200564D01*
X796055Y-201439D01*
X790596D01*
G01X796055D02*
X799330Y-209897D01*
G01X809188Y-202022D02*
X816175D01*
X815520Y-199980D01*
X814428Y-198814D01*
X812900Y-198231D01*
X811371Y-198522D01*
X810061Y-199397D01*
X809188Y-201439D01*
X808751Y-203189D01*
Y-204939D01*
X809188Y-206689D01*
X810280Y-208439D01*
X811590Y-209605D01*
X813118Y-209897D01*
X814646Y-209314D01*
X816175Y-207564D01*
G01X826033Y-209897D02*
Y-192397D01*
G01Y-201147D02*
X827125Y-199397D01*
X828435Y-198522D01*
X829745Y-198231D01*
X831709Y-198814D01*
X833020Y-199980D01*
X833893Y-202022D01*
Y-204355D01*
X833456Y-206689D01*
X832583Y-208439D01*
X831055Y-209605D01*
X829745Y-209897D01*
X828435Y-209605D01*
X827125Y-208731D01*
X826033Y-207273D01*
G01X844188Y-202022D02*
X851175D01*
X850520Y-199980D01*
X849428Y-198814D01*
X847900Y-198231D01*
X846371Y-198522D01*
X845061Y-199397D01*
X844188Y-201439D01*
X843751Y-203189D01*
Y-204939D01*
X844188Y-206689D01*
X845280Y-208439D01*
X846590Y-209605D01*
X848118Y-209897D01*
X849646Y-209314D01*
X851175Y-207564D01*
G01X868456Y-199689D02*
X866928Y-198522D01*
X865618Y-198231D01*
X863871Y-198814D01*
X862561Y-199980D01*
X861688Y-202022D01*
X861469Y-204064D01*
X861688Y-206106D01*
X862561Y-207856D01*
X863871Y-209314D01*
X865618Y-209897D01*
X867146Y-209314D01*
X868456Y-208147D01*
G01X885956Y-199689D02*
X884428Y-198522D01*
X883118Y-198231D01*
X881371Y-198814D01*
X880061Y-199980D01*
X879188Y-202022D01*
X878969Y-204064D01*
X879188Y-206106D01*
X880061Y-207856D01*
X881371Y-209314D01*
X883118Y-209897D01*
X884646Y-209314D01*
X885956Y-208147D01*
G01X903893Y-209897D02*
Y-198231D01*
G01Y-200272D02*
X903020Y-199106D01*
X901709Y-198522D01*
X900181Y-198231D01*
X898653Y-198814D01*
X897343Y-199980D01*
X896469Y-201730D01*
X896033Y-204064D01*
X896469Y-206397D01*
X897343Y-208147D01*
X898653Y-209314D01*
X900181Y-209897D01*
X901709Y-209605D01*
X903020Y-208731D01*
X903893Y-207564D01*
G01X781410Y-164897D02*
Y-147397D01*
X785776D01*
X787523Y-148272D01*
X788833Y-149439D01*
X789925Y-151188D01*
X790798Y-153231D01*
X791016Y-156147D01*
X790798Y-159064D01*
X789925Y-161106D01*
X788833Y-162856D01*
X787523Y-164022D01*
X785776Y-164897D01*
X781410D01*
G01X800438Y-157022D02*
X807425D01*
X806770Y-154980D01*
X805678Y-153814D01*
X804150Y-153231D01*
X802621Y-153522D01*
X801311Y-154397D01*
X800438Y-156439D01*
X800001Y-158189D01*
Y-159939D01*
X800438Y-161689D01*
X801530Y-163439D01*
X802840Y-164605D01*
X804368Y-164897D01*
X805896Y-164314D01*
X807425Y-162564D01*
G01X817938Y-162856D02*
X819030Y-164022D01*
X820558Y-164897D01*
X821868D01*
X823178Y-164314D01*
X824051Y-163439D01*
X824488Y-162273D01*
X824270Y-160522D01*
X823396Y-159647D01*
X819466Y-157897D01*
X818593Y-155855D01*
X819030Y-154397D01*
X819903Y-153522D01*
X821213Y-153231D01*
X822523Y-153522D01*
X823833Y-154397D01*
G01X838713Y-153231D02*
Y-164897D01*
G01Y-148564D02*
X838276Y-148272D01*
Y-147689D01*
X838713Y-147397D01*
X839150Y-147689D01*
Y-148272D01*
X838713Y-148564D01*
G01X853156Y-169272D02*
X854685Y-170439D01*
X856431Y-170730D01*
X857959Y-170439D01*
X859270Y-168981D01*
X860143Y-166939D01*
Y-153231D01*
G01Y-155564D02*
X859270Y-154397D01*
X857959Y-153522D01*
X856431Y-153231D01*
X854685Y-153814D01*
X853593Y-154980D01*
X852719Y-157022D01*
X852283Y-159064D01*
X852501Y-160814D01*
X853375Y-162856D01*
X854685Y-164314D01*
X856431Y-164897D01*
X857741Y-164605D01*
X859270Y-163439D01*
X860143Y-162273D01*
G01X870001Y-164897D02*
Y-153231D01*
G01Y-156147D02*
X870875Y-154689D01*
X872185Y-153522D01*
X873931Y-153231D01*
X875459Y-153522D01*
X876770Y-154689D01*
X877425Y-156730D01*
Y-164897D01*
G01X887938Y-157022D02*
X894925D01*
X894270Y-154980D01*
X893178Y-153814D01*
X891650Y-153231D01*
X890121Y-153522D01*
X888811Y-154397D01*
X887938Y-156439D01*
X887501Y-158189D01*
Y-159939D01*
X887938Y-161689D01*
X889030Y-163439D01*
X890340Y-164605D01*
X891868Y-164897D01*
X893396Y-164314D01*
X894925Y-162564D01*
G01X905656Y-164897D02*
Y-153231D01*
G01Y-155564D02*
X906748Y-154397D01*
X907840Y-153522D01*
X909368Y-153231D01*
X910459Y-153522D01*
X911770Y-154397D01*
G01X952413Y-192397D02*
X950666Y-192980D01*
X949356Y-194439D01*
X948483Y-196188D01*
X947828Y-198522D01*
X947610Y-201147D01*
X947828Y-203772D01*
X948483Y-206106D01*
X949356Y-207856D01*
X950666Y-209314D01*
X952413Y-209897D01*
X954159Y-209314D01*
X955470Y-207856D01*
X956343Y-206106D01*
X956998Y-203772D01*
X957216Y-201147D01*
X956998Y-198522D01*
X956343Y-196188D01*
X955470Y-194439D01*
X954159Y-192980D01*
X952413Y-192397D01*
G01X969913Y-209897D02*
X971441Y-209605D01*
X973188Y-208731D01*
X974280Y-207273D01*
X974716Y-205230D01*
X974280Y-203189D01*
X972970Y-201439D01*
X971005Y-200564D01*
X968821D01*
X967511Y-199980D01*
X966419Y-198522D01*
X965983Y-196481D01*
X966638Y-194439D01*
X968166Y-192980D01*
X969913Y-192397D01*
X971659Y-192980D01*
X973188Y-194439D01*
X973843Y-196481D01*
X973406Y-198522D01*
X972315Y-199980D01*
X971005Y-200564D01*
X968821D01*
X966856Y-201439D01*
X965546Y-203189D01*
X965110Y-205230D01*
X965546Y-207273D01*
X966638Y-208731D01*
X968385Y-209605D01*
X969913Y-209897D01*
G01X983483Y-210480D02*
X991343Y-192397D01*
G01X1004913D02*
X1003166Y-192980D01*
X1001856Y-194439D01*
X1000983Y-196188D01*
X1000328Y-198522D01*
X1000110Y-201147D01*
X1000328Y-203772D01*
X1000983Y-206106D01*
X1001856Y-207856D01*
X1003166Y-209314D01*
X1004913Y-209897D01*
X1006659Y-209314D01*
X1007970Y-207856D01*
X1008843Y-206106D01*
X1009498Y-203772D01*
X1009716Y-201147D01*
X1009498Y-198522D01*
X1008843Y-196188D01*
X1007970Y-194439D01*
X1006659Y-192980D01*
X1004913Y-192397D01*
G01X1022413Y-209897D02*
Y-192397D01*
X1019793Y-195897D01*
G01Y-209897D02*
X1025033D01*
G01X1035983Y-210480D02*
X1043843Y-192397D01*
G01X1053265Y-195314D02*
X1054575Y-193564D01*
X1056103Y-192689D01*
X1057850Y-192397D01*
X1060033Y-192980D01*
X1061561Y-194439D01*
X1061998Y-196188D01*
X1061780Y-197939D01*
X1060906Y-199397D01*
X1056540Y-202314D01*
X1054575Y-204355D01*
X1053265Y-207273D01*
X1052828Y-209897D01*
X1061998D01*
G01X1074913Y-192397D02*
X1073166Y-192980D01*
X1071856Y-194439D01*
X1070983Y-196188D01*
X1070328Y-198522D01*
X1070110Y-201147D01*
X1070328Y-203772D01*
X1070983Y-206106D01*
X1071856Y-207856D01*
X1073166Y-209314D01*
X1074913Y-209897D01*
X1076659Y-209314D01*
X1077970Y-207856D01*
X1078843Y-206106D01*
X1079498Y-203772D01*
X1079716Y-201147D01*
X1079498Y-198522D01*
X1078843Y-196188D01*
X1077970Y-194439D01*
X1076659Y-192980D01*
X1074913Y-192397D01*
G01X1092413Y-209897D02*
Y-192397D01*
X1089793Y-195897D01*
G01Y-209897D02*
X1095033D01*
G01X1112533D02*
Y-192397D01*
X1104454Y-204939D01*
X1115372D01*
G01X1000110Y-164897D02*
Y-147397D01*
X1004476D01*
X1006223Y-148272D01*
X1007533Y-149439D01*
X1008625Y-151188D01*
X1009498Y-153231D01*
X1009716Y-156147D01*
X1009498Y-159064D01*
X1008625Y-161106D01*
X1007533Y-162856D01*
X1006223Y-164022D01*
X1004476Y-164897D01*
X1000110D01*
G01X1026343D02*
Y-153231D01*
G01Y-155272D02*
X1025470Y-154106D01*
X1024159Y-153522D01*
X1022631Y-153231D01*
X1021103Y-153814D01*
X1019793Y-154980D01*
X1018919Y-156730D01*
X1018483Y-159064D01*
X1018919Y-161397D01*
X1019793Y-163147D01*
X1021103Y-164314D01*
X1022631Y-164897D01*
X1024159Y-164605D01*
X1025470Y-163731D01*
X1026343Y-162564D01*
G01X1039913Y-147397D02*
Y-164897D01*
G01X1036856Y-153231D02*
X1042970D01*
G01X1054138Y-157022D02*
X1061125D01*
X1060470Y-154980D01*
X1059378Y-153814D01*
X1057850Y-153231D01*
X1056321Y-153522D01*
X1055011Y-154397D01*
X1054138Y-156439D01*
X1053701Y-158189D01*
Y-159939D01*
X1054138Y-161689D01*
X1055230Y-163439D01*
X1056540Y-164605D01*
X1058068Y-164897D01*
X1059596Y-164314D01*
X1061125Y-162564D01*
G54D79*
X835075Y1734500D03*
G54D88*
X1005807Y1636102D03*
Y1631102D03*
Y1626102D03*
Y1621102D03*
Y1676102D03*
Y1671102D03*
Y1666102D03*
Y1661102D03*
Y1656102D03*
Y1651102D03*
Y1646102D03*
Y1641102D03*
G54D98*
G01X77166Y120511D02*
X79445D01*
X79458Y120498D01*
G02X81221Y119857I0J-2745D01*
G03X81615Y119694I394J394D01*
G01X95899D01*
G03X99099Y122894I0J3200D01*
G01Y126350D01*
G02X101299Y128550I2200J0D01*
G01X103499D01*
G03X104780Y129080I1J1811D01*
G01X105249Y129550D01*
G01X85630Y146141D02*
X90768D01*
G02X91094Y146006I0J-461D01*
G02X91229Y145680I-326J-326D01*
G01Y144678D01*
G03X91527Y144291I400J0D01*
G03X91629Y144278I101J387D01*
G01X98885D01*
G03X100749Y145050I0J2636D01*
G01X77166Y117362D02*
X79094D01*
X79107Y117349D01*
G03X80799Y118050I0J2393D01*
G02X81629Y118394I830J-830D01*
G01X95899D01*
G03X100399Y122894I0J4500D01*
G01Y126350D01*
G02X101299Y127250I900J0D01*
G01X103774D01*
G02X104243Y127056I0J-664D01*
G01X105249Y126050D01*
G01X77166Y129960D02*
X79445D01*
X79458Y129947D01*
G02X81221Y129306I0J-2745D01*
G03X81615Y129143I394J394D01*
G01X85499D01*
G03X86899Y130543I0J1400D01*
G01Y130567D01*
G01X77166Y126811D02*
X79094D01*
X79107Y126798D01*
G03X80799Y127499I0J2393D01*
G02X81629Y127843I830J-830D01*
G01X84499D01*
G02X86218Y127131I0J-2431D01*
G01X86599Y126750D01*
G01X85630Y141141D02*
X90800D01*
X90839Y141156D01*
G03X91017Y141260I-204J553D01*
G01X91096Y141328D01*
G03X91229Y141614I-241J286D01*
G01Y142578D01*
G02X91498Y142956I400J0D01*
G02X91629Y142978I131J-379D01*
G01X97302D01*
G02X100749Y141550I0J-4875D01*
G01X85630Y161141D02*
X90597D01*
G02X91044Y160956I0J-633D01*
G02X91229Y160509I-448J-447D01*
G01Y159678D01*
G03X91506Y159297I401J0D01*
G03X91510Y159295I179J353D01*
G03X91629Y159278I116J384D01*
G01X99500D01*
G03X104700Y164478I0J5200D01*
G01Y193719D01*
G03X104242Y194634I-1115J14D01*
G02X103785Y195549I658J900D01*
G01Y196674D01*
G02X104242Y197589I1115J15D01*
G03X104700Y198504I-657J901D01*
G01Y220544D01*
G03X104242Y221459I-1115J14D01*
G02X103785Y222374I658J900D01*
G01Y223499D01*
G02X104242Y224414I1115J15D01*
G03X104700Y225329I-657J901D01*
G01Y226454D01*
G03X104242Y227369I-1115J14D01*
G02X103785Y228284I658J900D01*
G01Y229409D01*
G02X104242Y230324I1115J15D01*
G03X104700Y231239I-657J901D01*
G01Y232364D01*
G03X104242Y233279I-1115J14D01*
G02X103785Y234194I658J900D01*
G01Y235319D01*
G02X104242Y236234I1115J15D01*
G03X104700Y237149I-657J901D01*
G01Y322542D01*
G03X104242Y323457I-1115J14D01*
G02X103785Y324372I658J900D01*
G01Y325497D01*
G02X104242Y326412I1115J15D01*
G03X104700Y327327I-657J901D01*
G01Y328452D01*
G03X104242Y329367I-1115J14D01*
G02X103785Y330282I658J900D01*
G01Y331407D01*
G02X104242Y332322I1115J15D01*
G03X104700Y333237I-657J901D01*
G01Y334362D01*
G03X104242Y335277I-1115J14D01*
G02X103785Y336192I658J900D01*
G01Y337317D01*
G02X104242Y338232I1115J15D01*
G03X104700Y339147I-657J901D01*
G01Y484518D01*
G02X108009Y492509I11300J1D01*
G01X114250Y498750D01*
G03X117000Y505389I-6639J6639D01*
G01Y600858D01*
G03X114071Y607929I-10000J0D01*
G01X100209Y621791D01*
G02X96900Y629782I7991J7990D01*
G01Y726158D01*
G02X99829Y733229I10000J0D01*
G01X120518Y753918D01*
G03X123700Y761600I-7682J7682D01*
G01Y993758D01*
G03X120771Y1000829I-10000J0D01*
G01X46176Y1075423D01*
G02X43247Y1082494I7071J7071D01*
G01Y1397050D01*
G03X42008Y1400041I-4230J0D01*
G01X37254Y1404794D01*
X37255Y1404795D01*
G02X35616Y1408750I3956J3956D01*
G01Y1414286D01*
G03X34819Y1416210I-2721J0D01*
G01X28903Y1422126D01*
G03X23100Y1424530I-5803J-5802D01*
G01X21356D01*
G03X20634Y1424231I0J-1021D01*
G02X18217Y1423230I-2417J2417D01*
G01X18211Y1423224D01*
X12569D01*
G01X85630Y156141D02*
X90396D01*
G03X90985Y156385I0J833D01*
G01X91095Y156495D01*
G03X91229Y156819I-325J324D01*
G01Y157578D01*
G02X91499Y157956I400J0D01*
G02X91508Y157959I131J-378D01*
G02X91629Y157978I122J-381D01*
G01X99500D01*
G03X106000Y164478I0J6500D01*
G01Y484518D01*
G02X108929Y491589I10000J0D01*
G01X115170Y497830D01*
G03X118300Y505388I-7559J7558D01*
G01Y600858D01*
G03X114991Y608849I-11300J1D01*
G01X101129Y622711D01*
G02X98200Y629782I7071J7071D01*
G01Y726158D01*
G02X100749Y732309I8699J-1D01*
G01X120569Y752130D01*
X120570D01*
X121438Y752998D01*
G03X125000Y761599I-8603J8601D01*
G01Y993758D01*
G03X121691Y1001749I-11300J1D01*
G01X47096Y1076343D01*
G02X44547Y1082494I6150J6152D01*
G01Y1397051D01*
G03X42928Y1400961I-5531J0D01*
G01X42679Y1401210D01*
X42678D01*
X38174Y1405714D01*
G02X36916Y1408751I3037J3037D01*
G01Y1414287D01*
G03X35739Y1417130I-4022J0D01*
G01X29823Y1423046D01*
G03X23102Y1425830I-6721J-6721D01*
G01X21443D01*
G02X20557Y1426197I0J1253D01*
G03X18215Y1427167I-2342J-2342D01*
G01X18209Y1427161D01*
X12569D01*
G01X26299Y383854D02*
X25203Y384949D01*
G03X24700Y385158I-504J-503D01*
G01X21381D01*
G03X21000Y385000I0J-539D01*
G03X20774Y384584I589J-589D01*
G01Y384563D01*
G02X20490Y384014I-673J0D01*
G02X20099Y383852I-391J391D01*
G01X12569D01*
G01X26299Y387629D02*
X25785Y387115D01*
G02X24751Y386527I-1586J1586D01*
G02X24512Y386479I-561J2172D01*
G02X24451Y386472I-286J2224D01*
G02X24199Y386458I-250J2229D01*
G01X22109D01*
G02X22102I-4J1782D01*
G02X22046Y386459I4J1782D01*
G02X21586Y386536I62J1781D01*
G02X21513Y386558I478J1717D01*
G02X21510Y386560I954J1434D01*
G02X21280Y386660I594J1681D01*
G02X20849Y386980I835J1575D01*
G03X18881Y387795I-1968J-1968D01*
G01X12575D01*
X12569Y387789D01*
G01X26492Y439350D02*
G03X24999Y440278I-1493J-737D01*
G01X22191D01*
G03X21397Y440221I-2J-5524D01*
G03X20452Y439579I0J-1017D01*
G02X19777Y439082I-750J312D01*
G02X19024Y438978I-755J2689D01*
G01X19018Y438972D01*
X12569D01*
G01X26599Y442749D02*
G02X24999Y441578I-1600J508D01*
G01X22271D01*
X22270Y441577D01*
G02X22223I-23J1985D01*
G02X21770Y441641I49J1985D01*
G02X21657Y441675I515J1917D01*
G02X21494Y441735I603J1891D01*
G02X21415Y441770I764J1832D01*
G02X20868Y442159I860J1789D01*
G03X19043Y442915I-1825J-1825D01*
G01X19037Y442909D01*
X12569D01*
G01X26299Y399601D02*
Y400009D01*
G03X25402Y400906I-897J0D01*
G01X22096D01*
G03X20842Y400386I1J-1774D01*
G01X20841D01*
G02X18958Y399606I-1883J1883D01*
G01X12575D01*
X12569Y399600D01*
G01X26299Y403376D02*
G02X25709Y402333I-1217J0D01*
G02X25402Y402206I-307J307D01*
G01X21839D01*
G02X20451Y402781I0J1963D01*
G03X18611Y403543I-1840J-1840D01*
G01X18605Y403537D01*
X12569D01*
G01X26899Y454850D02*
G03X25723Y456026I-1176J0D01*
G01X21620D01*
G03X20493Y455559I0J-1594D01*
G02X18482Y454726I-2011J2011D01*
G01X18476Y454720D01*
X12569D01*
G01X26799Y458497D02*
X26073Y457771D01*
G02X24999Y457326I-1074J1074D01*
G01X21664D01*
G02X20476Y457818I0J1680D01*
G03X18436Y458663I-2040J-2040D01*
G01X18430Y458657D01*
X12569D01*
G01X64403Y471046D02*
G03X62645Y471774I-1758J-1758D01*
G01X22133D01*
G03X21172Y471376I0J-1359D01*
G01X20872Y471076D01*
G02X19419Y470474I-1453J1453D01*
G01X19413Y470468D01*
X12569D01*
G01X64397Y474446D02*
G02X61085Y473074I-3312J3312D01*
G01X22715D01*
G02X20965Y473799I0J2475D01*
G03X19488Y474411I-1477J-1477D01*
G01X19482Y474405D01*
X12569D01*
G01X26524Y426720D02*
G02X24854Y425050I-1670J0D01*
G01X22000D01*
G02X21118Y425350I-1J1444D01*
G02X20883Y425917I567J567D01*
G01Y425955D01*
G03X20583Y426417I-1235J-474D01*
G01X20500Y426500D01*
G03X18904Y427161I-1596J-1596D01*
G01X12569D01*
G01X26399Y423322D02*
G03X25366Y423750I-1033J-1033D01*
G01X22294D01*
G03X22173Y423742I0J-922D01*
G03X21914Y423668I121J-914D01*
G03X21642Y423480I380J-840D01*
G02X21036Y423229I-606J606D01*
G01X12575D01*
X12569Y423223D01*
G01X36499Y517775D02*
G03X34499Y519018I-2000J-988D01*
G01X22087D01*
G03X21913Y519005I6J-1256D01*
G03X21199Y518650I173J-1244D01*
G02X20931Y518410I-2297J2295D01*
G02X19260Y517718I-1671J1671D01*
G01X19254Y517712D01*
X12569D01*
G01X36499Y521550D02*
G02X34499Y520318I-2000J1007D01*
G01X28336D01*
G02X27421Y520776I-14J1115D01*
G03X26506Y521233I-900J-658D01*
G01X25381D01*
G03X24466Y520776I-15J-1115D01*
G02X23551Y520318I-901J657D01*
G01X22142D01*
G02X21099Y520750I0J1475D01*
G03X18914Y521655I-2185J-2185D01*
G01X18908Y521649D01*
X12569D01*
G01X26399Y501966D02*
G03X25095Y503270I-1304J0D01*
G01X21553D01*
G03X21320Y503250I0J-1369D01*
G03X20585Y502869I233J-1349D01*
G02X18415Y501970I-2170J2170D01*
G01X18409Y501964D01*
X12569D01*
G01X26399Y505741D02*
G02X25228Y504570I-1171J0D01*
G01X21706D01*
G02X21072Y504687I-1J1769D01*
G02X20455Y505088I635J1651D01*
G03X18478Y505907I-1977J-1977D01*
G01X18472Y505901D01*
X12569D01*
G01X64600Y486300D02*
G03X63358Y487542I-1242J0D01*
G01X21940D01*
G03X20711Y487033I0J-1738D01*
G02X18753Y486222I-1958J1958D01*
G01X18747Y486216D01*
X12569D01*
G01X64700Y489700D02*
G02X62629Y488842I-2071J2071D01*
G01X22141D01*
G02X20980Y489323I0J1642D01*
G03X18962Y490159I-2018J-2018D01*
G01X18956Y490153D01*
X12569D01*
G01X77166Y526023D02*
X80166D01*
X80179Y526010D01*
G02X81702Y525554I1J-2769D01*
G03X82194Y525350I492J492D01*
G01X99655D01*
G03X101195Y525988I0J2178D01*
G01X85630Y551653D02*
X90406D01*
G02X90988Y551412I0J-823D01*
G01X91098Y551302D01*
G02X91229Y550986I-316J-316D01*
G01Y550190D01*
G03X91497Y549812I401J0D01*
G03X91629Y549790I131J378D01*
G01X98277D01*
G02X98668Y549774I3J-4721D01*
G03X99952Y550245I134J1621D01*
G01X100695Y550988D01*
G01X77166Y522874D02*
X80905D01*
X80918Y522861D01*
G03X82099Y523350I0J1670D01*
G02X83475Y524029I1690J-1690D01*
G02X83789Y524050I316J-2369D01*
G01X97424D01*
G02X101195Y522488I0J-5333D01*
G01X60003Y534150D02*
G03X58516Y534766I-1487J-1487D01*
G01X23469D01*
G03X21499Y533950I0J-2786D01*
G02X20331Y533466I-1168J1168D01*
G01X12575D01*
X12569Y533460D01*
G01X77166Y535472D02*
X80360D01*
X80373Y535459D01*
G02X81677Y534919I0J-1844D01*
G03X82809Y534450I1132J1132D01*
G01X84111D01*
G03X84986Y534812I1J1237D01*
G01X86199Y536025D01*
G01X59999Y537550D02*
Y536771D01*
G02X59102Y536016I-766J0D01*
G01Y536015D01*
G03X58517Y536066I-587J-3352D01*
G01X53570D01*
G02X52655Y536524I-14J1115D01*
G03X51740Y536981I-900J-658D01*
G01X50615D01*
G03X49700Y536524I-15J-1115D01*
G02X48785Y536066I-901J657D01*
G01X47660D01*
G02X46745Y536524I-14J1115D01*
G03X45830Y536981I-900J-658D01*
G01X44705D01*
G03X43790Y536524I-15J-1115D01*
G02X42875Y536066I-901J657D01*
G01X41750D01*
G02X40835Y536524I-14J1115D01*
G03X39920Y536981I-900J-658D01*
G01X38795D01*
G03X37880Y536524I-15J-1115D01*
G02X36965Y536066I-901J657D01*
G01X35840D01*
G02X34925Y536524I-14J1115D01*
G03X34010Y536981I-900J-658D01*
G01X32885D01*
G03X31970Y536524I-15J-1115D01*
G02X31055Y536066I-901J657D01*
G01X22369D01*
G02X21485Y536432I0J1250D01*
G03X19141Y537403I-2344J-2344D01*
G01X19135Y537397D01*
X12569D01*
G01X77166Y532323D02*
X80662D01*
X80675Y532310D01*
G03X81708Y532738I0J1461D01*
G02X82703Y533150I995J-995D01*
G01X84026D01*
G02X86199Y532250I0J-3073D01*
G01X85630Y561653D02*
X90587D01*
G03X91041Y561841I0J642D01*
G03X91229Y562295I-454J454D01*
G01Y563090D01*
G02X91497Y563467I399J0D01*
G02X91500Y563468I128J-379D01*
G02X91629Y563490I131J-378D01*
G01X96523D01*
G03X98599Y564350I0J2936D01*
G03X100799Y569661I-5311J5311D01*
G01Y602061D01*
G03X98270Y608170I-8640J1D01*
G01X93130Y613310D01*
G02X90200Y620382I7070J7072D01*
G01Y731258D01*
G02X92749Y737409I8699J-1D01*
G01X114191Y758851D01*
G03X117500Y766842I-7991J7990D01*
G01Y990357D01*
G03X114191Y998348I-11300J1D01*
G01X80896Y1031643D01*
X47602Y1064938D01*
X40894Y1071646D01*
G02X36999Y1081049I9402J9403D01*
G01Y1394318D01*
G03X36100Y1396488I-3069J0D01*
G01X27985Y1404603D01*
G02X27799Y1405051I448J448D01*
G01Y1405887D01*
G03X26712Y1408515I-3715J2D01*
G03X25428Y1409335I-2501J-2501D01*
G03X24216Y1409550I-1212J-3306D01*
G01X23311D01*
G02X22683Y1409810I0J888D01*
G03X22108Y1410048I-575J-575D01*
G01X21751D01*
G02X21426Y1410077I-2J1811D01*
G02X21205Y1410131I319J1784D01*
G02X20470Y1410578I547J1727D01*
G01X20455Y1410594D01*
G03X18463Y1411419I-1992J-1992D01*
G01X18457Y1411413D01*
X12569D01*
G01X85630Y546653D02*
X90695D01*
G03X90971Y546763I0J401D01*
G01X91097Y546882D01*
G03X91229Y547168I-244J286D01*
G01Y548090D01*
G02X91498Y548468I400J0D01*
G02X91629Y548490I131J-379D01*
G01X98276D01*
G02X100695Y547488I0J-3421D01*
G01X27499Y620203D02*
G03X24657Y621380I-2842J-2842D01*
G01X21481D01*
G03X20486Y620968I0J-1407D01*
G02X18342Y620080I-2144J2144D01*
G01X18336Y620074D01*
X12569D01*
G01X27499Y623857D02*
X27143Y623501D01*
G02X25161Y622680I-1983J1983D01*
G01X21519D01*
G02X20471Y623114I0J1482D01*
G03X18291Y624017I-2180J-2180D01*
G01X18285Y624011D01*
X12569D01*
G01X80499Y664550D02*
G03X79752Y663237I2014J-2015D01*
G03X79680Y662237I2761J-701D01*
G01X79816Y660947D01*
G03X79932Y660393I2782J293D01*
G03X79977Y660268I2653J884D01*
G01Y660267D01*
G03X80619Y659270I2619J981D01*
G01X82691Y657198D01*
G02X86000Y649207I-7991J-7990D01*
G01Y585232D01*
G02X82691Y577241I-11300J-1D01*
G01X77649Y572199D01*
G02X72819Y570199I-4830J4832D01*
G01X21621D01*
G03X20877Y569891I0J-1052D01*
G02X18482Y568899I-2395J2395D01*
G01X18476Y568893D01*
X12569D01*
G01X26568Y635950D02*
X26304Y636214D01*
G03X24100Y637127I-2204J-2204D01*
G01X21512D01*
G03X20445Y636685I0J-1509D01*
G02X18376Y635828I-2069J2069D01*
G01X18370Y635822D01*
X12569D01*
G01X26568Y639604D02*
X26304Y639340D01*
G02X24100Y638427I-2204J2204D01*
G01X21540D01*
G02X20446Y638880I0J1547D01*
G03X18309Y639765I-2137J-2137D01*
G01X18303Y639759D01*
X12569D01*
G01X85630Y566653D02*
X90748D01*
G02X91088Y566512I0J-480D01*
G02X91229Y566172I-339J-340D01*
G01Y565190D01*
G03X91497Y564812I401J0D01*
G03X91571Y564794I131J378D01*
G03X91629Y564790I56J396D01*
G01X96522D01*
G03X97679Y565270I0J1635D01*
G03X99499Y569662I-4390J4392D01*
G01Y602061D01*
G03X97350Y607250I-7339J0D01*
G01X95200Y609400D01*
X91829Y612770D01*
G02X88900Y619842I7071J7071D01*
G01Y660583D01*
G03X88442Y661498I-1115J14D01*
G02X87985Y662413I658J900D01*
G01Y663538D01*
G02X88442Y664453I1115J15D01*
G03X88900Y665368I-657J901D01*
G01Y666493D01*
G03X88442Y667408I-1115J14D01*
G02X87985Y668323I658J900D01*
G01Y669448D01*
G02X88442Y670363I1115J15D01*
G03X88900Y671278I-657J901D01*
G01Y672403D01*
G03X88442Y673318I-1115J14D01*
G02X87985Y674233I658J900D01*
G01Y675358D01*
G02X88442Y676273I1115J15D01*
G03X88900Y677188I-657J901D01*
G01Y694802D01*
G03X88442Y695717I-1115J14D01*
G02X87985Y696632I658J900D01*
G01Y697757D01*
G02X88442Y698672I1115J15D01*
G03X88900Y699587I-657J901D01*
G01Y700712D01*
G03X88442Y701627I-1115J14D01*
G02X87985Y702542I658J900D01*
G01Y703667D01*
G02X88442Y704582I1115J15D01*
G03X88900Y705497I-657J901D01*
G01Y706622D01*
G03X88442Y707537I-1115J14D01*
G02X87985Y708452I658J900D01*
G01Y709577D01*
G02X88442Y710492I1115J15D01*
G03X88900Y711407I-657J901D01*
G01Y719230D01*
G03X88442Y720145I-1115J14D01*
G02X87985Y721060I658J900D01*
G01Y722185D01*
G02X88442Y723100I1115J15D01*
G03X88900Y724015I-657J901D01*
G01Y731258D01*
G02X91829Y738329I10000J0D01*
G01X113271Y759771D01*
G03X116200Y766842I-7071J7071D01*
G01Y990357D01*
G03X113271Y997428I-10000J0D01*
G01X46682Y1064018D01*
X39974Y1070726D01*
G02X35699Y1081050I10323J10321D01*
G01Y1394317D01*
G03X35180Y1395568I-1769J-1D01*
G01X34804Y1395944D01*
Y1395945D01*
X27555Y1403193D01*
X27066Y1403683D01*
G02X26499Y1405050I1367J1368D01*
G01Y1405888D01*
G03X25792Y1407595I-2414J0D01*
G03X24980Y1408113I-1581J-1582D01*
G03X24211Y1408250I-771J-2099D01*
G01X22841D01*
G02X22257Y1408492I0J826D01*
G03X21635Y1408750I-623J-622D01*
G03X21149Y1408548I1J-688D01*
G01X20500Y1407900D01*
X20329Y1407729D01*
G02X19730Y1407481I-599J599D01*
G01X12575D01*
X12569Y1407475D01*
G01X32451Y1411468D02*
G03X31499Y1409170I2298J-2298D01*
G01Y1407698D01*
G03X32118Y1406204I2113J0D01*
G01X39411Y1398911D01*
G02X40847Y1395016I-3507J-3505D01*
G01Y1080595D01*
G03X43396Y1074444I8699J1D01*
G01X117891Y999949D01*
G02X121200Y991958I-7991J-7990D01*
G01Y765501D01*
G02X117426Y756386I-12889J-2D01*
G01X95920Y734880D01*
G03X94000Y730245I4635J-4635D01*
G01Y626642D01*
G03X96549Y620491I8699J1D01*
G01X100698Y616342D01*
X111160Y605881D01*
G02X113800Y599509I-6370J-6372D01*
G01Y552206D01*
G02X112920Y550080I-3008J0D01*
G02X109587Y548700I-3333J3335D01*
G01X107121D01*
G03X107105Y548699I250J-4130D01*
G03X104195Y547488I15J-4138D01*
G01Y550988D02*
X104806Y550377D01*
G03X105716Y550000I910J910D01*
G01X109586D01*
G03X112000Y551000I0J3414D01*
G03X112500Y552207I-1207J1207D01*
G01Y558343D01*
G03X112042Y559258I-1115J14D01*
G02X111585Y560173I658J900D01*
G01Y561298D01*
G02X112042Y562213I1115J15D01*
G03X112500Y563128I-657J901D01*
G01Y564253D01*
G03X112042Y565168I-1115J14D01*
G02X111585Y566083I658J900D01*
G01Y567208D01*
G02X112042Y568123I1115J15D01*
G03X112500Y569038I-657J901D01*
G01Y570163D01*
G03X112042Y571078I-1115J14D01*
G02X111585Y571993I658J900D01*
G01Y573118D01*
G02X112042Y574033I1115J15D01*
G03X112500Y574948I-657J901D01*
G01Y576073D01*
G03X112042Y576988I-1115J14D01*
G02X111585Y577903I658J900D01*
G01Y579028D01*
G02X112042Y579943I1115J15D01*
G03X112500Y580858I-657J901D01*
G01Y587689D01*
G03X112042Y588604I-1115J14D01*
G02X111585Y589519I658J900D01*
G01Y590644D01*
G02X112042Y591559I1115J15D01*
G03X112500Y592474I-657J901D01*
G01Y593599D01*
G03X112042Y594514I-1115J14D01*
G02X111585Y595429I658J900D01*
G01Y596554D01*
G02X112042Y597469I1115J15D01*
G03X112500Y598384I-657J901D01*
G01Y599509D01*
G03X110240Y604961I-7709J-1D01*
G01X99778Y615422D01*
X95629Y619571D01*
G02X92700Y626642I7071J7071D01*
G01Y730246D01*
G02X95000Y735800I7856J0D01*
G01X116506Y757306D01*
G03X119900Y765500I-8194J8194D01*
G01Y991958D01*
G03X116971Y999029I-10000J0D01*
G01X42476Y1073524D01*
G02X39547Y1080595I7071J7071D01*
G01Y1395071D01*
G03X38491Y1397991I-3642J334D01*
G01X31198Y1405284D01*
G02X30199Y1407697I2415J2413D01*
G01Y1409050D01*
G03X29280Y1411269I-3138J0D01*
G01X28999Y1411550D01*
G01X76999Y664550D02*
G02X78188Y662674I-3600J-3596D01*
G02X78469Y661402I-4787J-1725D01*
G03X78687Y660019I4504J1D01*
G01X78694Y659996D01*
G03X78759Y659810I3899J1258D01*
G03X79699Y658350I3837J1438D01*
G01X81771Y656278D01*
G02X84700Y649207I-7071J-7071D01*
G01Y585232D01*
G02X81771Y578161I-10000J0D01*
G01X76729Y573119D01*
G02X72818Y571499I-3911J3911D01*
G01X21703D01*
G02X20527Y571986I0J1663D01*
G03X18475Y572836I-2052J-2052D01*
G01X18469Y572830D01*
X12569D01*
G01X26737Y651957D02*
G03X24518Y652876I-2219J-2219D01*
G01X21515D01*
G03X20441Y652431I0J-1519D01*
G02X18377Y651576I-2064J2064D01*
G01X18371Y651570D01*
X12569D01*
G01X26999Y656550D02*
Y655757D01*
G02X26499Y654550I-1707J0D01*
G02X25596Y654176I-903J903D01*
G01X21520D01*
G02X20470Y654611I0J1485D01*
G03X18292Y655513I-2178J-2178D01*
G01X18286Y655507D01*
X12569D01*
G01X27687Y667447D02*
X27579Y667556D01*
G03X24999Y668624I-2579J-2580D01*
G01X21813D01*
G03X21028Y668484I1J-2278D01*
G01X21024Y668483D01*
G03X20196Y667954I789J-2148D01*
G02X18675Y667324I-1521J1521D01*
G01X18669Y667318D01*
X12569D01*
G01X27687Y671101D02*
X27579Y670992D01*
G02X24999Y669924I-2579J2580D01*
G01X22087D01*
G02X20725Y670488I0J1926D01*
G01X20271Y670941D01*
G03X19500Y671261I-772J-771D01*
G01X19494Y671255D01*
X12569D01*
G01X50410Y695801D02*
G03X47998Y696800I-2412J-2412D01*
G01X40989D01*
G03X37319Y695280I0J-5190D01*
G01X28569Y686530D01*
G02X23642Y684489I-4927J4927D01*
G01X21519D01*
G03X21134Y684427I3J-1243D01*
G03X20640Y684125I383J-1182D01*
G01X20073Y683558D01*
G02X18900Y683072I-1173J1173D01*
G01X18894Y683066D01*
X12569D01*
G01X50300Y699200D02*
X50260Y699161D01*
G02X47700Y698100I-2561J2560D01*
G01X40990D01*
G03X36400Y696199I-1J-6490D01*
G01X36399D01*
X27649Y687449D01*
X27650D01*
G02X23641Y685789I-4008J4008D01*
G01X21591D01*
G02X20943Y686058I1J917D01*
G01X20600Y686400D01*
X20268Y686733D01*
G03X19600Y687009I-667J-668D01*
G01X19594Y687003D01*
X12569D01*
G01X77166Y931535D02*
X80655D01*
G02X82038Y930962I0J-1956D01*
G03X83421Y930389I1383J1383D01*
G01X95622D01*
G03X96950Y930939I0J1878D01*
G02X98278Y931489I1328J-1328D01*
G01X99795D01*
G01X85630Y957165D02*
X90498D01*
G02X91229Y956434I0J-731D01*
G01Y955702D01*
G03X91506Y955320I401J-1D01*
G01X91507D01*
G03X91629Y955302I119J382D01*
G01X99929D01*
G03X102795Y956489I0J4053D01*
G01X85630Y972165D02*
X90498D01*
G02X91229Y971434I0J-731D01*
G01Y970702D01*
G03X91507Y970320I401J0D01*
G03X91536Y970312I121J383D01*
G03X91629Y970302I89J390D01*
G01X94834D01*
G03X95479Y970570I-1J911D01*
G03X96499Y973029I-2459J2461D01*
G01Y999259D01*
G03X93570Y1006330I-10000J0D01*
G01X31203Y1068697D01*
G02X28274Y1075768I7071J7071D01*
G01Y1219384D01*
G03X27817Y1220299I-1115J15D01*
G02X27359Y1221214I657J901D01*
G01Y1222339D01*
G02X27817Y1223254I1115J14D01*
G03X28274Y1224169I-658J900D01*
G01Y1225294D01*
G03X27817Y1226209I-1115J15D01*
G02X27359Y1227124I657J901D01*
G01Y1228249D01*
G02X27817Y1229164I1115J14D01*
G03X28274Y1230079I-658J900D01*
G01Y1292873D01*
G03X27817Y1293788I-1115J15D01*
G02X27359Y1294703I657J901D01*
G01Y1295828D01*
G02X27817Y1296743I1115J14D01*
G03X28274Y1297658I-658J900D01*
G01Y1298783D01*
G03X27817Y1299698I-1115J15D01*
G02X27359Y1300613I657J901D01*
G01Y1301738D01*
G02X27817Y1302653I1115J14D01*
G03X28274Y1303568I-658J900D01*
G01Y1323568D01*
G03X27817Y1324483I-1115J15D01*
G02X27359Y1325398I657J901D01*
G01Y1326523D01*
G02X27817Y1327438I1115J14D01*
G03X28274Y1328353I-658J900D01*
G01Y1329478D01*
G03X27817Y1330393I-1115J15D01*
G02X27359Y1331308I657J901D01*
G01Y1332433D01*
G02X27817Y1333348I1115J14D01*
G03X28274Y1334263I-658J900D01*
G01Y1335388D01*
G03X27817Y1336303I-1115J15D01*
G02X27359Y1337218I657J901D01*
G01Y1338343D01*
G02X27817Y1339258I1115J14D01*
G03X28274Y1340173I-658J900D01*
G01Y1380051D01*
X28273Y1380050D01*
G03X27389Y1382185I-3020J0D01*
G01X25512Y1384062D01*
X25510Y1384065D01*
G03X22872Y1385157I-2637J-2638D01*
G01X21699D01*
G03X21052Y1384889I0J-915D01*
G01X20719Y1384556D01*
G02X19034Y1383858I-1685J1685D01*
G01X19028Y1383852D01*
X12569D01*
G01X85630Y967165D02*
X90605D01*
G03X91041Y967342I1J624D01*
G01X91116Y967416D01*
G03X91229Y967684I-261J268D01*
G01Y968602D01*
G02X91540Y968991I399J0D01*
G02X91629Y969002I93J-388D01*
G01X94835D01*
G03X96399Y969651I-1J2212D01*
G03X97799Y973028I-3380J3380D01*
G01Y999259D01*
G03X94490Y1007250I-11300J1D01*
G01X32123Y1069617D01*
G02X29574Y1075768I6150J6152D01*
G01Y1380050D01*
G03X28309Y1383105I-4321J0D01*
G01X26681Y1384733D01*
X26489Y1384924D01*
G03X22872Y1386457I-3616J-3497D01*
G01X21476D01*
G02X20522Y1386852I0J1349D01*
G03X18245Y1387795I-2277J-2277D01*
G01X18239Y1387789D01*
X12569D01*
G01X77166Y940984D02*
X80828D01*
X80841Y940971D01*
G02X82099Y940450I0J-1779D01*
G01X82146Y940404D01*
G03X82839Y940117I693J693D01*
G01X85246D01*
G03X85999Y940429I0J1065D01*
G01X77166Y928386D02*
X81048D01*
G03X82328Y928765I0J2351D01*
G02X83422Y929089I1095J-1687D01*
G01X96133D01*
G02X97461Y928539I0J-1878D01*
G03X98789Y927989I1328J1328D01*
G01X99795D01*
G01X77166Y937835D02*
X80741D01*
X80754Y937822D01*
G03X82149Y938400I0J1973D01*
G02X82994Y938750I845J-845D01*
G01X84592D01*
G02X85799Y938250I0J-1707D01*
G01X85975Y938074D01*
G02X86399Y937050I-1025J-1024D01*
G01X102795Y952989D02*
G03X100349Y954002I-2446J-2446D01*
G01X91629D01*
G03X91229Y953602I0J-400D01*
G01Y952849D01*
G02X90940Y952369I-543J0D01*
G01X90893Y952344D01*
G02X90500Y952201I-709J1337D01*
G01X90197Y952169D01*
G02X90156Y952167I-40J390D01*
G01X89366D01*
X89364Y952165D01*
X85630D01*
G01X150591Y213937D02*
X145582D01*
G03X145164Y213764I0J-591D01*
G03X144990Y213344I420J-420D01*
G01Y212474D01*
G02X144718Y212095I-400J0D01*
G02X144590Y212074I-128J380D01*
G01X136668D01*
G02X129597Y215003I0J10000D01*
G01X117729Y226871D01*
G02X114800Y233942I7071J7071D01*
G01Y481858D01*
G02X117349Y488009I8699J-1D01*
G01X123491Y494151D01*
G03X126800Y502142I-7991J7990D01*
G01Y604956D01*
G03X123872Y612027I-10000J1D01*
G01X116650Y619249D01*
X109429Y626472D01*
G02X106501Y633543I7072J7070D01*
G01X106500Y633542D01*
Y721258D01*
G02X109049Y727409I8699J-1D01*
G01X130091Y748451D01*
G03X133400Y756442I-7991J7990D01*
G01Y997758D01*
G03X130091Y1005749I-11300J1D01*
G01X95610Y1040230D01*
X61129Y1074710D01*
X54591Y1081248D01*
G02X52767Y1083875I6376J6374D01*
G01X52765Y1083878D01*
G02X51948Y1087629I8207J3752D01*
G01X51947Y1087628D01*
Y1401364D01*
G03X51946Y1401418I-1458J0D01*
G03X50412Y1404912I-5251J-222D01*
G01X45638Y1409686D01*
G02X44316Y1412873I3182J3188D01*
G01Y1427049D01*
G03X42181Y1432207I-7292J2D01*
G01X33909Y1440480D01*
G03X31256Y1441578I-2653J-2656D01*
G01X21521D01*
G02X20471Y1442013I0J1485D01*
G03X18293Y1442915I-2178J-2178D01*
G01X18287Y1442909D01*
X12569D01*
G01X150591Y619449D02*
X150571Y619429D01*
X146025D01*
G03X145469Y619269I0J-1046D01*
G01X145369Y619206D01*
G03X144990Y618520I431J-686D01*
G01Y617986D01*
G02X144720Y617607I-401J0D01*
G02X144590Y617586I-128J379D01*
G01X140500D01*
G02X125650Y623737I0J21001D01*
G01X122544Y626843D01*
Y626844D01*
X116168Y633220D01*
G02X114999Y636042I2822J2822D01*
G01Y718552D01*
G02X116767Y722818I6036J-2D01*
G01X139603Y745654D01*
G03X141199Y749507I-3853J3853D01*
G01Y1002551D01*
G03X138274Y1009614I-9990J0D01*
G01X66918Y1080970D01*
X61122Y1086768D01*
G02X59347Y1091050I4280J4283D01*
G01Y1403437D01*
G03X57220Y1408570I-7261J-2D01*
G01X57221Y1408571D01*
X54289Y1411502D01*
X54290Y1411503D01*
X53371Y1412423D01*
X53370Y1412422D01*
G02X51716Y1416415I3993J3993D01*
G01Y1435249D01*
G03X50003Y1439385I-5849J0D01*
G01X49668Y1439719D01*
X33918Y1455469D01*
X33919Y1455470D01*
X33835Y1455554D01*
G03X29500Y1457349I-4335J-4337D01*
G01X22691D01*
G02X22504Y1457356I-4J2393D01*
G02X21217Y1457857I188J2386D01*
G03X19271Y1458663I-1946J-1946D01*
G01X19265Y1458657D01*
X12569D01*
G01X30378Y1462518D02*
X30425D01*
X53382Y1439561D01*
G02X54116Y1437789I-1772J-1772D01*
G01Y1417839D01*
G03X55383Y1414356I5415J-2D01*
G03X55712Y1413997I4276J3588D01*
G01X60579Y1409130D01*
G02X61747Y1406310I-2820J-2820D01*
G01Y1092549D01*
G03X63689Y1087859I6632J-1D01*
G01X66999Y1084550D01*
X141249Y1010300D01*
G02X143599Y1004627I-5673J-5673D01*
G01Y750502D01*
X143600Y750501D01*
Y747974D01*
G02X142196Y744587I-4791J1D01*
G01X125579Y727970D01*
X119334Y721726D01*
G03X117399Y717049I4677J-4674D01*
G01Y637441D01*
G03X118715Y634266I4492J2D01*
G01Y634265D01*
X118714Y634264D01*
X120464Y632514D01*
X120465Y632515D01*
Y632516D01*
G03X123785Y631140I3322J3321D01*
G01X129093D01*
G02X131688Y630065I0J-3670D01*
G01Y633565D02*
X131669Y633546D01*
G02X128999Y632440I-2670J2670D01*
G01X123786D01*
G02X121384Y633435I0J3397D01*
G01X119634Y635185D01*
G02X118699Y637442I2257J2257D01*
G01Y717050D01*
G02X120254Y720806I5311J1D01*
G01X126499Y727050D01*
X143116Y743667D01*
G03X144900Y747974I-4307J4307D01*
G01Y751040D01*
X144899Y751041D01*
Y1004628D01*
G03X142168Y1011219I-9323J-2D01*
G01X142169Y1011220D01*
X67919Y1085470D01*
X64609Y1088779D01*
G02X63048Y1092549I3771J3769D01*
G01X63047Y1092548D01*
Y1406309D01*
G03X61498Y1410049I-5288J1D01*
G01X61499Y1410050D01*
X61498Y1410051D01*
X56621Y1414930D01*
G02X55416Y1417839I2909J2909D01*
G01Y1433589D01*
X55421Y1433594D01*
Y1434670D01*
X55416Y1434675D01*
Y1437790D01*
G03X54301Y1440480I-3806J-1D01*
G01X54302Y1440481D01*
X34867Y1459915D01*
X34391Y1460392D01*
G02X33915Y1461541I1149J1149D01*
G01Y1462681D01*
G01X150591Y614449D02*
X150571Y614429D01*
X145536D01*
X145390Y614436D01*
G02X144990Y614836I0J400D01*
G01Y615886D01*
G03X144701Y616270I-400J0D01*
G03X144590Y616286I-112J-384D01*
G01X140501D01*
G02X124730Y622817I-2J22302D01*
G01X122273Y625274D01*
X115248Y632300D01*
X115249Y632301D01*
G02X113699Y636041I3741J3742D01*
G01Y718551D01*
G02X115847Y723738I7337J0D01*
G01X138683Y746574D01*
G03X139899Y749507I-2932J2934D01*
G01Y1002550D01*
G03X137354Y1008694I-8689J0D01*
G01X65998Y1080050D01*
X60202Y1085848D01*
G02X58047Y1091049I5201J5202D01*
G01Y1403436D01*
G03X56301Y1407650I-5961J-1D01*
G01Y1407651D01*
X52450Y1411502D01*
X52451Y1411503D01*
G02X50416Y1416414I4912J4912D01*
G01Y1435250D01*
X50415Y1435249D01*
G03X49084Y1438466I-4549J2D01*
G01Y1438465D01*
X48749Y1438799D01*
X32998Y1454550D01*
G03X32916Y1454635I-3518J-3312D01*
G01X32915Y1454634D01*
G03X29499Y1456049I-3416J-3416D01*
G01X22402D01*
G03X21602Y1455904I2J-2291D01*
G01X21597Y1455902D01*
G03X20782Y1455378I799J-2139D01*
G02X19208Y1454726I-1574J1574D01*
G01X19202Y1454720D01*
X12569D01*
G01X128249Y228050D02*
X127735Y227536D01*
G02X126200Y226900I-1536J1536D01*
G01X124694D01*
G02X123850Y227251I2J1195D01*
G01X121401Y229700D01*
G02X119000Y235497I5796J5797D01*
G01X118999Y235496D01*
Y480057D01*
G02X121548Y486208I8699J-1D01*
G01X128620Y493280D01*
G03X131000Y499027I-5749J5747D01*
G01Y606358D01*
G03X127691Y614349I-11300J1D01*
G01X113828Y628212D01*
G02X110899Y635283I7071J7071D01*
G01Y719557D01*
G02X113448Y725708I8699J-1D01*
G01X134190Y746450D01*
G03X137499Y754441I-7991J7990D01*
G01Y1001049D01*
G03X134787Y1007601I-9265J3D01*
G01X63418Y1078970D01*
X57632Y1084758D01*
G02X55647Y1089547I4787J4790D01*
G01Y1401550D01*
G03X53273Y1407285I-8111J2D01*
G01X52880Y1407680D01*
X51757Y1408801D01*
X51738D01*
X48919Y1411620D01*
G02X48016Y1413800I2180J2180D01*
G01Y1429210D01*
G03X46317Y1433311I-5800J0D01*
G01X34554Y1445074D01*
G03X31471Y1446351I-3083J-3083D01*
G01X31472Y1446350D01*
G02X30882Y1447121I-1J611D01*
G02X31040Y1447393I589J-160D01*
G01X32094Y1448448D01*
G01X128249Y224550D02*
G03X125714Y225600I-2535J-2535D01*
G01X124695D01*
G02X122930Y226331I0J2496D01*
G01X120481Y228780D01*
G02X117699Y235497I6716J6716D01*
G01Y480057D01*
G02X120628Y487128I10000J0D01*
G01X127700Y494200D01*
G03X129700Y499028I-4828J4828D01*
G01Y606358D01*
G03X126771Y613429I-10000J0D01*
G01X112528Y627672D01*
G02X109599Y634743I7071J7071D01*
G01Y719557D01*
G02X112528Y726628I10000J0D01*
G01X133270Y747370D01*
G03X136199Y754441I-7071J7071D01*
G01Y1001050D01*
G03X133867Y1006681I-7964J0D01*
G01X62498Y1078050D01*
X56712Y1083838D01*
G02X54347Y1089546I5708J5709D01*
G01Y1401550D01*
G03X52353Y1406365I-6810J0D01*
G01X52211Y1406507D01*
Y1406509D01*
X52205Y1406515D01*
X51218Y1407501D01*
X51199D01*
X47999Y1410700D01*
G02X46716Y1413799I3101J3099D01*
G01Y1429208D01*
G03X45398Y1432390I-4500J0D01*
G01X33634Y1444154D01*
G03X31471Y1445050I-2163J-2163D01*
G01Y1445049D01*
G02X29627Y1447462I1J1912D01*
G03X28989Y1448296I-638J173D01*
G01X28697D01*
G01X150591Y208937D02*
X145627D01*
G02X145176Y209124I0J637D01*
G02X144990Y209573I449J449D01*
G01Y210374D01*
G03X144590Y210774I-400J0D01*
G01X136668D01*
G02X128677Y214083I-1J11300D01*
G01X116809Y225951D01*
G02X113500Y233942I7991J7990D01*
G01Y481859D01*
G02X116429Y488929I10000J-1D01*
G01X122571Y495071D01*
G03X125499Y502142I-7072J7070D01*
G01X125500Y502141D01*
Y604957D01*
X125499Y604956D01*
G03X122952Y611107I-8699J1D01*
G01X108509Y625552D01*
G02X105200Y633543I7991J7990D01*
G01Y721258D01*
G02X108129Y728329I10000J0D01*
G01X129171Y749371D01*
G03X132100Y756442I-7071J7071D01*
G01Y997758D01*
G03X129171Y1004829I-10000J0D01*
G01X60209Y1073790D01*
X53671Y1080328D01*
G02X51581Y1083337I7301J7301D01*
G02X50647Y1087629I9391J4291D01*
G01Y1401363D01*
G03X49492Y1403992I-3952J-168D01*
G01X44718Y1408766D01*
G02X43016Y1412872I4102J4106D01*
G01Y1427050D01*
G03X41261Y1431287I-5992J0D01*
G01X32987Y1439561D01*
G03X31256Y1440278I-1731J-1731D01*
G01X21443D01*
G03X20535Y1439902I0J-1284D01*
G02X18304Y1438978I-2231J2231D01*
G01X18298Y1438972D01*
X12569D01*
G01X106295Y956489D02*
G03X108951Y955389I2656J2656D01*
G03X112300Y958738I0J3349D01*
G01Y973721D01*
G03X111842Y974636I-1115J14D01*
G02X111385Y975551I658J900D01*
G01Y976676D01*
G02X111842Y977591I1115J15D01*
G03X112300Y978506I-657J901D01*
G01Y979631D01*
G03X111842Y980546I-1115J14D01*
G02X111385Y981461I658J900D01*
G01Y982586D01*
G02X111842Y983501I1115J15D01*
G03X112300Y984416I-657J901D01*
G01Y987800D01*
G03X108552Y996848I-12795J0D01*
G01X34903Y1070497D01*
G02X31974Y1077568I7071J7071D01*
G01Y1382367D01*
G03X31195Y1384246I-2656J0D01*
G01X31044Y1384397D01*
X31042Y1384402D01*
X30384Y1385061D01*
G02X29628Y1386937I1951J1877D01*
G01Y1389200D01*
G03X29118Y1390431I-1741J0D01*
G01X28499Y1391050D01*
G01X106295Y952989D02*
G02X108885Y954088I2655J-2656D01*
G03X108951I33J5056D01*
G03X113600Y958738I0J4649D01*
G01Y987799D01*
G03X109472Y997768I-14096J2D01*
G01X35823Y1071417D01*
G02X33274Y1077568I6150J6152D01*
G01Y1382368D01*
G03X32115Y1385166I-3957J0D01*
G01X32113Y1385168D01*
X32111Y1385172D01*
X31314Y1385970D01*
G02X30928Y1386938I1021J968D01*
G01Y1387550D01*
G02X31231Y1388280I1033J-1D01*
G01X32333Y1389383D01*
G01X33206Y1432352D02*
G03X32499Y1430645I1707J-1707D01*
G01Y1427054D01*
G03X33525Y1424577I3503J0D01*
G01X39450Y1418652D01*
X39449Y1418651D01*
G02X40616Y1415833I-2817J-2817D01*
G01Y1410022D01*
G03X41687Y1407436I3657J0D01*
G01X41688Y1407437D01*
X42607Y1406517D01*
X42606Y1406516D01*
X46628Y1402497D01*
G02X48247Y1398587I-3912J-3910D01*
G01Y1086359D01*
G03X51828Y1077713I12228J0D01*
G01X56394Y1073147D01*
Y1073146D01*
G03X56396Y1073145I140J277D01*
G01X91143Y1038397D01*
X125891Y1003649D01*
G02X129200Y995658I-7991J-7990D01*
G01Y758942D01*
G02X126271Y751871I-10000J0D01*
G01X105329Y730929D01*
G03X102400Y723858I7071J-7071D01*
G01Y631682D01*
G03X105329Y624611I10000J0D01*
G01X119291Y610649D01*
G02X122600Y602658I-7991J-7990D01*
G01Y503942D01*
G02X119291Y495951I-11300J-1D01*
G01X112849Y489509D01*
G03X110300Y483358I6150J-6152D01*
G01Y145340D01*
G02X107610Y142650I-2690J0D01*
G01X106905D01*
G03X104249Y141550I0J-3756D01*
G01Y145050D02*
G03X106905Y143950I2656J2656D01*
G01X107610D01*
G03X109000Y145340I0J1390D01*
G01Y483358D01*
G02X111929Y490429I10000J0D01*
G01X118371Y496871D01*
G03X121300Y503942I-7071J7071D01*
G01Y602658D01*
G03X118371Y609729I-10000J0D01*
G01X104409Y623691D01*
G02X101100Y631682I7991J7990D01*
G01Y723858D01*
G02X104409Y731849I11300J1D01*
G01X125351Y752791D01*
G03X127900Y758942I-6150J6152D01*
G01Y995658D01*
G03X124971Y1002729I-10000J0D01*
G01X55476Y1072225D01*
X50908Y1076793D01*
G02X46947Y1086358I9568J9565D01*
G01Y1398586D01*
G03X45708Y1401577I-4230J0D01*
G01X40767Y1406516D01*
X40768Y1406517D01*
G02X39316Y1410023I3505J3505D01*
G01Y1415834D01*
G03X38530Y1417732I-2684J0D01*
G01X32605Y1423657D01*
X32606Y1423658D01*
G02X31199Y1427055I3396J3396D01*
G01Y1431504D01*
G03X31017Y1432422I-2400J1D01*
G01X30661Y1433281D01*
G02X30499Y1434093I1960J813D01*
G01Y1434550D01*
G01X150591Y1019961D02*
X145695D01*
G02X145196Y1020168I0J705D01*
G02X144990Y1020665I497J497D01*
G01Y1021398D01*
G03X144708Y1021779I-399J-1D01*
G03X144590Y1021798I-122J-380D01*
G01X139000D01*
G02X132601Y1024447I-2J9048D01*
G01X67748Y1089300D01*
G02X65899Y1093765I4467J4465D01*
G01Y1215335D01*
G02X67748Y1219799I6315J-1D01*
G01X74573Y1226624D01*
G03X76199Y1230550I-3927J3926D01*
G01Y1234550D01*
G03X76184Y1234959I-5941J-13D01*
G01X76193Y1234968D01*
X76155Y1235502D01*
X76134Y1235802D01*
Y1235848D01*
G03X75264Y1237946I-2968J-1D01*
G01X68079Y1245131D01*
G02X65999Y1250153I5022J5022D01*
G01Y1391217D01*
G02X68630Y1397569I8985J-1D01*
G01X74664Y1403603D01*
G03X75243Y1405000I-1396J1397D01*
G01Y1407400D01*
G03X74604Y1408943I-2182J0D01*
G01X73399Y1410148D01*
G03X71478Y1410944I-1921J-1919D01*
G01X65774D01*
G02X62925Y1412125I2J4031D01*
G01X62924Y1412124D01*
X61925Y1413123D01*
X60249Y1414800D01*
G02X58381Y1419310I4509J4509D01*
G01Y1444550D01*
G03X56417Y1449292I-6706J0D01*
G01X56416Y1449291D01*
X50603Y1455104D01*
X35578Y1470130D01*
X35579D01*
G03X31599Y1471779I-3980J-3978D01*
G01X22380D01*
G03X21602Y1471591I0J-1704D01*
G01X21381Y1471477D01*
G03X21000Y1471200I692J-1352D01*
G02X19247Y1470474I-1753J1753D01*
G01X19241Y1470468D01*
X12569D01*
G01X150591Y1024961D02*
X145813D01*
X145800Y1024948D01*
X145416D01*
G03X145129Y1024829I0J-406D01*
G03X144990Y1024493I337J-336D01*
G01Y1023498D01*
G02X144718Y1023119I-400J0D01*
G02X144590Y1023098I-128J380D01*
G01X138999D01*
G02X133521Y1025367I0J7747D01*
G01X68668Y1090220D01*
G02X67199Y1093766I3546J3546D01*
G01Y1215334D01*
G02X68668Y1218880I5015J0D01*
G01X75418Y1225630D01*
X75419D01*
X75493Y1225704D01*
G03X77499Y1230549I-4848J4845D01*
G01Y1235050D01*
X77490Y1235057D01*
X77434Y1235848D01*
G03X76184Y1238866I-4268J0D01*
G01X68999Y1246051D01*
X68998D01*
G02X67300Y1250153I4104J4101D01*
G01X67299Y1250152D01*
Y1391216D01*
G02X69550Y1396650I7685J0D01*
G01X75199Y1402299D01*
X75200D01*
X75584Y1402683D01*
G03X76543Y1404999I-2317J2316D01*
G01Y1407399D01*
G03X75524Y1409863I-3483J2D01*
G01X75493Y1409894D01*
X75492Y1409893D01*
X74318Y1411068D01*
G03X71479Y1412244I-2839J-2839D01*
G01X65775D01*
G02X63844Y1413044I0J2731D01*
G01X61168Y1415720D01*
G02X59681Y1419310I3590J3590D01*
G01Y1444551D01*
G03X57337Y1450210I-8003J0D01*
G01X36498Y1471050D01*
G03X31600Y1473079I-4898J-4898D01*
G01X22599D01*
G02X22597I-1J1736D01*
G02X21273Y1473628I0J1871D01*
G03X19383Y1474411I-1890J-1890D01*
G01X19377Y1474405D01*
X12569D01*
G01X34465Y1481683D02*
X34318D01*
G03X32999Y1480364I0J-1319D01*
G03X33409Y1479374I1400J0D01*
G01X34076Y1478707D01*
X34282Y1478500D01*
X61213Y1451569D01*
G02X63381Y1446334I-5236J-5235D01*
G01Y1420019D01*
G03X64286Y1417837I3086J1D01*
G01X65277Y1416845D01*
G03X67196Y1416050I1919J1919D01*
G01X71999D01*
G02X76392Y1414231I1J-6212D01*
G01X81710Y1408910D01*
X81711Y1408911D01*
Y1408912D01*
X82659Y1407964D01*
X85719Y1404902D01*
X85720D01*
X86060Y1404560D01*
X86156Y1404465D01*
G02X88791Y1398100I-6367J-6364D01*
G01Y1391550D01*
G02X87519Y1388481I-4342J1D01*
G01Y1388480D01*
X86419Y1387380D01*
Y1387381D01*
G02X83326Y1386100I-3092J3092D01*
G01X76756D01*
G03X74100Y1385000I0J-3756D01*
G01X72600Y1383500D01*
G03X71299Y1380359I3141J-3141D01*
G01Y1255216D01*
X71300Y1255217D01*
G03X71920Y1253720I2117J0D01*
G03X72448Y1253500I530J528D01*
G01X77799D01*
G02X82647Y1251494I3J-6854D01*
G01X84620Y1249520D01*
G02X86284Y1247202I-6231J-6229D01*
G02X87200Y1243290I-7895J-3912D01*
G01Y1236519D01*
G02X81424Y1222575I-19720J0D01*
G01X72449Y1213600D01*
G03X70899Y1209858I3742J-3742D01*
G01Y1096037D01*
G03X72535Y1092087I5586J0D01*
G01X125723Y1038899D01*
X125853Y1038768D01*
G03X128967I1557J1557D01*
G01X129249Y1039050D01*
G01Y1035550D02*
G02X125802Y1036978I0J4874D01*
G01X125541Y1037239D01*
X124931Y1037850D01*
X124803Y1037979D01*
X124615Y1038168D01*
Y1038167D01*
X71615Y1091167D01*
X71616Y1091168D01*
G02X69599Y1096038I4869J4869D01*
G01Y1209859D01*
G02X71530Y1214519I6592J-1D01*
G01X71528D01*
X80504Y1223495D01*
G03X85900Y1236522I-13027J13027D01*
G01Y1243289D01*
G03X85119Y1246624I-7511J0D01*
G03X83700Y1248600I-6730J-3335D01*
G01X81727Y1250574D01*
G03X77800Y1252200I-3926J-3927D01*
G01X72449D01*
G02X71000Y1252800I0J2049D01*
G02X69999Y1255217I2417J2417D01*
G01Y1380358D01*
G02X71681Y1384419I5742J1D01*
G01X71680D01*
X73180Y1385919D01*
X73181D01*
G02X76757Y1387400I3575J-3575D01*
G01X83327D01*
G03X85500Y1388300I0J3073D01*
G01X86600Y1389400D01*
G03X87491Y1391551I-2151J2151D01*
G01Y1398100D01*
G03X85236Y1403545I-7701J0D01*
G01X85140Y1403641D01*
X84799Y1403983D01*
X81739Y1407044D01*
X81712Y1407072D01*
X81710Y1407071D01*
X75472Y1413311D01*
Y1413312D01*
G03X71999Y1414750I-3472J-3473D01*
G01X67193D01*
G02X64359Y1415924I0J4008D01*
G01X63366Y1416917D01*
G02X62081Y1420019I3102J3102D01*
G01Y1446335D01*
G03X60294Y1450649I-6101J0D01*
G01X34445Y1476497D01*
X33497Y1477445D01*
X33362Y1477581D01*
X32488Y1478455D01*
G02X30999Y1482050I3595J3595D01*
G01X85630Y1372677D02*
X90287D01*
G03X90952Y1372952I0J942D01*
G01X91062Y1373061D01*
G03X91229Y1373464I-403J403D01*
G01Y1374114D01*
G02X91508Y1374495I400J0D01*
G02X91629Y1374514I122J-381D01*
G01X94975D01*
G02X96813Y1373753I0J-2600D01*
G01X97229Y1373337D01*
G01X25507Y1372045D02*
X24773Y1371311D01*
G02X23322Y1370710I-1451J1451D01*
G01X21674D01*
G02X20262Y1371295I0J1997D01*
G03X18447Y1372047I-1815J-1815D01*
G01X18441Y1372041D01*
X12569D01*
G01X25558Y1368447D02*
G03X23233Y1369410I-2325J-2325D01*
G01X21899D01*
G03X20910Y1369001I-1J-1398D01*
G01X20719Y1368809D01*
G02X19031Y1368110I-1688J1688D01*
G01X19025Y1368104D01*
X12569D01*
G01X85630Y1377677D02*
X90707D01*
G02X91076Y1377524I0J-521D01*
G02X91229Y1377155I-368J-369D01*
G01Y1376214D01*
G03X91506Y1375833I401J0D01*
G03X91629Y1375814I122J381D01*
G01X93400D01*
G03X96496Y1377097I-1J4379D01*
G01X97000Y1377600D01*
G01X77166Y1346496D02*
X80134D01*
X80147Y1346483D01*
G02X82399Y1345550I0J-3185D01*
G03X82882Y1345350I483J483D01*
G01X83799D01*
G03X86882Y1346627I0J4360D01*
G01X86890Y1346635D01*
G01X77166Y1343347D02*
X80840D01*
X80853Y1343334D01*
G03X82099Y1343850I0J1762D01*
G02X82582Y1344050I483J-483D01*
G01X84017D01*
G02X86890Y1342860I0J-4063D01*
G01X77166Y1337047D02*
X80790D01*
X80803Y1337034D01*
G02X81991Y1336542I0J-1680D01*
G03X83179Y1336050I1188J1188D01*
G01X98400D01*
G03X100578Y1336952I0J3080D01*
G01X85630Y1362677D02*
X91030D01*
G02X91499Y1362208I0J-469D01*
G01Y1361739D01*
G03X92029Y1360900I928J-1D01*
G03X92092Y1360873I397J839D01*
G03X92100Y1360871I228J894D01*
G03X92155Y1360853I316J871D01*
G03X92268Y1360826I271J885D01*
G03X92422Y1360813I155J913D01*
G03X92424Y1360814I-413J829D01*
G01X102135D01*
G03X103509Y1361383I0J1943D01*
G01X104078Y1361952D01*
G01X77166Y1333898D02*
X80251D01*
X80264Y1333885D01*
G03X81749Y1334500I0J2100D01*
G02X82353Y1334750I604J-604D01*
G01X98099D01*
G02X100115Y1333915I0J-2851D01*
G01X100578Y1333452D01*
G01X85630Y1357677D02*
X90751D01*
G03X91339Y1358265I0J588D01*
G01Y1358853D01*
G02X91999Y1359513I660J0D01*
G02X92040Y1359514I35J-610D01*
G01X102265D01*
G02X103547Y1358983I0J-1813D01*
G01X104078Y1358452D01*
G01X878937Y614449D02*
X873871D01*
G02X873664Y614482I1J675D01*
G01X873499Y614535D01*
G02X873107Y615075I176J540D01*
G01Y615444D01*
G03X872860Y616039I-841J0D01*
G03X872264Y616286I-596J-596D01*
G01X775006D01*
X774999Y616293D01*
X774992Y616294D01*
X774785D01*
G02X770761Y617961I0J5691D01*
G01X409959Y1064871D01*
X239352Y1276197D01*
X92303Y1423246D01*
X91998Y1423549D01*
Y1423550D01*
G02X89349Y1429948I6395J6395D01*
G01Y1450049D01*
G03X87474Y1454574I-6399J0D01*
G01X40649Y1501399D01*
X40648D01*
X40200Y1501847D01*
Y1501849D01*
G03X36768Y1503270I-3431J-3432D01*
G01X21613D01*
G03X20751Y1502913I0J-1219D01*
G02X18474Y1501970I-2277J2277D01*
G01X18468Y1501964D01*
X12569D01*
G01X878937Y619449D02*
X873938D01*
G03X873274Y619174I0J-939D01*
G01X873136Y619036D01*
G03X872999Y618705I331J-331D01*
G01Y618511D01*
G02X872084Y617586I-925J0D01*
G02X872074I-5J925D01*
G01X775141D01*
X775085Y617594D01*
X774786D01*
G02X771727Y618836I1J4390D01*
G01X410972Y1065689D01*
X261634Y1250669D01*
X240321Y1277068D01*
X92918Y1424470D01*
G02X90649Y1429948I5474J5476D01*
G01Y1450050D01*
G03X88394Y1455494I-7699J0D01*
G01X41120Y1502768D01*
G03X36768Y1504570I-4351J-4351D01*
G01X21653D01*
G02X20724Y1504955I0J1314D01*
G03X18426Y1505907I-2298J-2298D01*
G01X18420Y1505901D01*
X12569D01*
G01X878937Y213937D02*
X874867D01*
G03X873192Y213244I-1J-2368D01*
G01X872499Y212550D01*
X872371Y212421D01*
G02X872184Y212277I-633J628D01*
G02X872155Y212261I-445J772D01*
G02X872040Y212211I-412J790D01*
G02X872023Y212205I-305J837D01*
G02X871733Y212159I-283J846D01*
G02X871392Y212231I10J891D01*
G01X871336Y212255D01*
X871318Y212263D01*
X871195Y212315D01*
X871191Y212317D01*
X870585Y212573D01*
X870032Y212808D01*
X870029Y212809D01*
X870025Y212811D01*
X870022Y212812D01*
X870008Y212819D01*
X869996Y212824D01*
X869993Y212825D01*
X869987Y212828D01*
X869979Y212831D01*
Y212832D01*
X836007Y227247D01*
G02X773066Y257733I274964J647904D01*
G01X773075Y257728D01*
G02X766259Y264716I8757J15359D01*
G01X323756Y1087804D01*
X214286Y1291427D01*
X214287D01*
X214132Y1291714D01*
X214131D01*
G03X212018Y1294517I-10077J-5398D01*
G03X211991Y1294542I-338J-339D01*
G01X95826Y1410713D01*
Y1410714D01*
X84494Y1422046D01*
G02X82749Y1426259I4213J4213D01*
G01Y1437050D01*
G03X80954Y1441386I-6131J1D01*
G01X79420Y1442920D01*
X79419D01*
X35417Y1486922D01*
X35248Y1487090D01*
G03X31001Y1488849I-4248J-4249D01*
G01X21881D01*
G02X20978Y1489223I0J1277D01*
G03X18718Y1490159I-2260J-2260D01*
G01X18712Y1490153D01*
X12569D01*
G01X878937Y208937D02*
X874059D01*
G02X872700Y209500I0J1922D01*
G01X872596Y209604D01*
G02X872429Y210007I404J404D01*
G03X872262Y210411I-571J1D01*
G03X871680Y210695I-2948J-5304D01*
G01X870827Y211057D01*
X870809Y211065D01*
X870686Y211117D01*
X870682Y211119D01*
X869147Y211770D01*
X835499Y226050D01*
G02X772441Y256593I275474J649100D01*
G02X765114Y264100I9391J16495D01*
G01X322610Y1087188D01*
X213140Y1290811D01*
X212985Y1291100D01*
G03X211071Y1293622I-8928J-4788D01*
G01X210346Y1294347D01*
X94526Y1410174D01*
Y1410175D01*
X83575Y1421126D01*
G02X81449Y1426259I5133J5133D01*
G01Y1437050D01*
G03X80034Y1440466I-4831J0D01*
G01X34500Y1486000D01*
X34330Y1486169D01*
X34329Y1486170D01*
G03X31000Y1487549I-3329J-3329D01*
G01X21954D01*
G03X20865Y1487098I0J-1540D01*
G02X18750Y1486222I-2115J2115D01*
G01X18744Y1486216D01*
X12569D01*
G01X34099Y1497550D02*
X33550Y1497001D01*
G03X32949Y1495550I1451J-1451D01*
G01Y1494950D01*
G03X33520Y1493571I1950J0D01*
G01X33770Y1493321D01*
X33777Y1493315D01*
G03X34423Y1492941I1023J1022D01*
G02X36253Y1492029I-1330J-4961D01*
G01X36616Y1491667D01*
X84750Y1443532D01*
G02X86449Y1439431I-4101J-4101D01*
G01Y1427675D01*
G03X88111Y1423663I5674J0D01*
G01X215490Y1296284D01*
X215668Y1296105D01*
X216111Y1295663D01*
X216638Y1295136D01*
G02X217601Y1293839I-3922J-3918D01*
G01X217717Y1293624D01*
X217719Y1293622D01*
X327516Y1089575D01*
X770525Y266290D01*
X770526Y266287D01*
X770623Y266107D01*
G03X773693Y262725I8362J4506D01*
G01X841950Y229532D01*
X841970Y229523D01*
X842685Y229176D01*
G03X845787Y228318I17233J56266D01*
G01X851120Y227324D01*
X852287D01*
G03X853709Y227913I0J2011D01*
G02X854943Y228424I1234J-1234D01*
G01X855728D01*
G01Y224924D02*
X854018Y225297D01*
G02X852878Y225712I965J4423D01*
G01X852486Y225918D01*
G03X852167Y226010I-386J-740D01*
G01X851999Y226024D01*
X851083D01*
G02X850916Y226039I-2J914D01*
G01X845724Y227007D01*
G02X845474Y227056I373J2568D01*
G02X842305Y227933I14452J58384D01*
G01X842304Y227932D01*
X842208Y227962D01*
X841419Y228345D01*
X841399Y228354D01*
X773381Y261431D01*
G02X769378Y265673I5884J9562D01*
G01X326370Y1088959D01*
X216456Y1293223D01*
G03X215718Y1294216I-3738J-2007D01*
G01X214747Y1295187D01*
X214569Y1295366D01*
X87191Y1422744D01*
G02X85149Y1427674I4932J4931D01*
G01Y1439430D01*
G03X83831Y1442612I-4500J0D01*
G01X75403Y1451040D01*
X67067Y1459375D01*
X37971Y1488472D01*
X35946Y1490497D01*
Y1490498D01*
X35697Y1490748D01*
X35453Y1491004D01*
G03X34087Y1491686I-2362J-3022D01*
G01X34086Y1491684D01*
G02X34084Y1491685I1227J2457D01*
G02X32899Y1492355I717J2651D01*
G01X32886Y1492366D01*
X32850Y1492401D01*
X32600Y1492651D01*
G02X31649Y1494950I2300J2297D01*
G01Y1495550D01*
G03X31048Y1497001I-2052J0D01*
G01X30499Y1497550D01*
G01X855583Y1039392D02*
G02X851999Y1038292I-3584J5289D01*
G01X842303D01*
G02X838335Y1038967I-453J9336D01*
G01X260918Y1273207D01*
G02X258032Y1275063I2829J7571D01*
G01X108522Y1424573D01*
X103932Y1429160D01*
G02X101749Y1434430I5270J5270D01*
G01Y1458971D01*
G03X99749Y1463800I-6831J-1D01*
G01X49335Y1514214D01*
G02X47617Y1518362I4148J4148D01*
G01Y1520931D01*
X47618Y1520932D01*
Y1535050D01*
G03X43424Y1544476I-12689J0D01*
G01X32174Y1555726D01*
G03X31174Y1556725I-999000J-999000D01*
G02X29349Y1561050I4212J4325D01*
G01Y1569550D01*
G02X30520Y1572049I3252J0D01*
G01X878937Y1019961D02*
X878910Y1019988D01*
X873694D01*
G02X873212Y1020188I0J681D01*
G01X873079Y1020321D01*
G02X872972Y1020471I388J390D01*
G01X872932Y1020555D01*
G02X872900Y1020698I300J142D01*
G03X872324Y1021665I-1100J0D01*
G03X871800Y1021798I-524J-966D01*
G01X860442D01*
G02X857646Y1022247I-438J6203D01*
G01X259947Y1267269D01*
G02X259729Y1267363I724J1978D01*
G02X255891Y1270129I6597J13199D01*
G01X255889Y1270127D01*
X252743Y1273275D01*
X104984Y1421035D01*
X101934Y1424084D01*
X100055Y1425963D01*
X100054Y1425965D01*
X98984Y1427035D01*
G02X96749Y1432436I5408J5401D01*
G01Y1455825D01*
G03X94999Y1460050I-5975J0D01*
G01X42999Y1512050D01*
G02X40581Y1517888I5837J5837D01*
G01Y1537614D01*
G03X39623Y1539925I-3269J-1D01*
G01X25801Y1553748D01*
G03X24104Y1554451I-1697J-1697D01*
G01X21606D01*
G03X20628Y1554046I0J-1383D01*
G02X18467Y1553151I-2161J2161D01*
G01X18461Y1553145D01*
X12569D01*
G01X878937Y1024961D02*
X873669D01*
G03X873314Y1024814I0J-502D01*
G01X873167Y1024667D01*
G03X872999Y1024261I407J-406D01*
G01Y1024023D01*
G02X872402Y1023158I-925J0D01*
G02X872334Y1023135I-330J864D01*
G02X872074Y1023098I-259J888D01*
G01X860396D01*
X860351Y1023095D01*
G02X858138Y1023449I-350J4907D01*
G01X858139Y1023450D01*
X260310Y1268526D01*
G02X256810Y1271048I6015J12037D01*
G01X253663Y1274195D01*
X105904Y1421955D01*
X102854Y1425004D01*
X100977Y1426881D01*
X100976Y1426883D01*
X99904Y1427955D01*
G02X98049Y1432435I4482J4480D01*
G01Y1455825D01*
G03X95918Y1460970I-7275J1D01*
G01X43918Y1512970D01*
G02X41881Y1517888I4918J4918D01*
G01Y1537615D01*
G03X40543Y1540845I-4569J-1D01*
G01X26721Y1554668D01*
G03X24104Y1555751I-2616J-2617D01*
G01X22126D01*
G02X21131Y1556163I0J1407D01*
G03X18898Y1557088I-2233J-2233D01*
G01X18892Y1557082D01*
X12569D01*
G01X855583Y1035892D02*
G03X851881Y1036953I-4583J-9002D01*
G03X850999Y1036992I-887J-10062D01*
G01X842366D01*
Y1036993D01*
G02X837847Y1037763I-513J10635D01*
G01X837846Y1037762D01*
X260462Y1271989D01*
G02X257111Y1274142I4055J9995D01*
G01X107602Y1423653D01*
X103012Y1428241D01*
G02X100449Y1434429I6190J6189D01*
G01Y1458970D01*
G03X98829Y1462881I-5531J0D01*
G01X48416Y1513294D01*
G02X46317Y1518362I5067J5067D01*
G01Y1521470D01*
X46318Y1521471D01*
Y1535050D01*
G03X42554Y1543510I-11389J0D01*
G01X42528Y1543532D01*
X30266Y1555794D01*
G02X28049Y1561050I5121J5255D01*
G01Y1569550D01*
G03X27123Y1572205I-4269J0D01*
G01X855946Y630382D02*
G03X852999Y631482I-2947J-3398D01*
G01X772214D01*
G02X761743Y635849I1J14738D01*
G01X414666Y1066619D01*
X250879Y1269902D01*
G03X250874Y1269908I-291J-237D01*
G01X250866Y1269918D01*
X95616Y1425168D01*
X95040Y1425745D01*
G02X94067Y1426973I4804J4806D01*
G02X93049Y1430550I5778J3578D01*
G01Y1452050D01*
G03X91505Y1455778I-5273J0D01*
G01X41866Y1505417D01*
X41586Y1505698D01*
G03X38499Y1506976I-3086J-3087D01*
G01X36127D01*
G02X32724Y1508385I0J4813D01*
G01X32149Y1508961D01*
G02X31386Y1510802I1840J1841D01*
G03X30288Y1511900I-1098J0D01*
G01X30115D01*
G01X855946Y633882D02*
G02X852999Y632782I-2947J3398D01*
G01X772215D01*
G02X762713Y636718I0J13438D01*
G01X415678Y1067435D01*
X251835Y1270788D01*
X96536Y1426087D01*
X95960Y1426664D01*
Y1426665D01*
G02X95173Y1427658I3884J3887D01*
G02X94349Y1430550I4672J2894D01*
G01Y1452051D01*
G03X92425Y1456698I-6574J0D01*
G01X42787Y1506336D01*
X42507Y1506617D01*
G03X38499Y1508276I-4006J-4007D01*
G01X36128D01*
G02X33644Y1509305I0J3513D01*
G01X33068Y1509881D01*
G02X32686Y1510802I919J921D01*
G01Y1511225D01*
G02X33512Y1512051I826J0D01*
G01X31999Y1517846D02*
X31416Y1518429D01*
G03X30298Y1518995I-1422J-1421D01*
G03X29999Y1519018I-302J-1976D01*
G01X22376D01*
G03X21947Y1518975I3J-2192D01*
G03X20826Y1518376I428J-2150D01*
G02X19237Y1517718I-1589J1589D01*
G01X19231Y1517712D01*
X12569D01*
G01X31999Y1521500D02*
X31396Y1520896D01*
G02X29999Y1520318I-1396J1397D01*
G01X22444D01*
G02X20930Y1520945I0J2141D01*
G03X19216Y1521655I-1714J-1714D01*
G01X19210Y1521649D01*
X12569D01*
G01X107249Y1767550D02*
G03X109012Y1766551I2619J2567D01*
G03X109863Y1766450I853J3553D01*
G03X111631Y1767182I0J2501D01*
G01X111867Y1767418D01*
G03X112599Y1769186I-1769J1768D01*
G01Y1775826D01*
G03X111867Y1777594I-2501J0D01*
G01X85127Y1804334D01*
G03X80499Y1806251I-4628J-4628D01*
G01Y1806250D01*
X75999D01*
G03X71219Y1804270I0J-6760D01*
G01X68825Y1801876D01*
G03X65949Y1794933I6943J-6943D01*
G01Y1660004D01*
G02X62834Y1652484I-10635J0D01*
G01X36643Y1626293D01*
G02X34149Y1625260I-2494J2494D01*
G01X32896D01*
G02X31985Y1625638I1J1289D01*
G01X31776Y1625846D01*
G02X30906Y1627534I2204J2204D01*
G03X30122Y1629427I-2677J0D01*
G01X29499Y1630050D01*
G01X857077Y1440796D02*
G03X854144Y1441896I-2933J-3360D01*
G01X830499D01*
G02X826783Y1442443I0J12896D01*
G01X798279Y1451954D01*
X327885Y1608910D01*
G03X324948Y1609408I-3385J-11053D01*
G03X324499Y1609417I-456J-11551D01*
G01X32734D01*
G02X29999Y1610550I0J3868D01*
G02X28899Y1613206I2656J2656D01*
G01Y1613524D01*
G01X878937Y1835985D02*
X872716D01*
G03X871999Y1835268I0J-717D01*
G01Y1834550D01*
G02X871582Y1834133I-417J0D01*
G01X293356D01*
G03X292961Y1834127I8J-13549D01*
G01X292463D01*
G03X284397Y1830786I0J-11407D01*
G01X264922Y1811311D01*
G02X264920Y1811309I-6664J6662D01*
G02X258261Y1808550I-6659J6657D01*
G01X142931D01*
G02X136796Y1811092I0J8675D01*
G01X129418Y1818470D01*
G03X124599Y1820466I-4819J-4819D01*
G01X74400D01*
G03X62444Y1815446I0J-16748D01*
G03X60949Y1811238I5176J-4208D01*
G01Y1660577D01*
G02X59479Y1657028I-5019J0D01*
G01X58499Y1656050D01*
X42249Y1639801D01*
G02X38936Y1638428I-3313J3311D01*
G01X21444D01*
G02X20556Y1638796I0J1256D01*
G03X18217Y1639765I-2339J-2339D01*
G01X18211Y1639759D01*
X12569D01*
G01X878937Y1830985D02*
X873064D01*
G02X871999Y1832050I0J1065D01*
G03X871670Y1832687I-781J0D01*
G03X871321Y1832825I-454J-637D01*
G03X871216Y1832833I-112J-774D01*
G01X292480D01*
G03X285317Y1829866I0J-10130D01*
G01X265842Y1810391D01*
G02X265840Y1810389I-7584J7582D01*
G02X258262Y1807250I-7578J7578D01*
G01X142930D01*
G02X135876Y1810172I0J9976D01*
G01X128498Y1817550D01*
G03X124599Y1819166I-3900J-3898D01*
G01X74400D01*
G03X63414Y1814576I0J-15442D01*
G03X62249Y1811237I4205J-3340D01*
G01Y1660581D01*
G02X60398Y1656108I-6325J-2D01*
G01X59418Y1655130D01*
X43169Y1638881D01*
G02X38937Y1637128I-4232J4232D01*
G01X21500D01*
G03X20464Y1636699I0J-1465D01*
G02X18361Y1635828I-2103J2103D01*
G01X18355Y1635822D01*
X12569D01*
G01X878937Y1425473D02*
X873618D01*
G02X872999Y1426092I0J619D01*
G01Y1426710D01*
G03X872399Y1427310I-600J0D01*
G01X849999D01*
G02X847257Y1427733I0J9099D01*
G01X793806Y1445931D01*
X734308Y1466189D01*
X326771Y1604947D01*
G03X322999Y1605549I-3772J-11516D01*
G01X21586D01*
G03X20681Y1605174I0J-1280D01*
G02X18648Y1604332I-2033J2033D01*
G01X18642Y1604326D01*
X12569D01*
G01X878937Y1430473D02*
X873630D01*
G03X872999Y1429842I0J-631D01*
G01Y1429210D01*
G02X872399Y1428610I-600J0D01*
G01X849999D01*
G02X847583Y1428996I0J7754D01*
G01X794226Y1447163D01*
X734728Y1467421D01*
X327305Y1606139D01*
G03X327175Y1606183I-2274J-6505D01*
G03X322999Y1606849I-4175J-12752D01*
G01X21733D01*
G02X21656Y1606851I-2J1417D01*
G02X20732Y1607263I75J1410D01*
G01X20731Y1607264D01*
G03X18305Y1608269I-2426J-2426D01*
G01X18299Y1608263D01*
X12569D01*
G01X857077Y1444296D02*
G02X854144Y1443196I-2933J3360D01*
G01X830499D01*
G02X827206Y1443674I0J11582D01*
G01X798690Y1453188D01*
X328287Y1610148D01*
G03X324999Y1610707I-3799J-12397D01*
G03X324500Y1610717I-507J-12850D01*
G01X32735D01*
G02X30919Y1611470I0J2567D01*
G02X30878Y1611513I1756J1715D01*
G02X30895Y1612446I492J458D01*
G01X31743Y1613293D01*
G02X32299Y1613524I557J-556D01*
G01X85630Y1783189D02*
X90758D01*
X90771Y1783176D01*
G02X91799Y1782750I0J-1454D01*
G01X92823Y1781726D01*
G03X92898Y1781662I426J424D01*
G03X92904Y1781657I387J458D01*
G03X93248Y1781550I342J494D01*
G01X95240D01*
G03X95869Y1781715I8J1250D01*
G01X95909Y1781738D01*
G03X96498Y1782800I-661J1061D01*
G01X96499Y1782799D01*
Y1785846D01*
X96498Y1785845D01*
G03X96001Y1787045I-1697J0D01*
G01Y1787046D01*
X95498Y1787550D01*
X91191Y1791857D01*
G03X90507Y1792442I-4087J-4086D01*
G03X87106Y1793550I-3402J-4670D01*
G01X81499D01*
G03X76377Y1791429I-1J-7243D01*
G01X75999Y1791050D01*
X72413Y1787464D01*
G03X69649Y1780791I6673J-6673D01*
G01Y1749670D01*
G03X70106Y1748755I1115J-15D01*
G02X70564Y1747840I-657J-901D01*
G01Y1746715D01*
G02X70106Y1745800I-1115J-14D01*
G03X69649Y1744885I658J-900D01*
G01Y1743760D01*
G03X70106Y1742845I1115J-15D01*
G02X70564Y1741930I-657J-901D01*
G01Y1740805D01*
G02X70106Y1739890I-1115J-14D01*
G03X69649Y1738975I658J-900D01*
G01Y1714911D01*
G03X70106Y1713996I1115J-15D01*
G02X70564Y1713081I-657J-901D01*
G01Y1711956D01*
G02X70106Y1711041I-1115J-14D01*
G03X69649Y1710126I658J-900D01*
G01Y1709001D01*
G03X70106Y1708086I1115J-15D01*
G02X70564Y1707171I-657J-901D01*
G01Y1706046D01*
G02X70106Y1705131I-1115J-14D01*
G03X69649Y1704216I658J-900D01*
G01Y1703091D01*
G03X70106Y1702176I1115J-15D01*
G02X70564Y1701261I-657J-901D01*
G01Y1700136D01*
G02X70106Y1699221I-1115J-14D01*
G03X69649Y1698306I658J-900D01*
G01Y1689479D01*
G03X70106Y1688564I1115J-15D01*
G02X70564Y1687649I-657J-901D01*
G01Y1686524D01*
G02X70106Y1685609I-1115J-14D01*
G03X69649Y1684694I658J-900D01*
G01Y1683569D01*
G03X70106Y1682654I1115J-15D01*
G02X70564Y1681739I-657J-901D01*
G01Y1680614D01*
G02X70106Y1679699I-1115J-14D01*
G03X69649Y1678784I658J-900D01*
G01Y1677659D01*
G03X70106Y1676744I1115J-15D01*
G02X70564Y1675829I-657J-901D01*
G01Y1674704D01*
G02X70106Y1673789I-1115J-14D01*
G03X69649Y1672874I658J-900D01*
G01Y1656996D01*
G03X73259Y1647522I14236J0D01*
G01X73262Y1647519D01*
G03X73820Y1646928I10627J9475D01*
G01X77725Y1643023D01*
G02X79578Y1638551I-4472J-4473D01*
G01Y1626979D01*
G02X78199Y1623650I-4708J0D01*
G02X72719Y1621380I-5480J5480D01*
G01X21668D01*
G03X20683Y1620972I0J-1393D01*
G02X18530Y1620080I-2153J2153D01*
G01X18524Y1620074D01*
X12569D01*
G01X85630Y1778189D02*
X90447D01*
G03X91135Y1778474I0J973D01*
G03X91499Y1779213I-706J807D01*
G02X92536Y1780250I1037J0D01*
G01X95231D01*
G03X96514Y1780586I18J2550D01*
G01Y1780585D01*
G03X97799Y1782800I-1265J2214D01*
G01Y1785845D01*
G03X96921Y1787965I-2998J0D01*
G01X96418Y1788469D01*
X92111Y1792777D01*
G03X87106Y1794850I-5004J-5003D01*
G01X81499D01*
Y1794849D01*
G03X75457Y1792348I-2J-8543D01*
G01X71493Y1788384D01*
G03X68349Y1780791I7594J-7592D01*
G01Y1656995D01*
G03X72288Y1646656I15538J0D01*
G03X72900Y1646008I11598J10340D01*
G01X76805Y1642103D01*
G02X78278Y1638551I-3551J-3554D01*
G01Y1626980D01*
G02X77279Y1624570I-3407J0D01*
G02X72718Y1622680I-4561J4559D01*
G01X21605D01*
G02X20777Y1623023I0J1171D01*
G03X18377Y1624017I-2400J-2400D01*
G01X18371Y1624011D01*
X12569D01*
G01X32663Y1628181D02*
Y1627143D01*
G03X33246Y1626560I583J0D01*
G01X34419D01*
G03X35532Y1627021I0J1574D01*
G01X62030Y1653519D01*
G03X64649Y1659842I-6323J6323D01*
G01Y1794934D01*
G02X67905Y1802795I11119J-1D01*
G01X70299Y1805189D01*
G02X75999Y1807550I5700J-5700D01*
G01X80342D01*
G02X80499Y1807552I178J-7844D01*
G02X86047Y1805254I0J-7846D01*
G01X112787Y1778514D01*
G02X113899Y1775826I-2690J-2687D01*
G01Y1769186D01*
G02X112787Y1766498I-3802J-1D01*
G01X112551Y1766262D01*
G02X109863Y1765150I-2687J2690D01*
G01X109385D01*
G03X107249Y1764050I0J-2624D01*
G01X150591Y1830985D02*
X146048D01*
G02X144797Y1831503I0J1770D01*
G02X144499Y1832222I718J719D01*
G03X144091Y1832789I-598J0D01*
G03X143899Y1832822I-192J-542D01*
G01X118485D01*
G02X111616Y1835667I-1J9713D01*
G01X111615Y1835666D01*
X94628Y1852654D01*
G03X88040Y1855383I-6588J-6588D01*
G01X62842D01*
G03X59535Y1854013I0J-4677D01*
G01X57035Y1851513D01*
G03X54849Y1846236I5277J-5277D01*
G01Y1674522D01*
G02X51972Y1667576I-9823J0D01*
G01X38472Y1654076D01*
G02X35575Y1652876I-2897J2897D01*
G01X21703D01*
G03X20638Y1652435I0J-1506D01*
G02X18564Y1651576I-2074J2074D01*
G01X18558Y1651570D01*
X12569D01*
G01X150591Y1835985D02*
X146354D01*
G03X144700Y1835300I0J-2339D01*
G01X144441Y1835042D01*
G03X144300Y1834700I342J-341D01*
G01Y1834622D01*
G02X143800Y1834122I-500J0D01*
G01X118484D01*
G02X112535Y1836586I0J8413D01*
G01X95547Y1853574D01*
G03X88041Y1856683I-7507J-7508D01*
G01X62841D01*
G03X58616Y1854932I2J-5977D01*
G01X58615D01*
X56115Y1852432D01*
G03X53549Y1846237I6197J-6196D01*
G01Y1674522D01*
G02X51053Y1668496I-8522J0D01*
G01X37465Y1654908D01*
G02X35697Y1654176I-1768J1769D01*
G01X21793D01*
G02X20556Y1654689I1J1750D01*
G01X20555D01*
G03X18566Y1655513I-1989J-1989D01*
G01X18560Y1655507D01*
X12569D01*
G01X128342Y1849754D02*
X128263Y1849675D01*
G02X125499Y1848530I-2764J2764D01*
G01X113842D01*
G02X108989Y1850540I0J6863D01*
G01X100238Y1859291D01*
G03X94784Y1861550I-5455J-5456D01*
G01X62474D01*
G03X58249Y1859799I2J-5977D01*
G01X58248D01*
X52499Y1854050D01*
G03X49849Y1847652I6397J-6397D01*
G01Y1675786D01*
G02X47897Y1671075I-6663J1D01*
G01X47686Y1670863D01*
X35129Y1658306D01*
G02X34743Y1658028I-1037J1033D01*
G02X34700Y1658008I-639J1317D01*
G02X34304Y1657892I-605J1332D01*
G02X34091Y1657876I-216J1448D01*
G01X33209D01*
G02X31499Y1658552I0J2501D01*
G01X31353Y1658698D01*
G02X31124Y1659017I853J854D01*
G01X31123D01*
G02X30999Y1659551I1083J533D01*
G02Y1659568I1393J9D01*
G02X31000Y1659593I1392J-43D01*
G03X30995Y1659809I-1997J62D01*
G02X31179Y1660307I633J49D01*
G01X31999Y1661127D01*
G01X128342Y1846254D02*
G03X125986Y1847230I-2356J-2356D01*
G01X113843D01*
G02X108070Y1849621I-1J8163D01*
G01X108069Y1849620D01*
X99319Y1858371D01*
G03X94783Y1860250I-4536J-4536D01*
G01X62475D01*
G03X59168Y1858880I0J-4677D01*
G01X53418Y1853130D01*
G03X51149Y1847652I5478J-5478D01*
G01Y1675786D01*
G02X48816Y1670155I-7962J0D01*
G01X48605Y1669943D01*
X38605Y1659943D01*
X36049Y1657386D01*
G02X35319Y1656862I-1955J1954D01*
G02X34095Y1656576I-1224J2476D01*
G01X33209D01*
G02X30521Y1657688I-1J3802D01*
G01X30433Y1657776D01*
Y1657778D01*
G02X29699Y1659546I1773J1772D01*
G02Y1659579I2693J17D01*
G02X29700Y1659630I2693J-27D01*
G03X29496Y1660143I-697J20D01*
G01X28600Y1661039D01*
G01X29626Y1645002D02*
G02X30116Y1644007I-1218J-1218D01*
G01X30218Y1643226D01*
G03X30933Y1641776I2487J325D01*
G03X33224Y1640828I2290J2291D01*
G01X35000D01*
G03X37098Y1641697I0J2968D01*
G01X37974Y1642573D01*
X53975Y1658573D01*
X57435Y1662032D01*
G03X58549Y1664719I-2686J2688D01*
G01Y1813371D01*
G02X60051Y1816997I5128J0D01*
G02X74400Y1822866I14171J-14171D01*
G01X127999D01*
Y1822867D01*
G02X130021Y1822029I-1J-2861D01*
G01X130498Y1821551D01*
X130804Y1821245D01*
G03X134896Y1819550I4092J4092D01*
G01X134897Y1819549D01*
X134898Y1819550D01*
X264482D01*
G03X269157Y1820646I0J10518D01*
G03X271919Y1822630I-4675J9422D01*
G01X283574Y1834284D01*
G02X289000Y1836533I5427J-5424D01*
G01X829300D01*
Y1836534D01*
G03X835569Y1839128I3J8864D01*
G01X840519Y1844080D01*
X840520D01*
X842248Y1845808D01*
G02X849501Y1848813I7253J-7251D01*
G01X854499D01*
G02X858537Y1847141I1J-5710D01*
G01X859064Y1846613D01*
G01X33026Y1645051D02*
G03X32128Y1644679I0J-1270D01*
G01X31853Y1644404D01*
G03X31509Y1643394I853J-854D01*
G03X31853Y1642696I1197J156D01*
G03X33224Y1642128I1371J1371D01*
G01X34999D01*
G03X36178Y1642617I-1J1668D01*
G01X37055Y1643493D01*
X53055Y1659493D01*
X56516Y1662953D01*
G03X57249Y1664721I-1767J1768D01*
G01Y1813372D01*
G02X59131Y1817917I6429J0D01*
G02X74400Y1824166I15090J-15091D01*
G01X127999D01*
G02X130941Y1822948I1J-4160D01*
G01X131418Y1822470D01*
X131723Y1822165D01*
G03X134897Y1820850I3174J3172D01*
G01X264481D01*
G03X268579Y1821811I0J9218D01*
G03X270999Y1823550I-4098J8257D01*
G01X282654Y1835204D01*
G02X288999Y1837833I6346J-6345D01*
G01X829300D01*
G03X834649Y1840048I1J7564D01*
G01X839600Y1845000D01*
X841328Y1846728D01*
G02X849500Y1850113I8172J-8172D01*
G01X859064D01*
G01X32494Y1669706D02*
X31762Y1668974D01*
G03X31400Y1668100I874J-874D01*
G01Y1667600D01*
G03X31655Y1666984I872J0D01*
G01X31719Y1666920D01*
G03X32733Y1666500I1014J1014D01*
G01X33800D01*
G03X35848Y1667348I0J2897D01*
G01X39750Y1671250D01*
G03X41200Y1674751I-3501J3501D01*
G01Y1724394D01*
G02X42080Y1726519I3005J0D01*
G02X43966Y1727300I1886J-1886D01*
G01X44000D01*
G03X45195Y1727795I0J1690D01*
G01X45877Y1728477D01*
G01X29100Y1669500D02*
X29817Y1668783D01*
G02X30100Y1668100I-683J-683D01*
G01Y1667599D01*
G03X30735Y1666064I2173J0D01*
G01X30799Y1666000D01*
X30800Y1666001D01*
G03X32734Y1665200I1933J1933D01*
G01X33799D01*
G03X36768Y1666428I2J4198D01*
G01X40669Y1670329D01*
Y1670331D01*
G03X42500Y1674752I-4420J4420D01*
G01Y1724393D01*
G02X43000Y1725600I1707J0D01*
G02X43966Y1726000I966J-966D01*
G01X44000D01*
G02X45195Y1725505I0J-1690D01*
G01X45877Y1724823D01*
G01X47000Y1737100D02*
X46195Y1736295D01*
G03X45700Y1735100I1195J-1195D01*
G01Y1734600D01*
G02X43900Y1732800I-1800J0D01*
G01X42507D01*
G03X41300Y1732300I0J-1707D01*
G01X39861Y1730860D01*
G03X38800Y1728300I2560J-2561D01*
G01Y1685156D01*
G02X37319Y1681580I-5056J-1D01*
G01X25697Y1669958D01*
G02X23500Y1669050I-2195J2200D01*
G01Y1669049D01*
X22589D01*
G03X22235Y1669006I1J-1489D01*
G03X21536Y1668613I353J-1446D01*
G01X20733Y1667810D01*
G02X19560Y1667324I-1173J1173D01*
G01X12575D01*
X12569Y1667318D01*
G01Y1671255D02*
X12575Y1671261D01*
X20338D01*
G02X20763Y1671085I0J-601D01*
G01X21198Y1670650D01*
X21199D01*
G03X21926Y1670349I727J727D01*
G01X23500D01*
G03X24778Y1670879I-1J1808D01*
G01X25050Y1671150D01*
X36400Y1682500D01*
G03X37500Y1685156I-2656J2656D01*
G01Y1728300D01*
X37501D01*
G02X38941Y1731780I4921J2D01*
G01X40380Y1733220D01*
G02X42506Y1734100I2126J-2128D01*
G01X43900D01*
G03X44400Y1734600I0J500D01*
G01Y1735700D01*
G03X43976Y1736724I-1449J0D01*
G01X43600Y1737100D01*
G01X77166Y1752008D02*
X80724D01*
X80737Y1751995D01*
G02X81701Y1751754I1J-2045D01*
G01X81829Y1751626D01*
G03X81972Y1751509I665J667D01*
G03X82498Y1751350I526J790D01*
G01X83180D01*
G03X83744Y1751402I3J3056D01*
G03X85341Y1752245I-564J3004D01*
G01X77166Y1748859D02*
X79950D01*
X79963Y1748846D01*
G03X81293Y1749397I0J1881D01*
G01X81558Y1749663D01*
G02X82492Y1750050I934J-934D01*
G01X83499D01*
G02X84800Y1749511I0J-1840D01*
G01X85084Y1749227D01*
G02X85199Y1748950I-276J-277D01*
G01Y1748848D01*
G02X85194I-2J102D01*
G01X77166Y1742559D02*
X81668D01*
X81681Y1742546D01*
G02X82190Y1742335I0J-720D01*
G03X83361Y1741850I1171J1171D01*
G01X99199D01*
G03X101503Y1742805I-1J3259D01*
G01X101749Y1743050D01*
G01X85630Y1768189D02*
X90234D01*
G02X90557Y1768125I0J-847D01*
G01X90835Y1768010D01*
G02X91140Y1767706I-215J-521D01*
G01X91186Y1767594D01*
G02X91229Y1767379I-519J-216D01*
G01Y1766726D01*
G03X91497Y1766348I401J0D01*
G03X91629Y1766326I131J378D01*
G01X100794D01*
G03X103749Y1767550I0J4179D01*
G01X77166Y1739410D02*
X80692D01*
X80705Y1739397D01*
G03X81799Y1739850I0J1547D01*
G01X82249Y1740300D01*
G02X82853Y1740550I604J-604D01*
G01X99335D01*
G02X101749Y1739550I0J-3414D01*
G01X85630Y1763189D02*
X90400D01*
G03X90970Y1763425I0J806D01*
G03X91101Y1763639I-614J523D01*
G01X91167Y1763799D01*
G03X91229Y1764108I-743J310D01*
G01Y1764626D01*
G02X91497Y1765002I398J0D01*
G02X91507Y1765006I153J-367D01*
G02X91563Y1765020I125J-379D01*
G02X91570Y1765021I60J-395D01*
G02X91629Y1765026I63J-395D01*
G01X101393D01*
G02X103749Y1764050I0J-3332D01*
G01X108749Y126050D02*
X109999D01*
G03X110994Y126462I0J1407D01*
G01X111458Y126926D01*
G02X111999Y127150I541J-541D01*
G01X114499D01*
G02X115876Y125973I0J-1394D01*
G01X108749Y129550D02*
X109999D01*
G02X110994Y129138I0J-1407D01*
G01X111385Y128747D01*
G03X111544Y128618I715J719D01*
G03X111950Y128450I406J406D01*
G01X114999D01*
G03X115876Y129327I0J877D01*
G01Y130050D01*
G01X150591Y223937D02*
X145708D01*
G02X144990Y224656I0J718D01*
G01Y225374D01*
G03X144678Y225763I-399J-1D01*
G03X144590Y225774I-93J-388D01*
G01X134704D01*
G03X131749Y224550I0J-4179D01*
G01X150591Y228937D02*
X145722D01*
G03X144990Y228206I-1J-731D01*
G01Y227474D01*
G02X144590Y227074I-400J0D01*
G01X134105D01*
G02X131749Y228050I0J3332D01*
G01X159055Y243267D02*
X155105D01*
X155092Y243254D01*
G03X154457Y242991I0J-898D01*
G01X154157Y242691D01*
G02X153285Y242330I-872J872D01*
G01X151593D01*
G02X151536Y242331I-11J1014D01*
G02X150876Y242627I58J1013D01*
G01X149999Y243504D01*
G01X159055Y240118D02*
X155136D01*
X155123Y240105D01*
G02X154437Y240389I0J970D01*
G01X154218Y240608D01*
G03X153199Y241030I-1019J-1019D01*
G01X151632D01*
G03X151067Y240796I0J-799D01*
G01X149999Y239729D01*
G01X128249Y252550D02*
X126874Y251175D01*
G02X126089Y250850I-785J785D01*
G01X123823D01*
G02X123099Y251150I0J1024D01*
G01X122798Y251451D01*
G02X122397Y252419I968J968D01*
G01Y252688D01*
G01X128249Y249050D02*
G03X127042Y249550I-1207J-1207D01*
G01X123765D01*
G03X122799Y249150I0J-1366D01*
G01X159055Y249567D02*
X154497D01*
X154484Y249554D01*
G02X153649Y249900I0J1181D01*
G03X153000Y250169I-649J-649D01*
G01X134399D01*
G03X134251Y250166I1J-3696D01*
G03X134031Y250150I158J-3692D01*
G03X131786Y249086I368J-3677D01*
G01X131749Y249050D01*
G01X159055Y252716D02*
X155212D01*
X155199Y252703D01*
G03X154201Y252289I1J-1412D01*
G01X154130Y252219D01*
X153830Y251919D01*
G02X153557Y251702I-1086J1086D01*
G02X152744Y251469I-813J1303D01*
G01X132346D01*
G02X131924Y251644I0J596D01*
G02X131749Y252066I421J422D01*
G01Y252550D01*
G01X104695Y522488D02*
G02X107351Y523588I2656J-2656D01*
G01X108398D01*
G02X109091Y523347I0J-1117D01*
G02X109189Y523261I-686J-881D01*
G01X109188Y523260D01*
X109731Y522718D01*
G02X109850Y522584I-1133J-1126D01*
G02X110199Y521588I-1249J-997D01*
G01Y520416D01*
G02X109799Y519450I-1366J0D01*
G01X109498Y519149D01*
X109499D01*
G02X109017Y518950I-481J481D01*
G01X101161D01*
G03X97899Y517599I-1J-4612D01*
G01X97500Y517200D01*
G03X96600Y515028I2173J-2173D01*
G02X96227Y514126I-1275J-1D01*
G01X95500Y513400D01*
G01X104695Y525988D02*
G03X107351Y524888I2656J2656D01*
G01X108399D01*
G02X109896Y524368I-1J-2417D01*
G02X110108Y524180I-1495J-1899D01*
G01X110368Y523919D01*
X110649Y523637D01*
X110650D01*
G02X110867Y523394I-2050J-2049D01*
G02X111499Y521587I-2266J-1806D01*
G01Y520417D01*
G02X110718Y518531I-2666J-1D01*
G01Y518530D01*
X110418Y518230D01*
G02X109018Y517650I-1400J1400D01*
G01X101161D01*
G03X98819Y516680I0J-3312D01*
G01X98418Y516279D01*
G03X97901Y515027I1255J-1251D01*
G01X97900Y515028D01*
G03X98344Y513956I1516J0D01*
G01X98900Y513400D01*
G01X159055Y1051142D02*
X162609D01*
X162622Y1051129D01*
G03X163469Y1051480I0J1198D01*
G01X163919Y1051930D01*
G02X164692Y1052250I773J-773D01*
G01X166799D01*
G02X167899Y1051150I0J-1100D01*
G01Y1007504D01*
G02X165979Y1002869I-6555J0D01*
G01X148730Y985620D01*
G03X147299Y982165I3454J-3454D01*
G01Y752036D01*
X147300Y752035D01*
Y745550D01*
G02X145349Y740839I-6663J0D01*
G01X145160Y740649D01*
X145159D01*
X123247Y718738D01*
G03X121191Y714710I5188J-5187D01*
G03X121099Y713551I7244J-1158D01*
G01Y638233D01*
G03X121679Y636830I1983J-1D01*
G01X121780Y636730D01*
G03X123865Y636178I1518J1521D01*
G01X124368D01*
G02X125227Y635822I0J-1214D01*
G01X125499Y635550D01*
G01X159055Y1054291D02*
X162975D01*
X162988Y1054278D01*
G02X163299Y1054149I0J-440D01*
G02X163649Y1053900I-563J-1162D01*
G03X164494Y1053550I845J845D01*
G01X166799D01*
G02X169199Y1051150I0J-2400D01*
G01Y1007503D01*
G02X166899Y1001950I-7855J1D01*
G01X149649Y984700D01*
G03X148599Y982165I2535J-2535D01*
G01Y752575D01*
X148600Y752574D01*
Y745551D01*
G02X146269Y739919I-7964J-2D01*
G01X145699Y739349D01*
X145698D01*
X124167Y717818D01*
G03X122475Y714504I4268J-4268D01*
G03X122399Y713550I5960J-955D01*
G01Y638233D01*
G03X122599Y637750I683J0D01*
G01X122699Y637650D01*
G03X123522Y637432I600J601D01*
G03X124615Y638066I-646J2374D01*
G01X125499Y638950D01*
G01X131688Y658065D02*
X131161Y657539D01*
G02X129499Y656850I-1663J1662D01*
G01X128771D01*
G03X126598Y655950I-1J-3072D01*
G01X126597D01*
G03X125499Y653299I2653J-2652D01*
G01Y652050D01*
G03X126735Y649067I4218J0D01*
G01X126875Y648927D01*
X126874Y648925D01*
X128374Y647425D01*
G02X128591Y647108I-752J-747D01*
G02X128592Y647105I-1005J-337D01*
G02X128643Y646968I-965J-437D01*
G02X128657Y646433I-1019J-294D01*
G02X128374Y645925I-1033J242D01*
G01X127999Y645550D01*
G01X131688Y654565D02*
X131555Y654699D01*
G03X129499Y655550I-2055J-2056D01*
G01X128770D01*
G03X127517Y655031I0J-1772D01*
G03X126799Y653298I1733J-1733D01*
G01Y652051D01*
G03X127655Y649987I2917J0D01*
G01X127795Y649847D01*
X127794Y649846D01*
Y649845D01*
X129931Y647708D01*
X130595Y647045D01*
G02X131400Y645102I-1943J-1943D01*
G01Y644600D01*
G01X159055Y645630D02*
X155463D01*
X155450Y645617D01*
G02X154564Y645984I0J1253D01*
G03X153199Y646550I-1366J-1365D01*
G01X145432D01*
G03X144238Y645356I0J-1194D01*
G01X150591Y629449D02*
X145465D01*
G02X145100Y629600I0J516D01*
G02X144990Y629866I266J266D01*
G01Y630886D01*
G03X144719Y631264I-399J0D01*
G03X144590Y631286I-131J-378D01*
G01X137999D01*
G03X135284Y630162I-1J-3839D01*
G01X135188Y630065D01*
G01X150591Y634449D02*
X146132D01*
G03X145799Y634383I-1J-869D01*
G01X145661Y634326D01*
G03X145142Y633806I369J-887D01*
G01X145032Y633539D01*
G03X144990Y633330I505J-210D01*
G01Y632986D01*
G02X144677Y632595I-401J0D01*
G02X144666Y632592I-111J384D01*
G02X144590Y632586I-69J395D01*
G01X137552D01*
G02X135188Y633565I0J3343D01*
G01X159055Y648779D02*
X155858D01*
X155845Y648766D01*
G03X154599Y648250I0J-1762D01*
G02X153633Y647850I-966J966D01*
G01X145519D01*
G02X144238Y649131I0J1281D01*
G01X159055Y655079D02*
X154996D01*
X154983Y655066D01*
G02X154499Y655550I0J484D01*
G03X154088Y656041I-499J0D01*
G03X153999Y656050I-95J-490D01*
G01X138773D01*
G03X135188Y654565I0J-5070D01*
G01X159055Y658228D02*
X154877D01*
X154864Y658215D01*
G03X154399Y657750I0J-465D01*
G02X154087Y657359I-401J0D01*
G02X153999Y657350I-84J391D01*
G01X136914D01*
G02X135188Y658065I0J2441D01*
G01X103295Y931489D02*
X103685Y931099D01*
G03X105399Y930389I1714J1714D01*
G01X108110D01*
G03X108499Y930550I0J550D01*
G03X108845Y931385I-835J835D01*
G01Y931657D01*
G01X103295Y927989D02*
X103331Y928026D01*
G02X105532Y929070I2567J-2569D01*
G02X105899Y929089I371J-3612D01*
G01X107538D01*
G02X108770Y928578I-1J-1743D01*
G01X109099Y928250D01*
G01X129249Y1063550D02*
X126073Y1060374D01*
G03X124699Y1057057I3317J-3317D01*
G01Y1055740D01*
G02X124583Y1055006I-2390J2D01*
G02X124116Y1054176I-2275J733D01*
G02X123999Y1054050I-1809J1562D01*
G01X129249Y1060050D02*
X128206D01*
G03X126999Y1059550I0J-1707D01*
G03X125999Y1057136I2414J-2414D01*
G01Y1052550D01*
G02X124099Y1050650I-1900J0D01*
G01X123999D01*
G01X159055Y1060591D02*
X155321D01*
X155308Y1060578D01*
G02X154543Y1060895I0J1082D01*
G01X154293Y1061145D01*
G03X153583Y1061439I-710J-710D01*
G01X135399D01*
G03X133247Y1060547I1J-3044D01*
G01X132749Y1060050D01*
G01X150591Y1034961D02*
X145708D01*
G02X144990Y1035680I0J718D01*
G01Y1036398D01*
G03X144718Y1036776I-399J0D01*
G03X144590Y1036798I-131J-378D01*
G01X135762D01*
G03X134835Y1036696I0J-4261D01*
G03X134546Y1036621I925J-4159D01*
G03X132749Y1035550I1216J-4084D01*
G01X150591Y1039961D02*
X145462D01*
G03X145211Y1039858I0J-357D01*
G01X145105Y1039753D01*
G03X144990Y1039482I260J-270D01*
G01Y1038498D01*
G02X144590Y1038098I-400J0D01*
G01X135762D01*
G03X135497Y1038092I-7J-5561D01*
G01X135062D01*
G02X134514Y1038138I-1J3271D01*
G02X134303Y1038171I0J690D01*
G01X134063Y1038248D01*
G02X132749Y1039050I999J3115D01*
G01X159055Y1063740D02*
X155028D01*
X155015Y1063727D01*
G03X154242Y1063407I0J-1093D01*
G01X153892Y1063057D01*
G02X153124Y1062739I-768J768D01*
G01X134707D01*
G02X132749Y1063550I0J2769D01*
G01X132700Y1077600D02*
X132774Y1077675D01*
G02X135250Y1078700I2475J-2476D01*
G01X135650D01*
G02X136825Y1078214I1J-1661D01*
G01X137481Y1077557D01*
G01X132700Y1081100D02*
X132774Y1081025D01*
G03X135250Y1080000I2475J2476D01*
G01X135650D01*
G03X136759Y1080460I-1J1569D01*
G01X137477Y1081177D01*
G01X129200Y1077600D02*
X129019Y1077781D01*
G03X126800Y1078700I-2219J-2219D01*
G03X124752Y1077851I1J-2897D01*
G01X124423Y1077523D01*
G01X129200Y1081100D02*
X129019Y1080919D01*
G02X126800Y1080000I-2219J2219D01*
G02X124752Y1080849I1J2897D01*
G01X124423Y1081177D01*
G01X107578Y1358452D02*
Y1358540D01*
G02X107641Y1358692I214J0D01*
G01X108039Y1359090D01*
G02X109154Y1359552I1115J-1114D01*
G01X110603D01*
G02X112300Y1358849I0J-2400D01*
G01X112440Y1358709D01*
Y1358196D01*
G01X107578Y1361952D02*
X107837D01*
G02X108280Y1361769I1J-626D01*
G01X108647Y1361402D01*
G03X109975Y1360852I1328J1328D01*
G01X111314D01*
G03X112999Y1361550I0J2383D01*
G01X104078Y1336952D02*
X104598Y1336433D01*
G03X105999Y1335852I1402J1401D01*
G01X106999D01*
G03X108690Y1336553I-1J2392D01*
G01X109228Y1337090D01*
G01X104078Y1333452D02*
X104598Y1333971D01*
G02X105999Y1334552I1402J-1401D01*
G01X106999D01*
G02X108693Y1333851I1J-2395D01*
G01X109228Y1333315D01*
G01X109200Y1344600D02*
G02X111373Y1345500I2173J-2173D01*
G01X111500D01*
G02X113207Y1344793I0J-2414D01*
G01X113500Y1344500D01*
G01X109200Y1348100D02*
X109452Y1347849D01*
G03X111500Y1347000I2049J2048D01*
G03X112944Y1347598I0J2042D01*
G01X113500Y1348154D01*
G01X105700Y1344600D02*
X105365Y1344934D01*
G03X104000Y1345500I-1366J-1365D01*
G03X102891Y1345040I1J-1569D01*
G01X102350Y1344500D01*
G01X105700Y1348100D02*
X105378Y1347778D01*
G02X103500Y1347000I-1878J1878D01*
G02X102350Y1348150I0J1150D01*
G01Y1348154D01*
G01X124290Y1469241D02*
X127640D01*
G01Y1465741D02*
X126907Y1466474D01*
G03X125999Y1466850I-908J-908D01*
G01X125794D01*
G03X124297Y1466230I0J-2117D01*
G03X123808Y1465050I1179J-1180D01*
G01X150591Y1425473D02*
X147913D01*
X147900Y1425460D01*
X145424D01*
G02X144499Y1426385I0J925D01*
G03X143574Y1427310I-925J0D01*
G01X119283D01*
G03X117945Y1426756I0J-1893D01*
G01X117390Y1426201D01*
G01X150591Y1430473D02*
X146785D01*
X146772Y1430460D01*
X146732D01*
G03X144499Y1429535I0J-3158D01*
G01X143980Y1429017D01*
G02X142999Y1428610I-982J981D01*
G01X127050D01*
G02X126135Y1429068I-14J1115D01*
G03X125220Y1429525I-900J-658D01*
G01X124095D01*
G03X123180Y1429068I-15J-1115D01*
G02X122265Y1428610I-901J657D01*
G01X119283D01*
G02X117945Y1429164I0J1893D01*
G01X117572Y1429538D01*
G02X117390Y1429976I438J439D01*
G01X127640Y1441241D02*
X127474D01*
G02X127191Y1441358I0J401D01*
G01X126140Y1442409D01*
G03X124799Y1443085I-1696J-1697D01*
G03X124443Y1443112I-359J-2373D01*
G01X106857D01*
G03X105498Y1442549I0J-1922D01*
G01X105413Y1442464D01*
G03X104935Y1441310I1154J-1154D01*
G01Y1440634D01*
G01X159055Y1456654D02*
X154896D01*
X154883Y1456641D01*
G02X154436Y1456826I0J632D01*
G02X153994Y1457146I777J1539D01*
G03X153019Y1457550I-975J-975D01*
G01X145199D01*
G03X143452Y1456827I-1J-2470D01*
G01X142999Y1456373D01*
G01X127640Y1444741D02*
X127475Y1444576D01*
G02X127078Y1444412I-397J399D01*
G01X105902D01*
G02X105264Y1444676I0J903D01*
G01X104999Y1444941D01*
G01X159055Y1466103D02*
X154302D01*
X154289Y1466090D01*
G02X153550Y1466396I0J1045D01*
G03X152056Y1467015I-1494J-1494D01*
G01X134216D01*
G03X131140Y1465741I0J-4350D01*
G01X150591Y1440473D02*
X150578Y1440460D01*
X145924D01*
G02X144999Y1441385I0J925D01*
G03X144334Y1442272I-924J0D01*
G03X144332I-1J-924D01*
G03X144074Y1442310I-262J-886D01*
G01X132965D01*
G03X131674Y1441775I0J-1825D01*
G01X131140Y1441241D01*
G01X159055Y1469252D02*
X154751D01*
X154738Y1469239D01*
G03X153799Y1468850I0J-1328D01*
G02X152507Y1468315I-1292J1292D01*
G01X133376D01*
G02X131140Y1469241I0J3162D01*
G01X159055Y1459803D02*
X155035D01*
X155022Y1459790D01*
G03X154129Y1459420I0J-1263D01*
G01X153879Y1459170D01*
G02X153710Y1459032I-772J773D01*
G02X153106Y1458850I-604J911D01*
G01X145676D01*
G02X142900Y1460000I0J3926D01*
G01X150591Y1445473D02*
X146502D01*
G03X145277Y1445012I0J-1857D01*
G01X145140Y1444874D01*
G03X144999Y1444535I337J-339D01*
G02X144074Y1443610I-925J0D01*
G01X132606D01*
G02X131570Y1444040I1J1466D01*
G01X131236Y1444373D01*
G02X131140Y1444605I232J232D01*
G01Y1444741D01*
G01X105249Y1743050D02*
X105395Y1742905D01*
G03X107699Y1741950I2305J2304D01*
G03X108041Y1742091I1J483D01*
G01X109499Y1743550D01*
G01X105249Y1739550D02*
X105395Y1739695D01*
G02X107699Y1740650I2305J-2304D01*
G02X109079Y1740079I1J-1951D01*
G01X109399Y1739758D01*
Y1739550D01*
G01X128342Y1870754D02*
X128299Y1870798D01*
G03X125999Y1871750I-2299J-2300D01*
G01X124999D01*
G03X123779Y1871244I1J-1726D01*
G01X123393Y1870859D01*
G01X159055Y1862166D02*
X155524D01*
X155511Y1862153D01*
G02X154161Y1862712I0J1909D01*
G03X153280Y1863077I-881J-881D01*
G01X141299D01*
G03X141222Y1863076I15J-4152D01*
G03X138363Y1861861I77J-4152D01*
G01X137999Y1861497D01*
G01X159055Y1865315D02*
X155211D01*
X155198Y1865302D01*
G03X154384Y1864965I0J-1151D01*
G01X154184Y1864765D01*
G02X153247Y1864377I-937J937D01*
G01X141296D01*
G03X141196Y1864376I5J-5452D01*
G03X139560Y1864093I101J-5452D01*
G02X138903Y1864247I-204J608D01*
G01X137999Y1865151D01*
G01X128342Y1874254D02*
X128121Y1874033D01*
G02X125999Y1873154I-2122J2122D01*
G01X125299D01*
G02X124263Y1873583I0J1465D01*
G01X123592Y1874254D01*
G01X150591Y1845985D02*
X145716D01*
G02X145203Y1846197I0J727D01*
G02X144990Y1846711I514J514D01*
G01Y1847422D01*
G03X144590Y1847822I-400J0D01*
G01X135627D01*
G03X131842Y1846254I0J-5353D01*
G01X159055Y1871615D02*
X155277D01*
X155264Y1871602D01*
G02X154335Y1871987I0J1314D01*
G03X153034Y1872526I-1301J-1301D01*
G01X135599D01*
G03X135129Y1872502I9J-4791D01*
G03X132211Y1871122I470J-4768D01*
G01X131842Y1870754D01*
G01X159055Y1874764D02*
X155175D01*
X155162Y1874751D01*
G03X154409Y1874439I0J-1065D01*
G01X154109Y1874139D01*
G02X153353Y1873826I-756J756D01*
G01X132875D01*
G02X131842Y1874254I0J1461D01*
G01X150591Y1850985D02*
X145911D01*
G03X145016Y1850328I-1J-937D01*
G01X144999Y1850275D01*
G03X144990Y1850212I204J-61D01*
G01Y1849522D01*
G02X144709Y1849140I-400J0D01*
G02X144590Y1849122I-119J382D01*
G01X133368D01*
G02X131842Y1849754I0J2158D01*
G01X859228Y224924D02*
X860146D01*
G03X861474Y225474I0J1878D01*
G02X862802Y226024I1328J-1328D01*
G01X872031D01*
G02X872876Y225674I0J-1195D01*
G02X873032Y225484I-556J-616D01*
G01X873075Y225412D01*
G02X873247Y225069I-2287J-1362D01*
G01X873320Y224892D01*
G03X873547Y224553I968J402D01*
G01X873600Y224500D01*
G03X874959Y223937I1359J1359D01*
G01X878937D01*
G01Y228937D02*
X874984D01*
G03X874050Y228550I0J-1321D01*
G01X873410Y227910D01*
G02X872665Y227438I-1416J1411D01*
G02X872624Y227424I-667J1885D01*
G02X872591Y227414I-596J1908D01*
G02X872524Y227394I-605J1906D01*
G02X872240Y227338I-528J1929D01*
G02X872001Y227323I-245J1985D01*
G02X871996Y227324I390J1962D01*
G01X863378D01*
G02X862050Y227874I0J1878D01*
G03X860722Y228424I-1328J-1328D01*
G01X859228D01*
G01X887401Y240118D02*
X883512D01*
X883499Y240105D01*
G02X882761Y240410I-1J1043D01*
G01X882760Y240412D01*
X882325Y240848D01*
G03X881886Y241030I-439J-439D01*
G01X880199D01*
G03X878160Y240186I-1J-2883D01*
G01X878078Y240103D01*
G01X887401Y243267D02*
X883311D01*
X883298Y243254D01*
G03X882900Y243089I0J-563D01*
G01X882381Y242568D01*
G02X881805Y242330I-575J576D01*
G01X880399D01*
X880230Y242334D01*
G02X879192Y242764I0J1468D01*
G01X878078Y243878D01*
G01X855728Y252924D02*
X854841D01*
G03X847878Y250040I0J-9847D01*
G01X855728Y249424D02*
G03X854400Y249974I-1328J-1328D01*
G01X851278D01*
G01X887401Y249567D02*
X883522D01*
X883509Y249554D01*
G02X882826Y249837I0J966D01*
G02X882585Y250036I923J1363D01*
G03X881651Y250423I-934J-934D01*
G01X861640D01*
G03X859228Y249424I0J-3411D01*
G01X887401Y252716D02*
X883612D01*
X883599Y252703D01*
G03X882689Y252326I0J-1287D01*
G01X882501Y252138D01*
G02X881499Y251723I-1002J1002D01*
G01X861999D01*
G02X861850Y251725I-24J3791D01*
G02X859319Y252833I150J3788D01*
G01X859228Y252924D01*
G01X887401Y645630D02*
X884328D01*
X884315Y645617D01*
G02X883149Y646100I0J1649D01*
G01X882849Y646400D01*
G03X882004Y646750I-845J-845D01*
G01X880250D01*
G03X879436Y646413I0J-1151D01*
G01X878596Y645573D01*
G01X878937Y629449D02*
X873574D01*
G02X873443Y629475I-1J340D01*
G01X873376Y629503D01*
G02X872832Y630317I337J814D01*
G01Y630402D01*
G03X872573Y631027I-884J0D01*
G03X871948Y631286I-625J-625D01*
G01X861499D01*
G03X859446Y630382I0J-2783D01*
G01X878937Y634449D02*
X873438D01*
G03X872774Y634174I0J-939D01*
G01X872636Y634036D01*
G03X872499Y633705I331J-331D01*
G01Y633511D01*
G02X872076Y632734I-925J0D01*
G02X872041Y632712I-510J772D01*
G02X871574Y632586I-466J800D01*
G01X861499D01*
G02X859446Y633882I0J2274D01*
G01X855946Y654882D02*
X855261Y655567D01*
G03X854199Y656007I-1062J-1062D01*
G01X852560D01*
G03X851172Y655432I0J-1963D01*
G01X887401Y648779D02*
X883816D01*
X883803Y648766D01*
G03X882799Y648350I0J-1420D01*
G02X882075Y648050I-724J724D01*
G01X880457D01*
G02X880376Y648052I-7J1359D01*
G02X879496Y648448I81J1357D01*
G01X878596Y649348D01*
G01X855946Y658382D02*
X855417Y657853D01*
G02X854099Y657307I-1318J1318D01*
G01X850676D01*
G03X849025Y656623I0J-2335D01*
G01X847772Y655370D01*
G01X887401Y655079D02*
X884622D01*
X884609Y655066D01*
G02X883199Y655650I0J1994D01*
G03X882233Y656050I-966J-966D01*
G01X861899D01*
G03X859706Y655141I1J-3102D01*
G01X859446Y654882D01*
G01X887401Y658228D02*
X884165D01*
X884152Y658215D01*
G03X882880Y657688I0J-1799D01*
G03X882766Y657582I1414J-1635D01*
G02X882534Y657421I-560J560D01*
G02X882206Y657350I-328J721D01*
G01X861899D01*
G02X859473Y658355I0J3431D01*
G01X859446Y658382D01*
G01X887401Y1051142D02*
X884371D01*
X884358Y1051129D01*
G02X883651Y1051422I0J1000D01*
G02X883475Y1051573I896J1223D01*
G03X883048Y1051750I-427J-427D01*
G01X879814D01*
G03X878233Y1051095I0J-2236D01*
G01X887401Y1054291D02*
X884275D01*
X884262Y1054278D01*
G03X883349Y1053900I0J-1291D01*
G01X883149Y1053700D01*
X882748Y1053300D01*
G02X882216Y1053079I-533J532D01*
G02X882017Y1053052I-283J1337D01*
G02X881933Y1053050I-75J1364D01*
G01X880899D01*
G02X878339Y1054111I1J3621D01*
G01X877964Y1054485D01*
G01X878937Y1034961D02*
X878917Y1034941D01*
X875095D01*
G02X873327Y1035673I0J2501D01*
G01X872594Y1036406D01*
G03X871180Y1036992I-1414J-1413D01*
G01X862770D01*
G03X861442Y1036442I0J-1878D01*
G02X860114Y1035892I-1328J1328D01*
G01X859083D01*
G01X878937Y1039961D02*
X874252D01*
X874232Y1039941D01*
G03X872949Y1039410I0J-1815D01*
G01X872417Y1038878D01*
G02X871003Y1038292I-1414J1413D01*
G01X862986D01*
G02X861658Y1038842I0J1878D01*
G03X860330Y1039392I-1328J-1328D01*
G01X859083D01*
G01X855583Y1060892D02*
X855320Y1061155D01*
G03X853299Y1061992I-2021J-2021D01*
G01X851384D01*
G03X850833Y1061441I0J-551D01*
G01X855583Y1064392D02*
X855108Y1063917D01*
G02X853599Y1063292I-1509J1509D01*
G01X850399D01*
G03X848067Y1062326I0J-3298D01*
G01X847233Y1061492D01*
G01X887401Y1060591D02*
X883533D01*
X883520Y1060578D01*
G02X882747Y1060898I0J1093D01*
G01X882447Y1061198D01*
G03X881711Y1061503I-736J-736D01*
G01X860558D01*
G03X859083Y1060892I0J-2086D01*
G01X887401Y1063740D02*
X883732D01*
X883719Y1063727D01*
G03X882604Y1063265I0J-1577D01*
G02X881489Y1062803I-1115J1114D01*
G01X862919D01*
G02X859083Y1064392I0J5425D01*
G01X857077Y1469296D02*
X856994Y1469213D01*
G02X854599Y1468221I-2395J2395D01*
G01X852799D01*
G03X849227Y1466742I-1J-5051D01*
G01X848888Y1466402D01*
G01X857077Y1465796D02*
X856908Y1465964D01*
G03X854599Y1466921I-2310J-2309D01*
G01X853676D01*
G03X852288Y1466346I0J-1963D01*
G01X887401Y1456654D02*
X883489D01*
X883476Y1456641D01*
G02X882778Y1456930I0J987D01*
G03X881243Y1457566I-1535J-1535D01*
G01X879170D01*
G03X878054Y1456450I0J-1116D01*
G01X887401Y1459803D02*
X883612D01*
X883599Y1459790D01*
G03X882689Y1459413I0J-1287D01*
G01X882412Y1459136D01*
G02X881760Y1458866I-652J652D01*
G01X878978D01*
G02X877853Y1459991I0J1125D01*
G01X878937Y1440473D02*
X873730D01*
G02X873213Y1440687I0J732D01*
G02X872999Y1441204I518J517D01*
G01Y1441710D01*
G03X872636Y1442259I-599J-2D01*
G03X872634Y1442261I-394J-392D01*
G03X872399Y1442310I-237J-551D01*
G01X863999D01*
G03X860742Y1440961I0J-4606D01*
G01X860577Y1440796D01*
G01X887401Y1466103D02*
X883523D01*
X883510Y1466090D01*
G02X882752Y1466404I0J1072D01*
G03X881279Y1467014I-1473J-1473D01*
G01X863399D01*
G03X860661Y1465880I0J-3872D01*
G01X860577Y1465796D01*
G01X887401Y1469252D02*
X883828D01*
X883815Y1469239D01*
G03X882538Y1468710I0J-1806D01*
G02X881582Y1468314I-956J956D01*
G01X862899D01*
G02X860612Y1469262I1J3235D01*
G01X860577Y1469296D01*
G01X878937Y1445473D02*
X873513D01*
G03X873150Y1445323I0J-514D01*
G03X872999Y1444958I366J-365D01*
G01Y1444210D01*
G02X872399Y1443610I-600J0D01*
G01X862999D01*
G02X860577Y1444296I0J4619D01*
G01X887401Y1862166D02*
X887388Y1862153D01*
X883499D01*
G02X882684Y1862535I0J1060D01*
G03X882226Y1862803I-1682J-2350D01*
G03X880999Y1863077I-1228J-2616D01*
G01X868151D01*
G03X866914Y1861840I0J-1237D01*
G01X859064Y1871113D02*
X857999D01*
G02X856688Y1871656I0J1854D01*
G01X856396Y1871948D01*
G03X855756Y1872213I-640J-640D01*
G01X854676D01*
G03X853499Y1871036I0J-1177D01*
G01X887401Y1865315D02*
X887388Y1865302D01*
X883399D01*
G03X882757Y1864992I0J-820D01*
G01X882457Y1864692D01*
G02X882406Y1864669I-1477J3208D01*
G02X880999Y1864377I-1406J3240D01*
G01X869099D01*
G02X866914Y1865615I0J2547D01*
G01X859064Y1874613D02*
X857743D01*
G03X856869Y1874251I0J-1236D01*
G01X856578Y1873960D01*
G02X855499Y1873513I-1079J1079D01*
G01X853999D01*
G03X851535Y1872493I-1J-3484D01*
G01X850099Y1871056D01*
G01X887401Y1871615D02*
X887388Y1871602D01*
X883572D01*
G02X882708Y1871960I0J1222D01*
G01X882408Y1872260D01*
G03X881766Y1872526I-642J-642D01*
G01X865975D01*
G03X862564Y1871113I0J-4824D01*
G01X887401Y1874764D02*
X887388Y1874751D01*
X883682D01*
G03X882632Y1874316I0J-1485D01*
G01X882432Y1874116D01*
G02X881732Y1873826I-700J700D01*
G01X863351D01*
G02X862564Y1874613I0J787D01*
G01X878937Y1845985D02*
X873478D01*
G02X873200Y1846100I0J393D01*
G02X872900Y1846824I724J724D01*
G01Y1847200D01*
G03X872278Y1847822I-622J0D01*
G01X865483D01*
G03X862564Y1846613I0J-4128D01*
G01X878937Y1850985D02*
X874013D01*
G03X873650Y1850834I1J-514D01*
G01X873610Y1850794D01*
G03X873499Y1850528I263J-266D01*
G01Y1850047D01*
G02X872756Y1849140I-925J0D01*
G02X872574Y1849122I-182J907D01*
G01X864956D01*
G02X862564Y1850113I0J3383D01*
G54D89*
G01X-71137Y-139897D02*
Y-219897D01*
G01D02*
X1129963D01*
G01X-75137Y-123897D02*
G02I-12000J0D01*
G01X-80287D02*
G02I-6850J0D01*
G01X-87137Y-139897D02*
Y-107897D01*
G01X-71137Y-123897D02*
X-103137D01*
G01X-71137Y-139897D02*
X1129963D01*
G01X-71137Y-175397D02*
X1129963D01*
G01X23499Y381831D02*
X21589Y379921D01*
X12575D01*
X12569Y379915D01*
G01X23399Y389679D02*
X21346Y391732D01*
X12575D01*
X12569Y391726D01*
G01X23499Y397579D02*
X21589Y395669D01*
X12575D01*
X12569Y395663D01*
G01X23499Y436951D02*
X21589Y435041D01*
X12575D01*
X12569Y435035D01*
G01X23399Y429051D02*
X21346Y431104D01*
X12575D01*
X12569Y431098D01*
G01X23399Y460547D02*
X21346Y462600D01*
X12575D01*
X12569Y462594D01*
G01X23499Y452699D02*
X21589Y450789D01*
X12575D01*
X12569Y450783D01*
G01X23399Y444799D02*
X21346Y446852D01*
X12575D01*
X12569Y446846D01*
G01X23399Y476295D02*
X21346Y478348D01*
X12575D01*
X12569Y478342D01*
G01X23499Y468447D02*
X21589Y466537D01*
X12575D01*
X12569Y466531D01*
G01Y407474D02*
X12575Y407480D01*
X22003D01*
G01X23499Y484195D02*
X21589Y482285D01*
X12575D01*
X12569Y482279D01*
G01X23399Y507791D02*
X21346Y509844D01*
X12575D01*
X12569Y509838D01*
G01X23499Y499943D02*
X21589Y498033D01*
X12575D01*
X12569Y498027D01*
G01X23399Y492043D02*
X21346Y494096D01*
X12575D01*
X12569Y494090D01*
G01X23499Y531439D02*
X21589Y529529D01*
X12575D01*
X12569Y529523D01*
G01X23399Y523539D02*
X21346Y525592D01*
X12575D01*
X12569Y525586D01*
G01X23499Y515691D02*
X21589Y513781D01*
X12575D01*
X12569Y513775D01*
G01X22800Y539600D02*
X21060Y541340D01*
X12575D01*
X12569Y541334D01*
G01X22999Y565550D02*
X22411Y564962D01*
X12575D01*
X12569Y564956D01*
G01X22699Y577950D02*
X21522Y576773D01*
X12575D01*
X12569Y576767D01*
G01X23499Y633801D02*
X21589Y631891D01*
X12575D01*
X12569Y631885D01*
G01X23799Y625950D02*
X21795Y627954D01*
X12575D01*
X12569Y627948D01*
G01X23499Y618053D02*
X21589Y616143D01*
X12575D01*
X12569Y616137D01*
G01X23399Y641649D02*
X21346Y643702D01*
X12575D01*
X12569Y643696D01*
G01Y698814D02*
X12575Y698820D01*
X22049D01*
X25986Y694883D01*
G01X23725Y657471D02*
X21746Y659450D01*
X12575D01*
X12569Y659444D01*
G01X23499Y649549D02*
X21589Y647639D01*
X12575D01*
X12569Y647633D01*
G01X23499Y681045D02*
X21589Y679135D01*
X12575D01*
X12569Y679129D01*
G01X23699Y673150D02*
X21651Y675198D01*
X12575D01*
X12569Y675192D01*
G01X23499Y665297D02*
X21589Y663387D01*
X12575D01*
X12569Y663381D01*
G01X23999Y689050D02*
X22103Y690946D01*
X12575D01*
X12569Y690940D01*
G01X25986Y694883D02*
X12575D01*
X12569Y694877D01*
G01X12560Y852381D02*
X22881D01*
X24000Y853500D01*
G01X18500Y1086250D02*
X8750D01*
G01X23499Y1381500D02*
Y1381199D01*
X22221Y1379921D01*
X12575D01*
X12569Y1379915D01*
G01X22999Y1366050D02*
X21122Y1364173D01*
X12575D01*
X12569Y1364167D01*
G01X22851Y1374169D02*
X21036Y1375984D01*
X12575D01*
X12569Y1375978D01*
G01X24499Y1389663D02*
X22430Y1391732D01*
X12575D01*
X12569Y1391726D01*
G01X23999Y1413550D02*
X22193Y1415356D01*
X12575D01*
X12569Y1415350D01*
G01X23499Y1421550D02*
Y1420999D01*
X21793Y1419293D01*
X12575D01*
X12569Y1419287D01*
G01X23999Y1429050D02*
X21945Y1431104D01*
X12575D01*
X12569Y1431098D01*
G01X22999Y1437050D02*
X20990Y1435041D01*
X12575D01*
X12569Y1435035D01*
G01X23499Y1445050D02*
X21697Y1446852D01*
X12575D01*
X12569Y1446846D01*
G01X22999Y1453050D02*
Y1452799D01*
X20989Y1450789D01*
X12575D01*
X12569Y1450783D01*
G01X23499Y1460550D02*
X21350Y1462699D01*
X21251Y1462600D01*
X12575D01*
X12569Y1462594D01*
G01X23028Y1468579D02*
X20986Y1466537D01*
X12575D01*
X12569Y1466531D01*
G01X25247Y1546912D02*
X22945Y1549214D01*
X12575D01*
X12569Y1549208D01*
G01X23277Y1484050D02*
X21512Y1482285D01*
X12575D01*
X12569Y1482279D01*
G01X23599Y1476350D02*
X21601Y1478348D01*
X12575D01*
X12569Y1478342D01*
G01X24499Y1492050D02*
X22453Y1494096D01*
X12575D01*
X12569Y1494090D01*
G01X23799Y1508050D02*
X22005Y1509844D01*
X12575D01*
X12569Y1509838D01*
G01X22999Y1515550D02*
X21230Y1513781D01*
X12575D01*
X12569Y1513775D01*
G01X22999Y1500050D02*
X20982Y1498033D01*
X12575D01*
X12569Y1498027D01*
G01X24423Y1527123D02*
X23600Y1526300D01*
X23121D01*
X22413Y1525592D01*
X12575D01*
X12569Y1525586D01*
G01X24323Y1559950D02*
X23248Y1561025D01*
X12575D01*
X12569Y1561019D01*
G01X23499Y1602050D02*
X21844Y1600395D01*
X12575D01*
X12569Y1600389D01*
G01X23499Y1610050D02*
X21244Y1612305D01*
X21145Y1612206D01*
X12575D01*
X12569Y1612200D01*
G01X23499Y1618050D02*
X21592Y1616143D01*
X12575D01*
X12569Y1616137D01*
G01X23499Y1634050D02*
Y1633399D01*
X21991Y1631891D01*
X12575D01*
X12569Y1631885D01*
G01X22999Y1626050D02*
X21095Y1627954D01*
X12575D01*
X12569Y1627948D01*
G01X23415Y1641634D02*
X21347Y1643702D01*
X12575D01*
X12569Y1643696D01*
G01X23999Y1649550D02*
X22088Y1647639D01*
X12575D01*
X12569Y1647633D01*
G01X23499Y1657050D02*
X21099Y1659450D01*
X12575D01*
X12569Y1659444D01*
G01X22864Y1673550D02*
X21216Y1675198D01*
X12575D01*
X12569Y1675192D01*
G01Y1679129D02*
X12575Y1679135D01*
X21511D01*
X24244Y1681868D01*
G01X22999Y1665550D02*
X20836Y1663387D01*
X12575D01*
X12569Y1663381D01*
G01X24244Y1681868D02*
X23040Y1683072D01*
X12575D01*
X12569Y1683066D01*
G01X12560Y1836633D02*
X22367D01*
G01X5303Y1947050D02*
X11999D01*
X12999Y1948050D01*
X18249D01*
G01X20087Y1972850D02*
X17724D01*
X5303Y1960429D01*
Y1947050D01*
G01X18249Y1952050D02*
X11807D01*
X11703Y1951946D01*
G01X93999Y58550D02*
X91610Y56161D01*
X85650D01*
X85630Y56141D01*
G01X92900Y66128D02*
X92867Y66161D01*
X85650D01*
X85630Y66141D01*
G01X92999Y86128D02*
X92966Y86161D01*
X85650D01*
X85630Y86141D01*
G01X92999Y96128D02*
X92966Y96161D01*
X85650D01*
X85630Y96141D01*
G01X95814Y136065D02*
X95718Y136161D01*
X85650D01*
X85630Y136141D01*
G01X28000Y102250D02*
X15750D01*
G01X96184Y151065D02*
X96088Y151161D01*
X85650D01*
X85630Y151141D01*
G01X59249Y203550D02*
Y201050D01*
X60749Y199550D01*
G01X81249Y204550D02*
X95350D01*
G01X81249Y208550D02*
X89800D01*
G01X46800Y408850D02*
Y406200D01*
X45800Y405200D01*
G01X22003Y407480D02*
X23600Y405883D01*
Y405700D01*
G01X34749Y611550D02*
X37999D01*
G01X34749Y616050D02*
Y619023D01*
X34976Y619250D01*
G01X81251Y611450D02*
Y607249D01*
G01Y615450D02*
Y619251D01*
G01X25986Y694883D02*
X25999Y694870D01*
G01X78499Y654050D02*
X76774Y655775D01*
X74049D01*
G01X56999Y656487D02*
X55936Y657550D01*
X43499D01*
G01X85630Y962165D02*
X85623Y962172D01*
X80602D01*
G03X77499Y962152I4905J-1001719D01*
G01X77166Y925236D02*
Y921883D01*
X77499Y921550D01*
G01X27500Y902750D02*
Y898000D01*
X29000Y896500D01*
G01X83849Y1004450D02*
X80699D01*
G01X83849Y1000450D02*
X80699D01*
G01X59749Y1017050D02*
X59999D01*
X65549Y1011500D01*
X67000D01*
G01X84750Y1008500D02*
X88000D01*
G01X79250Y1013000D02*
X76239D01*
X75500Y1012261D01*
G01X80500Y1097550D02*
X84700D01*
X84750Y1097500D01*
G01Y1104500D02*
X80500D01*
G01X78499Y1273550D02*
X79352Y1272697D01*
X85610D01*
X85630Y1272677D01*
G01X78613Y1282664D02*
X78646Y1282697D01*
X85610D01*
X85630Y1282677D01*
G01X78779Y1302664D02*
X78812Y1302697D01*
X85610D01*
X85630Y1302677D01*
G01X77166Y1349646D02*
Y1353400D01*
G01Y1340197D02*
X77179Y1340184D01*
X82865D01*
X83999Y1339050D01*
X86165D01*
G01X77166Y1330748D02*
Y1327336D01*
X77165Y1327335D01*
G01X78779Y1312664D02*
X78812Y1312697D01*
X85610D01*
X85630Y1312677D01*
G01X93316Y1351000D02*
X91652Y1352664D01*
X85643D01*
X85630Y1352677D01*
G01Y1367677D02*
X94677D01*
X96000Y1369000D01*
G01X34599Y1592100D02*
Y1595300D01*
G01X30499Y1592110D02*
Y1594750D01*
X31099Y1595350D01*
G01X92900Y1678176D02*
X92867Y1678209D01*
X85650D01*
X85630Y1678189D01*
G01X78100Y1688189D02*
X78120Y1688209D01*
X85610D01*
X85630Y1688189D01*
G01X92873Y1708176D02*
X92840Y1708209D01*
X85650D01*
X85630Y1708189D01*
G01X92479Y1718176D02*
X92446Y1718209D01*
X85650D01*
X85630Y1718189D01*
G01X77166Y1755158D02*
Y1759549D01*
X77165Y1759550D01*
G01X60449Y1838725D02*
Y1842550D01*
G01X77249Y1837550D02*
X79999D01*
X80999Y1836550D01*
G01X85999Y1828613D02*
X89287D01*
X90000Y1827900D01*
G01X93500D02*
X93201Y1828199D01*
Y1830099D01*
X90800Y1832500D01*
G01X85999Y1832613D02*
X86112Y1832500D01*
X90800D01*
G01X42600Y1867550D02*
Y1865100D01*
X40500Y1863000D01*
G01X43999Y1968300D02*
Y1968550D01*
X45999Y1970550D01*
Y1971450D01*
G01X18249Y1940050D02*
X14999D01*
G01X18249Y1944050D02*
X15099D01*
G01X44624Y1974886D02*
X43657D01*
X41371Y1972600D01*
X40661D01*
X40411Y1972350D01*
X40299D01*
X37999Y1970050D01*
Y1968750D01*
G01X21749Y1940050D02*
Y1944050D01*
G01X26999Y1941550D02*
X25499Y1940050D01*
X21749D01*
G01X18249Y1936050D02*
X14999D01*
G01X19999Y1968300D02*
X19249D01*
X17299Y1966350D01*
Y1961250D01*
X17499Y1961050D01*
G01X31999Y1968300D02*
Y1972300D01*
G01X23030Y1925188D02*
Y1922038D01*
G01X27999Y1968300D02*
X23999D01*
G01D02*
Y1971301D01*
X22450Y1972850D01*
X20087D01*
G01X21749Y1952050D02*
Y1948050D01*
G01Y1956050D02*
Y1952050D01*
G01X31999Y1922300D02*
X32749Y1921550D01*
X36249D01*
G01X53749Y1901550D02*
X53499Y1901800D01*
X49499D01*
G01D02*
X43249D01*
X42499Y1902550D01*
G01X18249Y1956050D02*
X18549Y1956350D01*
Y1957377D01*
X20422Y1959250D01*
X23076D01*
X23576Y1958750D01*
X23621D01*
X24499Y1957872D01*
Y1957827D01*
X24949Y1957377D01*
Y1956600D01*
X25499Y1956050D01*
G01X52249Y1897050D02*
X48499D01*
G01X27030Y1925188D02*
Y1922835D01*
X26999Y1922804D01*
Y1922179D01*
X26765Y1921945D01*
G01X23030Y1928688D02*
X27030D01*
G01X31999Y1975800D02*
Y1978850D01*
X31799Y1979050D01*
G01X49999Y1972050D02*
X47999Y1974050D01*
X47926D01*
X47090Y1974886D01*
X44624D01*
G01X31999Y1972300D02*
X28249D01*
X26999Y1973550D01*
G01X179376Y82428D02*
X175999D01*
G01X174999Y74800D02*
Y79050D01*
G01X169999Y90550D02*
X170021Y90572D01*
G01D02*
X179422D01*
G01Y86572D02*
X175499D01*
G01X179999Y95050D02*
X179821Y94872D01*
X176399D01*
G01X143110Y203861D02*
X143166Y203917D01*
X150571D01*
X150591Y203937D01*
G01X142688Y218861D02*
X142744Y218917D01*
X150571D01*
X150591Y218937D01*
G01X176749Y165050D02*
Y165300D01*
X175949Y166100D01*
X173715D01*
X173500Y166315D01*
G01X154749Y165050D02*
X154200Y165599D01*
Y168500D01*
G01X154749Y161050D02*
X151450D01*
X149400Y163100D01*
Y166400D01*
G01X150591Y313937D02*
X150607Y313921D01*
X155600D01*
G03X157440Y313924I-4543J3350629D01*
G01X150591Y303937D02*
X150607Y303921D01*
X155600D01*
G03X157440Y303924I-4543J3350629D01*
G01X159055Y255866D02*
X158999Y255922D01*
Y259800D01*
G01X157440Y283924D02*
X157433Y283917D01*
X150611D01*
X150591Y283937D01*
G01X166850Y420300D02*
X166750Y420200D01*
Y417750D01*
X165500Y416500D01*
G01X154101Y445550D02*
X158299Y441352D01*
Y438173D01*
G01X166500Y428500D02*
X165699Y429301D01*
Y433053D01*
G01X167199Y517100D02*
X163549D01*
G01X151749Y517613D02*
Y520249D01*
X152000Y520500D01*
Y520813D01*
G01X171722Y513827D02*
X171864D01*
X172999Y514962D01*
Y515900D01*
X174199Y517100D01*
G01X163549D02*
X159199D01*
G01X174199D02*
X175137D01*
X178449Y520412D01*
Y524850D01*
G01D02*
Y529000D01*
X174099Y533350D01*
G01X147250Y545000D02*
X150500D01*
G01X163449Y524850D02*
Y521650D01*
G01X170949Y524850D02*
Y525453D01*
X168453Y527949D01*
G01X154249Y570050D02*
Y571149D01*
X156951Y573851D01*
X157000D01*
G01X154249Y566050D02*
X153722D01*
X151049Y568723D01*
Y572475D01*
X155625Y577051D01*
X160500D01*
X160551Y577000D01*
X160824D01*
G01X159055Y661378D02*
Y665399D01*
X159054Y665400D01*
G01X158385Y719436D02*
X158378Y719429D01*
X150611D01*
X150591Y719449D01*
G01X141500Y711000D02*
X143071Y709429D01*
X150571D01*
X150591Y709449D01*
G01X158885Y689436D02*
X158878Y689429D01*
X150611D01*
X150591Y689449D01*
G01X159500Y818250D02*
Y814700D01*
G01X174749Y916113D02*
Y917045D01*
X172500Y919294D01*
G01X109000Y967901D02*
X108949Y967850D01*
G01X109000Y972000D02*
Y967901D01*
G01X108200Y963600D02*
X109000Y964400D01*
Y967901D01*
G01X180350Y931600D02*
X172000D01*
G01X161999Y919363D02*
Y921250D01*
X160399Y922850D01*
G01X154749Y975550D02*
Y979149D01*
G01Y971550D02*
Y968249D01*
G01X159055Y1047992D02*
Y1045023D01*
X159499Y1044579D01*
G01X159055Y1057441D02*
X159068Y1057428D01*
X165600D01*
G01X150591Y1014961D02*
X158261D01*
X158300Y1015000D01*
G01X141234Y1029885D02*
X141290Y1029941D01*
X150571D01*
X150591Y1029961D01*
G01X140864Y1044885D02*
X140920Y1044941D01*
X150571D01*
X150591Y1044961D01*
G01X109439Y1085800D02*
X105999D01*
G01X97849Y1077400D02*
Y1076200D01*
X101499Y1072550D01*
G01X97849Y1081700D02*
Y1077400D01*
G01X128230Y1094482D02*
Y1093730D01*
X125900Y1091400D01*
Y1091282D01*
G01X128230Y1098482D02*
X130067D01*
X132499Y1096050D01*
Y1094550D01*
G01X116249Y1099110D02*
Y1102550D01*
G01X114559Y1079300D02*
X117499D01*
G01X159055Y1066890D02*
Y1070400D01*
G01X122750Y1113500D02*
X127000D01*
G01X112999Y1103740D02*
Y1104050D01*
X113499Y1104550D01*
Y1106640D01*
G01X109499Y1198363D02*
Y1197050D01*
X106999Y1194550D01*
G01X105499Y1198363D02*
X103186Y1196050D01*
X102900D01*
G01X106999Y1223863D02*
X103686D01*
G01X106939Y1216863D02*
X103999D01*
G01X131250Y1202000D02*
X127000D01*
G01X148000Y1206000D02*
X143250D01*
G01D02*
Y1202000D01*
G01X111999Y1182550D02*
Y1188050D01*
G01X112059Y1210363D02*
X114999D01*
G01X130699Y1213553D02*
Y1210653D01*
G01X102999Y1182550D02*
Y1188050D01*
G01X120999Y1182550D02*
Y1188050D01*
G01X118999Y1219050D02*
X122922D01*
X123299Y1218673D01*
G01X103499Y1301363D02*
Y1305050D01*
G01X116499Y1324863D02*
Y1328013D01*
G01X120507Y1324946D02*
Y1328096D01*
G01X142150Y1335800D02*
X143700Y1334250D01*
Y1332500D01*
G01X114939Y1311800D02*
X111499D01*
G01X133475Y1326750D02*
Y1331200D01*
G01X119749Y1356050D02*
Y1358349D01*
X121700Y1360300D01*
X123500D01*
G01X131750Y1361000D02*
Y1358750D01*
X129500Y1356500D01*
X129000D01*
G01X128250Y1365000D02*
X126100D01*
X125100Y1366000D01*
G01X115599Y1468500D02*
Y1463050D01*
X106999Y1454450D01*
G01X111499Y1468550D02*
X115549D01*
X115599Y1468500D01*
G01X103999Y1468550D02*
X102250D01*
X100699Y1470101D01*
Y1471050D01*
G01X105099Y1459150D02*
X107999Y1462050D01*
Y1476050D01*
G01X98599Y1491350D02*
X100299Y1493050D01*
X119199D01*
X122799Y1489450D01*
Y1485300D01*
G01D02*
X118549D01*
G01X105749Y1720613D02*
Y1716613D01*
G01X117499Y1702613D02*
Y1706050D01*
G01X131999Y1703300D02*
X128749D01*
G01X135999D02*
Y1702725D01*
X133233Y1699959D01*
X133090D01*
G01X174250Y1691200D02*
Y1694500D01*
G01X104999Y1705613D02*
Y1708963D01*
G01X165575Y1682050D02*
Y1676975D01*
G01X151499Y1660887D02*
Y1673550D01*
G01X177314Y1786613D02*
Y1787865D01*
X186499Y1797050D01*
X297499D01*
G01X154721Y1786909D02*
Y1787897D01*
X157024Y1790200D01*
X165600D01*
X165900Y1790500D01*
G01X154721Y1782909D02*
X153191D01*
X151521Y1784579D01*
Y1789223D01*
X155698Y1793400D01*
X161900D01*
G01X150591Y1935985D02*
X159160D01*
X159173Y1935972D01*
G01X159421Y1925972D02*
X159414Y1925965D01*
X150611D01*
X150591Y1925985D01*
G01X142499Y1905972D02*
X142506Y1905965D01*
X150571D01*
X150591Y1905985D01*
G01X141506Y1895965D02*
X141499Y1895972D01*
G01D02*
X141512Y1895985D01*
X150591D01*
G01X201499Y101300D02*
Y104550D01*
G01X246499Y80550D02*
X242699D01*
X240999Y82250D01*
G01X246499Y86050D02*
X242699Y82250D01*
X240999D01*
G01X235499Y81300D02*
X240049D01*
X240999Y82250D01*
G01X213499Y101300D02*
Y104650D01*
G01X183249Y99050D02*
X186999D01*
G01X185499Y120800D02*
X188999D01*
G01X217499Y101300D02*
X219249D01*
X223499Y105550D01*
Y108150D01*
G01X241749Y95550D02*
X245399D01*
X248699Y98850D01*
Y104350D01*
X236786Y116263D01*
X199436D01*
X194299Y111126D01*
Y99973D01*
X196472Y97800D01*
X197499D01*
G01X205499Y101300D02*
Y105550D01*
G01X242499Y76550D02*
X247614D01*
X250114Y79050D01*
Y88435D01*
X248699Y89850D01*
X240999D01*
G01X233749Y110800D02*
X231486Y113063D01*
X200762D01*
X197499Y109800D01*
Y101300D01*
G01X233749Y105050D02*
Y110800D01*
G01Y101050D02*
X236399D01*
X237399Y102050D01*
G01X233749Y97050D02*
Y101050D01*
G01X237399Y102050D02*
Y106550D01*
X237899Y107050D01*
G01X209499Y101300D02*
Y108050D01*
X207999Y109550D01*
G01X178999Y74800D02*
Y79050D01*
G01X182499Y74800D02*
X185589D01*
X187024Y76235D01*
G01X182876Y82428D02*
X185299Y80005D01*
Y78431D01*
X187024Y76706D01*
Y76235D01*
G01X182922Y90572D02*
Y86572D01*
G01X193549Y165075D02*
X197899D01*
G01X327499Y320050D02*
Y304550D01*
X310063Y287114D01*
X242000D01*
G01D02*
X229748D01*
G01X244050Y269700D02*
X247800D01*
G01X216998Y283864D02*
X213499D01*
G01X246498Y319114D02*
X252935D01*
G01X218998Y318114D02*
X214063D01*
G01X225900Y318400D02*
X225914Y318414D01*
X231800D01*
G01X184000Y433500D02*
Y424250D01*
G01X188000D02*
X184000D01*
G01X183000Y434500D02*
X184000Y433500D01*
G01X193549Y572275D02*
Y575875D01*
G01X229749Y693550D02*
X232548D01*
X232550Y693552D01*
X236450D01*
X236452Y693550D01*
X241400D01*
G01X324999Y727550D02*
Y712050D01*
X306499Y693550D01*
X241400D01*
G01X243450Y677100D02*
X246800D01*
G01X216999Y690300D02*
Y686550D01*
G01X218499Y725050D02*
X213999D01*
G01X246499Y726050D02*
X252499D01*
G01X225499D02*
X230849D01*
G01X227025Y683750D02*
Y678176D01*
X226399Y677550D01*
G01X238500Y680800D02*
X238800D01*
X240500Y682500D01*
X241440D01*
G01X218224Y765325D02*
X221299Y762250D01*
Y760550D01*
G01X211500Y822750D02*
X207500D01*
G01D02*
Y833000D01*
G01X191499Y884113D02*
X198499D01*
G01X215050Y896950D02*
X215900D01*
G01X209999Y901763D02*
X210871D01*
X212599Y900035D01*
Y899401D01*
X215050Y896950D01*
G01X205999Y901763D02*
X209999D01*
G01X193549Y975975D02*
X198924D01*
G01X226800Y1090050D02*
Y1093400D01*
G01X247500Y1082000D02*
Y1085500D01*
G01X208049Y1380675D02*
Y1385550D01*
G01X191249Y1381050D02*
Y1382749D01*
X194200Y1385700D01*
X194700D01*
G01X184600Y1373050D02*
Y1369100D01*
X181000Y1365500D01*
G01X180500Y1373050D02*
Y1369900D01*
G01X259000Y1530100D02*
Y1534000D01*
G01X225499Y1502800D02*
X249400D01*
X251000Y1504400D01*
G01X325499Y1538550D02*
Y1511300D01*
X317499Y1503300D01*
X267100D01*
X263500Y1506900D01*
X253500D01*
X251000Y1504400D01*
G01X224750Y1480100D02*
Y1483950D01*
G01X228825Y1493450D02*
X232650D01*
G01X198750Y1645500D02*
X195000D01*
G01X194049Y1786375D02*
Y1792600D01*
G01X231000Y1883950D02*
Y1886300D01*
X231800Y1887100D01*
G01X236225Y1887950D02*
Y1883125D01*
G01X223436Y1893615D02*
Y1890465D01*
G01X232314Y1893863D02*
Y1890513D01*
G01X342463Y-139897D02*
Y-219897D01*
G01X334249Y63050D02*
Y67050D01*
G01X352999Y70050D02*
X336377D01*
X334249Y67922D01*
Y67050D01*
G01X305749Y86613D02*
X306621D01*
X307058Y87050D01*
X308999D01*
G01X319650Y105200D02*
X323400D01*
G01X328999Y321550D02*
X327499Y320050D01*
G01X280499Y345300D02*
X284999D01*
G01X287664Y328715D02*
Y343885D01*
X286249Y345300D01*
X284999D01*
G01X307000Y370250D02*
Y366000D01*
G01X311000Y370250D02*
X307000D01*
G01X295500Y332750D02*
X295750Y333000D01*
X298800D01*
G01X325499Y728050D02*
X324999Y727550D01*
G01X334749Y737800D02*
Y741050D01*
G01D02*
Y745050D01*
G01X281499Y751800D02*
X285499D01*
G01X288999Y733550D02*
X289799Y734350D01*
G01D02*
Y750750D01*
X288749Y751800D01*
X285499D01*
G01X323249Y746110D02*
Y749010D01*
G01X322059Y766750D02*
X324959D01*
G01X279939Y740300D02*
X277039D01*
G01X298000Y739250D02*
Y743500D01*
G01X311000Y754750D02*
X314750D01*
X315000Y754500D01*
G01X331249Y1549300D02*
X328999Y1547050D01*
X327999D01*
G01X331249Y1553550D02*
Y1549300D01*
G01Y1553550D02*
Y1557550D01*
G01X286799Y1546350D02*
Y1561750D01*
X285749Y1562800D01*
X282499D01*
G01X278499D02*
X282499D01*
G01X318250Y1587000D02*
X325000D01*
X333000Y1579000D01*
Y1578000D01*
G01X321059Y1577250D02*
X323999D01*
G01X334999Y1797050D02*
X297499D01*
G01X710549Y1797884D02*
Y1785449D01*
X705500Y1780400D01*
X535864D01*
X521494Y1766030D01*
X326301D01*
G01X284358Y1955078D02*
X288358D01*
G01X292999Y1945550D02*
X291886Y1946663D01*
Y1953663D01*
X290471Y1955078D01*
X288358D01*
G01X339471Y1947409D02*
X342999D01*
G01X339471Y1943409D02*
X342621D01*
G01X330000Y1969750D02*
Y1967000D01*
X330500Y1966500D01*
G01X296858Y1956228D02*
Y1947578D01*
G01X375249Y53050D02*
Y57050D01*
G01X363000Y42750D02*
X367000D01*
G01X369500Y32000D02*
X367000Y34500D01*
Y42750D01*
G01X479963Y-139897D02*
Y-219897D01*
G01X644049Y1792884D02*
Y1788888D01*
X639799Y1784638D01*
X544300D01*
G01X594963Y-139897D02*
Y-219897D01*
G01X660519Y1806887D02*
X659949Y1806317D01*
Y1803670D01*
G01X651799Y1803634D02*
X655299D01*
X655549Y1803884D01*
G01D02*
X655763Y1803670D01*
X659949D01*
G01X669001Y1801888D02*
X664549Y1797436D01*
G01X651799Y1796134D02*
X655299D01*
X655549Y1796384D01*
G01D02*
X663497D01*
X664549Y1797436D01*
G01X644049Y1803884D02*
X640049D01*
G01X648299Y1803634D02*
X648049Y1803884D01*
X644049D01*
G01X640049D02*
X638799D01*
X637965Y1803050D01*
X634999D01*
G01X644049Y1796384D02*
X640049D01*
G01X648299Y1796134D02*
X644299D01*
X644049Y1796384D01*
G01X640049D02*
X634850D01*
X633931Y1795465D01*
G01X649049Y1814384D02*
X646799D01*
X646049Y1815134D01*
X645549D01*
G01X647799Y1818634D02*
X647296Y1819137D01*
X644360D01*
G01X640049Y1807384D02*
X633837D01*
G01X749500Y351750D02*
Y356000D01*
X748000Y357500D01*
G01X753750Y351500D02*
X750580D01*
X750330Y351750D01*
X749500D01*
G01X751499Y679148D02*
X754401Y682050D01*
X820600D01*
G01X750500Y751250D02*
Y755000D01*
X750000Y755500D01*
G01X754750Y751000D02*
X750750D01*
X750500Y751250D01*
G01X757499Y1079550D02*
X811623D01*
X814073Y1082000D01*
X814600D01*
X816000Y1083400D01*
G01X747500Y1155250D02*
X747000Y1155750D01*
Y1159000D01*
G01X751750Y1154500D02*
X748250D01*
X747500Y1155250D01*
G01X757999Y1484050D02*
X802550D01*
X809400Y1490900D01*
X822100D01*
G01X751000Y1557250D02*
Y1559500D01*
X750000Y1560500D01*
G01X755250Y1556500D02*
X751750D01*
X751000Y1557250D01*
G01X736299Y1798634D02*
X733149D01*
G01X753949Y1801294D02*
Y1798194D01*
G01X682549Y1803634D02*
Y1802134D01*
X685549Y1799134D01*
G01X697299Y1801634D02*
X697049Y1801884D01*
X693549D01*
G01D02*
X693249Y1801584D01*
X692222D01*
X689772Y1799134D01*
X685549D01*
G01X710549Y1801384D02*
X713799D01*
X715549Y1799634D01*
G01X706549Y1801384D02*
X710549D01*
G01X700799Y1801634D02*
X706299D01*
X706549Y1801384D01*
G01X717564Y1804045D02*
X716676Y1804933D01*
X699973D01*
X697299Y1807607D01*
Y1808634D01*
G01X707600Y1815600D02*
X705000D01*
X704400Y1816200D01*
X699300D01*
X697799Y1814699D01*
Y1813134D01*
G01D02*
X697549Y1813384D01*
X693549D01*
G01D02*
X689299D01*
X688499Y1812584D01*
X688473D01*
X687536Y1811647D01*
G01X736299Y1814134D02*
X733049D01*
G01X736299Y1806634D02*
X732549D01*
G01X712549Y1812084D02*
X716700D01*
X717000Y1812384D01*
G01X708549Y1808584D02*
X712549D01*
G01X700799Y1808634D02*
X708499D01*
X708549Y1808584D01*
G01X712549D02*
X720000D01*
X720300Y1808884D01*
G01X697299Y1808634D02*
X696549Y1809384D01*
X693549D01*
G01D02*
X690451D01*
X689731Y1808664D01*
G01X749500Y1961750D02*
Y1965000D01*
X750000Y1965500D01*
G01X753750Y1961000D02*
X750250D01*
X749500Y1961750D01*
G01X762463Y-139897D02*
Y-219897D01*
G01X835749Y160300D02*
Y167550D01*
G01X835999Y160050D02*
X835749Y160300D01*
G01X792999Y315550D02*
X796499D01*
X800749Y319800D01*
Y332050D01*
G01X827500Y270950D02*
Y274500D01*
G01X800749Y336050D02*
Y332050D01*
G01X758778Y341984D02*
Y345000D01*
G01X767728Y328984D02*
Y333514D01*
X768178Y333964D01*
G01D02*
X767722D01*
X766178Y335508D01*
Y336864D01*
G01X844446Y681882D02*
X844278Y682050D01*
X820600D01*
G01X795499Y719050D02*
X799249Y722800D01*
Y732050D01*
G01X826100Y666650D02*
X829800D01*
G01X799249Y736050D02*
Y732050D01*
G01X844083Y1087392D02*
X819992D01*
X816000Y1083400D01*
G01X792999Y1116050D02*
Y1124550D01*
X799249Y1130800D01*
Y1133050D01*
G01D02*
Y1137050D01*
G01X825700Y1079250D02*
Y1083100D01*
G01X816000Y1090750D02*
Y1089000D01*
X814000Y1087000D01*
G01X815400Y1078800D02*
Y1078400D01*
X812900Y1075900D01*
Y1075460D01*
G01X846077Y1492296D02*
X844681Y1490900D01*
X822100D01*
G01X793499Y1525050D02*
X796931D01*
X801931Y1530050D01*
Y1538893D01*
G01D02*
Y1542893D01*
G01X827700Y1484150D02*
Y1487600D01*
G01X787693Y1535628D02*
X784577D01*
G01X833025Y1486550D02*
X835775D01*
X836625Y1487400D01*
G01X816000Y1494250D02*
X812750D01*
X812550Y1494050D01*
G01X837499Y1780050D02*
Y1785773D01*
X836249Y1787023D01*
Y1788050D01*
G01X783049Y1813634D02*
X779149D01*
X776149Y1810634D01*
Y1808974D01*
G01X828000Y1881250D02*
X828500Y1880750D01*
Y1877800D01*
G01X800431Y1948393D02*
Y1949482D01*
X802499Y1951550D01*
G01X800431Y1944393D02*
Y1941193D01*
G01X846564Y1898113D02*
X845551Y1897100D01*
X819486D01*
X817386Y1895000D01*
G01X758499Y1893550D02*
X759949Y1895000D01*
X817386D01*
G01X815500Y1900750D02*
X814750D01*
X812500Y1898500D01*
G01X916499Y111800D02*
Y115050D01*
G01X903499Y131800D02*
X907499D01*
G01X902249Y103050D02*
X894999D01*
G01X912499Y111800D02*
Y115550D01*
X922499Y125550D01*
X934499D01*
X937999Y122050D01*
G01X920499Y111800D02*
Y118050D01*
X924499Y122050D01*
X926999D01*
G01X920499Y108300D02*
Y103550D01*
X920999Y103050D01*
G01X916499Y108300D02*
X920499D01*
G01X902249Y107050D02*
X902499Y107300D01*
Y110550D01*
G01X924499Y111800D02*
X923999Y112300D01*
Y116550D01*
X926199Y118750D01*
X934499D01*
G01X900499Y115050D02*
X898999Y113550D01*
Y110550D01*
G01X900499Y88300D02*
X899749D01*
X897555Y90494D01*
G01X907249Y124550D02*
X910999D01*
G01X905749Y107050D02*
Y103050D01*
G01X878937Y218937D02*
X871799D01*
X871786Y218924D01*
G01X916499Y172550D02*
X922249D01*
G01X871478Y163924D02*
X867500D01*
G01X871478Y159924D02*
X867576D01*
G01X845728Y280924D02*
X842499D01*
G01X922049Y570775D02*
Y574375D01*
G01X870773Y624705D02*
X871049Y624429D01*
X878917D01*
X878937Y624449D01*
G01X905196Y570882D02*
Y572156D01*
X903999Y573353D01*
Y574378D01*
G01X883249Y570550D02*
X879750D01*
G01X883249Y565050D02*
X879950D01*
G01X905083Y974392D02*
Y974966D01*
X900999Y979050D01*
G01X883083Y975892D02*
Y979183D01*
G01Y971892D02*
X879708D01*
G01X870468Y1030227D02*
X870754Y1029941D01*
X878917D01*
X878937Y1029961D01*
G01X873249Y1359550D02*
Y1356800D01*
X873499Y1356550D01*
Y1356050D01*
G01X870077Y1379796D02*
X866700D01*
G01X870077Y1375796D02*
X866596D01*
G01X871836Y1435460D02*
X871843Y1435453D01*
X878917D01*
X878937Y1435473D01*
G01X895500Y1721500D02*
X900500D01*
G01X871100Y1690300D02*
Y1692100D01*
X876000Y1697000D01*
Y1703899D01*
G01X870201Y1709900D02*
Y1706899D01*
X873201Y1703899D01*
X876000D01*
G01X896400Y1716200D02*
X899000D01*
X899200Y1716000D01*
X901500D01*
G01X894800Y1710000D02*
X895800Y1711000D01*
Y1715600D01*
X896400Y1716200D01*
G01X864000Y1738000D02*
X876000Y1750000D01*
X893500D01*
X904000Y1739500D01*
Y1718500D01*
X901500Y1716000D01*
G01X889700Y1708150D02*
X889800Y1708250D01*
Y1711500D01*
G01D02*
Y1715600D01*
X890400Y1716200D01*
G01X921549Y1784875D02*
Y1788475D01*
G01X904814Y1785613D02*
Y1789113D01*
G01X879700Y1786300D02*
X882850D01*
G01X864000Y1736500D02*
Y1738000D01*
G01X882814Y1782213D02*
X879664D01*
G01X871836Y1840972D02*
X871843Y1840965D01*
X878917D01*
X878937Y1840985D01*
G01X932463Y-139897D02*
Y-219897D01*
G01X946899Y122550D02*
Y119750D01*
X946999Y119650D01*
G01X932499Y111800D02*
Y113524D01*
X932298Y113725D01*
Y114772D01*
X931520Y115550D01*
X930999D01*
G01X936499Y111800D02*
Y114550D01*
X937499Y115550D01*
X938499D01*
G01X952499Y111800D02*
X954499Y113800D01*
Y116550D01*
G01X948499Y111800D02*
X952499D01*
G01X944499D02*
Y112950D01*
X946999Y115450D01*
G01X940499Y111800D02*
X944499D01*
G01X934499Y118750D02*
X941077D01*
X944377Y115450D01*
X946999D01*
G01X928499Y108300D02*
X924499D01*
G01X932499D02*
X928499D01*
G01Y111800D02*
Y113550D01*
X926999Y115050D01*
G01X939549Y171575D02*
Y175175D01*
G01X990425Y1633898D02*
Y1633575D01*
X992898Y1631102D01*
X1005807D01*
G01X987029Y1634075D02*
X987000Y1634046D01*
Y1630900D01*
X991798Y1626102D01*
X1005807D01*
G01X987200Y1675600D02*
X992300D01*
X992802Y1676102D01*
X1005807D01*
G01X989502Y1646000D02*
X992000D01*
X992102Y1646102D01*
X1005807D01*
G01X1129963Y-139897D02*
Y-219897D01*
G01X1157963Y-123897D02*
G02I-12000J0D01*
G01X1152813D02*
G02I-6850J0D01*
G01X1145963Y-139897D02*
Y-107897D01*
G01X1161963Y-123897D02*
X1129963D01*
G54D99*
G01X102999Y29050D02*
X103640Y29691D01*
G03X104700Y32249I-2558J2559D01*
G01Y51606D01*
G03X95165Y61141I-9535J0D01*
G01X85630D01*
G01X97499Y90050D02*
X96388Y91161D01*
X85650D01*
X85630Y91141D01*
G01X77749Y204550D02*
X75880Y206419D01*
X71785D01*
X71773Y206431D01*
G01D02*
X70118D01*
X68900Y207649D01*
Y216611D01*
X69510Y217221D01*
G01X66023Y206431D02*
X66011Y206419D01*
X61380D01*
X60374Y207425D01*
X59374D01*
X59249Y207550D01*
G01D02*
Y208300D01*
X61499Y210550D01*
Y216157D01*
X61757Y216415D01*
G01X49949Y207900D02*
X50299Y207550D01*
X55749D01*
G01D02*
Y203550D01*
G01D02*
Y201800D01*
X52499Y198550D01*
G01X59249Y211550D02*
Y213300D01*
X56999Y215550D01*
Y217050D01*
G01X66023Y209631D02*
X66022Y209632D01*
Y213027D01*
X63857Y215191D01*
Y215518D01*
X63876Y215537D01*
Y217293D01*
X62635Y218534D01*
X57983D01*
X56999Y217550D01*
Y217050D01*
G01X77749Y213500D02*
Y208550D01*
G01X71773Y209631D02*
X75642Y213500D01*
X77749D01*
G01X55749Y211550D02*
Y213200D01*
X51849Y217100D01*
G01X65999Y216050D02*
Y217406D01*
X65514Y217891D01*
Y217972D01*
X63314Y220172D01*
X53021D01*
X51849Y219000D01*
Y217100D01*
G01X42449Y211775D02*
X41499Y212725D01*
Y219050D01*
G01X48349Y217100D02*
X46399Y219050D01*
X41499D01*
G01X38999Y372160D02*
X38886Y372047D01*
X12575D01*
X12569Y372041D01*
G01X28100Y374000D02*
X26116Y375984D01*
X12575D01*
X12569Y375978D01*
G01X100999Y468550D02*
G02X99102Y466653I-1897J0D01*
G01X85630D01*
G01X52730Y406470D02*
X52400Y406800D01*
Y409900D01*
X49950Y412350D01*
X46800D01*
G01X35900Y412600D02*
X34717Y411417D01*
X12575D01*
X12569Y411411D01*
G01X42700Y412350D02*
X36150D01*
X35900Y412600D01*
G01X46800Y412350D02*
X42700D01*
G01X43099Y555850D02*
Y555550D01*
X40449Y552900D01*
X28749D01*
X28498Y553151D01*
X12575D01*
X12569Y553145D01*
G01X33699Y561850D02*
X32874Y561025D01*
X12575D01*
X12569Y561019D01*
G01X46299Y552950D02*
X43699D01*
X39963Y549214D01*
X12575D01*
X12569Y549208D01*
G01X29999Y557150D02*
X29937Y557088D01*
X12575D01*
X12569Y557082D01*
G01X107499Y497050D02*
X107122Y496673D01*
X85650D01*
X85630Y496653D01*
G01X65599Y514250D02*
Y539901D01*
X61750Y543750D01*
X23399D01*
X21872Y545277D01*
X12575D01*
X12569Y545271D01*
G01X60400Y616000D02*
Y613500D01*
X61537Y612364D01*
X61756Y612218D01*
X63504Y610470D01*
Y610445D01*
X63925Y610024D01*
X63950D01*
X64101Y609873D01*
X69373D01*
X71443Y611943D01*
X71773D01*
G01X77751Y611450D02*
X77258Y611943D01*
X71773D01*
G01X66023D02*
X65157D01*
X62519Y614581D01*
Y616878D01*
X62500Y616897D01*
Y633300D01*
G01X56999Y652487D02*
X55487D01*
X53500Y650500D01*
Y646500D01*
X62500Y637500D01*
Y633300D01*
G01X38850Y603200D02*
Y603940D01*
X42202Y607292D01*
Y608195D01*
G01X39600Y626984D02*
Y625900D01*
X49526Y615974D01*
Y600626D01*
X44100Y595200D01*
X37750D01*
X35550Y597400D01*
G01X38850Y607326D02*
Y608350D01*
X41400Y610900D01*
Y611500D01*
G01X35550Y593300D02*
X44900D01*
X51426Y599826D01*
Y616890D01*
X42709Y625607D01*
G01X38300Y633800D02*
X34700Y630200D01*
Y623000D01*
G01D02*
X29480Y617780D01*
Y611607D01*
X25304Y607431D01*
X13413D01*
X12575Y608269D01*
X12569Y608263D01*
G01X44950Y639600D02*
X44452Y639102D01*
X41367D01*
G01X41500Y642800D02*
X41367Y642667D01*
Y639102D01*
G01X48450Y635500D02*
X53400Y630550D01*
Y630500D01*
G01D02*
Y619397D01*
X53381Y619378D01*
Y618698D01*
X53362Y618679D01*
Y599062D01*
X45550Y591250D01*
X27604D01*
X26844Y592010D01*
X26790D01*
X26279Y592521D01*
X12575D01*
X12569Y592515D01*
G01X28000Y578500D02*
X25790Y580710D01*
X12575D01*
X12569Y580704D01*
G01X43150Y597400D02*
X47626Y601876D01*
Y611300D01*
G01X42900Y604850D02*
Y604899D01*
X45701Y607700D01*
G01X66023Y615143D02*
Y638100D01*
G01X56999Y648487D02*
X66023Y639463D01*
Y638100D01*
G01X71800Y622700D02*
X71773Y622673D01*
Y615143D01*
G01X77751Y615450D02*
X77444Y615143D01*
X71773D01*
G01X79249Y642550D02*
X81499Y640300D01*
Y627800D01*
X82249Y627050D01*
X82499D01*
G01X60499Y648487D02*
X68687D01*
X71000Y650800D01*
X76249D01*
X79249Y647800D01*
Y642550D01*
G01X57400Y610900D02*
Y592000D01*
X50047Y584647D01*
X12575D01*
X12569Y584641D01*
G01X74049Y648025D02*
Y644250D01*
X75749Y642550D01*
G01D02*
Y638300D01*
X76499Y637550D01*
G01X26800Y611500D02*
X26094Y612206D01*
X12575D01*
X12569Y612200D01*
G01X41500Y635000D02*
X42000Y635500D01*
X44950D01*
G01D02*
Y632950D01*
X43500Y631500D01*
G01X55500Y618500D02*
X55000Y618000D01*
Y597815D01*
X45885Y588700D01*
X27837D01*
X26166Y590371D01*
X23751D01*
X23732Y590390D01*
X22224D01*
X22205Y590371D01*
X20300D01*
X18513Y588584D01*
X12575D01*
X12569Y588578D01*
G01X48450Y639600D02*
X48999Y640149D01*
Y642900D01*
G01X55500Y618500D02*
X55519Y618519D01*
Y631981D01*
X52500Y635000D01*
G01X31249Y611550D02*
Y616050D01*
G01Y611550D02*
Y610949D01*
X24632Y604332D01*
X12575D01*
X12569Y604326D01*
G01X31249Y616050D02*
X33099Y614200D01*
X38149D01*
X39499Y615550D01*
G01X39650Y597400D02*
X37650Y599400D01*
X31134D01*
X30286Y600248D01*
X28586D01*
G01X12569Y596452D02*
X12575Y596458D01*
X24796D01*
X28586Y600248D01*
G01X12569Y600389D02*
X12575Y600395D01*
X23192D01*
X27845Y605048D01*
X28519D01*
G01X42900Y601350D02*
X42850Y601300D01*
X31922D01*
X30300Y602922D01*
Y603267D01*
X28519Y605048D01*
G01X32050Y593300D02*
X28958D01*
X28808Y593150D01*
G01X32050Y597400D02*
X29551D01*
X28700Y596549D01*
G01X35350Y603200D02*
X34840Y603710D01*
X32200D01*
G01X35350Y607326D02*
X35126Y607102D01*
X31598D01*
G01X66549Y651900D02*
X61086D01*
X60499Y652487D01*
G01D02*
Y656487D01*
G01D02*
Y660050D01*
X61999Y661550D01*
G01X110202Y813379D02*
X53889D01*
X51891Y811381D01*
X40019D01*
X38231Y813169D01*
X33091D01*
X32453Y812531D01*
X30945D01*
X30466Y813010D01*
X12560D01*
G01X111200Y799450D02*
X84567D01*
X84529Y799488D01*
X51717D01*
X51679Y799450D01*
X49504D01*
X45649Y795595D01*
X45595D01*
X45100Y795100D01*
X42300D01*
X40493Y793293D01*
X34805D01*
X34773Y793325D01*
X12560D01*
G01Y809073D02*
X12573Y809060D01*
X32440D01*
X35349Y806151D01*
X36443D01*
X36462Y806132D01*
X37970D01*
X37989Y806151D01*
X45751D01*
X48600Y809000D01*
X51773D01*
X52752Y809979D01*
X110195D01*
G01X110500Y790200D02*
X88200D01*
X82700Y795700D01*
X54509D01*
X44247Y785438D01*
X12573D01*
X12560Y785451D01*
G01X32800Y803050D02*
X30949Y801199D01*
X12560D01*
G01X110700Y795700D02*
X86000D01*
X84362Y797338D01*
X51911D01*
X42129Y787556D01*
X32745D01*
X30913Y789388D01*
X12560D01*
G01X46887Y803413D02*
X45947Y802473D01*
X40734D01*
G01X12560Y805136D02*
X33964D01*
X36627Y802473D01*
X40734D01*
G01X109831Y806598D02*
X51635D01*
X51337Y806300D01*
X51100D01*
G01X27299Y783550D02*
X25250Y781501D01*
X12573D01*
X12560Y781514D01*
G01Y797262D02*
X12722Y797100D01*
X44837D01*
X50937Y803200D01*
X109700D01*
G01X12560Y832696D02*
X25094D01*
X29299Y836901D01*
G01X40400Y840792D02*
X29641D01*
X25469Y836620D01*
X12573D01*
X12560Y836633D01*
G01Y816947D02*
X12573Y816934D01*
X37666D01*
X40500Y814100D01*
X49000D01*
X49900Y813200D01*
G01X48346Y844529D02*
X28178D01*
X24206Y840557D01*
X12573D01*
X12560Y840570D01*
G01X106499Y834550D02*
X100949Y829000D01*
X79283D01*
X76421Y831862D01*
X73120Y835162D01*
X64934D01*
X52696Y847400D01*
X31019D01*
X30960Y847341D01*
X29997D01*
X29449Y846793D01*
X27764D01*
X25478Y844507D01*
X12560D01*
G01X54074Y815750D02*
X41563D01*
X36429Y820884D01*
X12560D01*
G01Y848444D02*
X12573Y848431D01*
X28770D01*
X29999Y849660D01*
G01X26662Y861550D02*
X25650D01*
X20405Y856305D01*
X12573D01*
X12560Y856318D01*
G01X109999Y872550D02*
X109634Y872185D01*
X85650D01*
X85630Y872165D01*
G01X80500Y817000D02*
Y819346D01*
X77277Y822569D01*
X75521D01*
X75502Y822550D01*
X61701D01*
X61151Y822000D01*
X39649D01*
G01X25000Y858100D02*
X27000Y856100D01*
X48700D01*
X58900Y845900D01*
X74727D01*
X74746Y845881D01*
X76254D01*
X76273Y845900D01*
X89800D01*
X93100Y842600D01*
X98700D01*
G01Y822550D02*
X81802D01*
X79126Y825226D01*
Y825253D01*
X70855Y833524D01*
X65924D01*
X64171Y831771D01*
X47756D01*
X46576Y832951D01*
G01X98000Y833500D02*
X77100D01*
X73800Y836800D01*
X65613D01*
X48961Y853452D01*
X30148D01*
X29600Y854000D01*
G01X94999Y901550D02*
X94364Y902185D01*
X85650D01*
X85630Y902165D01*
G01X72000Y1013400D02*
X71773Y1013627D01*
Y1017455D01*
G01X81250Y1008500D02*
X75500D01*
X72000Y1012000D01*
Y1013400D01*
G01X63273Y1023974D02*
Y1023823D01*
X62999Y1023549D01*
Y1019050D01*
X64594Y1017455D01*
X66023D01*
G01X59686Y1021050D02*
Y1021737D01*
X61999Y1024050D01*
X63197D01*
X63273Y1023974D01*
G01X87349Y1000450D02*
X90000Y997799D01*
Y993100D01*
G01X87349Y1004450D02*
X91900Y999899D01*
Y996450D01*
X92250Y996100D01*
X92600D01*
G01X56186Y1021050D02*
Y1021910D01*
X54000Y1024096D01*
Y1033286D01*
X31236Y1056050D01*
X28349D01*
G01X56186Y1021050D02*
Y1017113D01*
X56249Y1017050D01*
G01D02*
X52749Y1013550D01*
X52499D01*
G01X66499Y1025050D02*
Y1021131D01*
X66023Y1020655D01*
G01X59686Y1025050D02*
X61186Y1026550D01*
X65499D01*
X66499Y1025550D01*
Y1025050D01*
G01X71773Y1020655D02*
X74345D01*
X75900Y1019100D01*
G01X82750Y1013000D02*
X80350Y1015400D01*
X79600D01*
X75900Y1019100D01*
G01X63500Y1029600D02*
X60736D01*
X56186Y1025050D01*
G01X34000Y1058250D02*
Y1055900D01*
X56186Y1033714D01*
Y1025050D01*
G01X26500Y1064500D02*
X25424D01*
X20849Y1059925D01*
G01X86000Y1113000D02*
X88980D01*
X95900Y1119920D01*
Y1132400D01*
X99550Y1136050D01*
X104999D01*
G01X26500Y1064500D02*
X31250D01*
X34000Y1061750D01*
G01X100500Y1111750D02*
X99250Y1113000D01*
X95000D01*
G01D02*
Y1116000D01*
X97800Y1118800D01*
Y1131271D01*
X100029Y1133500D01*
X112500D01*
X113500Y1134500D01*
G01X76999Y1196550D02*
X81999Y1191550D01*
X114499D01*
X115499Y1192550D01*
Y1197550D01*
G01X105999Y1311050D02*
X98885D01*
X95532Y1307697D01*
X85650D01*
X85630Y1307677D01*
G01X141499Y1267050D02*
X138949Y1269600D01*
X128501D01*
X128500Y1269601D01*
X128397D01*
X127398Y1270600D01*
X98449D01*
X91352Y1277697D01*
X85650D01*
X85630Y1277677D01*
G01X20999Y1320550D02*
Y1315550D01*
X20499Y1315050D01*
G01X20999Y1352050D02*
Y1355501D01*
X20201Y1356299D01*
X12575D01*
X12569Y1356293D01*
G01X25000Y1357742D02*
X22506Y1360236D01*
X12575D01*
X12569Y1360230D01*
G01X71773Y1422967D02*
X75694D01*
X113999Y1384662D01*
Y1380550D01*
G01X66023Y1422967D02*
X66022Y1422966D01*
Y1422384D01*
X69750Y1418656D01*
X75371D01*
X108900Y1385127D01*
Y1373848D01*
X115499Y1367249D01*
Y1364550D01*
G01X121000Y1364000D02*
Y1365747D01*
X110550Y1376197D01*
Y1385794D01*
X76050Y1420294D01*
X70429D01*
X68900Y1421823D01*
Y1424107D01*
X66853Y1426154D01*
X66036D01*
X66023Y1426167D01*
G01X71773D02*
X74811D01*
X122800Y1378178D01*
Y1372700D01*
X123500Y1372000D01*
G01X12569Y1395663D02*
X30337D01*
X30500Y1395500D01*
G01X79000Y1548250D02*
Y1545700D01*
X80009Y1544691D01*
X80043D01*
G01X83000Y1548250D02*
Y1545637D01*
X83932Y1544705D01*
G01X29631Y1533063D02*
X26097Y1529529D01*
X12575D01*
X12569Y1529523D01*
G01X37999Y1530900D02*
X35900Y1532999D01*
Y1535200D01*
X29760Y1541340D01*
X12575D01*
X12569Y1541334D01*
G01X32099Y1535550D02*
X30246Y1537403D01*
X12575D01*
X12569Y1537397D01*
G01X26705Y1534795D02*
X25376Y1533466D01*
X12575D01*
X12569Y1533460D01*
G01X97499Y1554550D02*
X96449Y1553500D01*
X92750D01*
G01X12569Y1545271D02*
X12575Y1545277D01*
X22023D01*
X22789Y1544511D01*
X29260D01*
X30199Y1545450D01*
G01X79000Y1551750D02*
Y1555500D01*
G01X83000Y1551750D02*
Y1554929D01*
X82429Y1555500D01*
G01X89250Y1553500D02*
X85150Y1557600D01*
X66400D01*
X63014Y1560986D01*
G01X79000Y1565150D02*
Y1562400D01*
X78600Y1562000D01*
Y1561900D01*
G01X75000Y1565150D02*
Y1561800D01*
G01X12569Y1592515D02*
X12575Y1592521D01*
X21129D01*
X21550Y1592100D01*
X23400D01*
X29051Y1597751D01*
X33751D01*
X37050Y1601050D01*
X38499D01*
G01X42199D02*
X38499D01*
G01X38208Y1569841D02*
X40819Y1572452D01*
Y1574254D01*
X36225Y1578848D01*
X20448D01*
X18373Y1576773D01*
X12575D01*
X12569Y1576767D01*
G01X25521Y1563350D02*
X23909Y1564962D01*
X12575D01*
X12569Y1564956D01*
G01X96999Y1558050D02*
X96449Y1557500D01*
X92750D01*
G01X34999Y1572550D02*
X32824Y1574725D01*
X23107D01*
X21047Y1572665D01*
Y1571791D01*
X18155Y1568899D01*
X12575D01*
X12569Y1568893D01*
G01X96999Y1632050D02*
Y1637400D01*
X87099Y1647300D01*
Y1651250D01*
X77900Y1660449D01*
Y1680500D01*
X80609Y1683209D01*
X85610D01*
X85630Y1683189D01*
G01X33599Y1600200D02*
X27386D01*
X23644Y1596458D01*
X12575D01*
X12569Y1596452D01*
G01Y1572830D02*
X18530D01*
X22872Y1577172D01*
X23317D01*
X23355Y1577210D01*
X35285D01*
X38995Y1573500D01*
X39000D01*
G01X42449Y1588600D02*
X34599D01*
G01X30499Y1588610D02*
X30473Y1588584D01*
X12575D01*
X12569Y1588578D01*
G01X34599Y1588600D02*
X30509D01*
X30499Y1588610D01*
G01X75000Y1568650D02*
Y1569260D01*
X77506Y1571766D01*
X80400D01*
G01X79000Y1568650D02*
X81796D01*
X82329Y1568117D01*
G01X12569Y1580704D02*
X12575Y1580710D01*
X43290D01*
X63014Y1560986D01*
G01X89250Y1557500D02*
X87250Y1559500D01*
X67500D01*
X60172Y1566828D01*
G01X12569Y1584641D02*
X12575Y1584647D01*
X26805D01*
X26822Y1584630D01*
X42370D01*
X60172Y1566828D01*
G01X85630Y1713189D02*
X92486D01*
X103562Y1702113D01*
X104999D01*
G01X46999Y1779550D02*
X45013Y1777564D01*
X12573D01*
X12560Y1777577D01*
G01Y1793325D02*
X12573Y1793312D01*
X28620D01*
X28670Y1793262D01*
X32287D01*
X35699Y1789850D01*
X37699D01*
G01X46199Y1783050D02*
X38750D01*
X37201Y1781501D01*
X12573D01*
X12560Y1781514D01*
G01X38094Y1785840D02*
X37673Y1785419D01*
X29520D01*
X29488Y1785451D01*
X12560D01*
G01X42199Y1792250D02*
X38347D01*
X38328Y1792231D01*
X36820D01*
X36801Y1792250D01*
X35650D01*
X33000Y1794900D01*
X29349D01*
X27000Y1797249D01*
X12573D01*
X12560Y1797262D01*
G01X37574Y1794050D02*
Y1794475D01*
X30863Y1801186D01*
X12573D01*
X12560Y1801199D01*
G01X45799Y1757650D02*
X37696Y1765753D01*
X12573D01*
X12560Y1765766D01*
G01Y1805136D02*
X24164D01*
X26476Y1802824D01*
X31542D01*
X32366Y1802000D01*
X39699D01*
X46799Y1794900D01*
G01X31811Y1790271D02*
X30915Y1789375D01*
X12573D01*
X12560Y1789388D01*
G01X47400Y1765250D02*
X40999D01*
X36559Y1769690D01*
X12573D01*
X12560Y1769703D01*
G01X43559Y1767884D02*
X43000Y1768443D01*
Y1768815D01*
X38188Y1773627D01*
X12573D01*
X12560Y1773640D01*
G01X71773Y1828479D02*
X71786Y1828466D01*
X76883D01*
X78099Y1827250D01*
G01X82499Y1828613D02*
X81136Y1827250D01*
X78099D01*
G01X66023Y1828479D02*
X63570D01*
X62104Y1829945D01*
Y1831918D01*
X65300Y1835114D01*
Y1839800D01*
X64700Y1840400D01*
Y1844418D01*
X65301Y1845019D01*
X76030D01*
X77499Y1843550D01*
Y1843113D01*
G01X89499D02*
X88612Y1844000D01*
X78386D01*
X77499Y1843113D01*
G01X83499Y1841550D02*
X81999Y1840050D01*
X76354D01*
X73854Y1837550D01*
X73749D01*
G01X73999Y1843113D02*
X68462D01*
X67949Y1842600D01*
G01X73749Y1837550D02*
X73499Y1837800D01*
Y1840050D01*
X73999Y1840550D01*
Y1843113D01*
G01X28123Y1831527D02*
X25342Y1828746D01*
X12573D01*
X12560Y1828759D01*
G01Y1820885D02*
X26937D01*
X28999Y1818823D01*
X33626D01*
X36399Y1816050D01*
Y1812873D01*
X35876Y1812350D01*
G01X34129Y1815267D02*
X32448Y1816948D01*
X12560D01*
G01Y1824822D02*
X12573Y1824809D01*
X21891D01*
X23550Y1823150D01*
X25326D01*
X25345Y1823131D01*
X26853D01*
X26872Y1823150D01*
X31499D01*
X33701Y1825352D01*
X36532D01*
G01X66023Y1831679D02*
X67370D01*
X68542Y1830507D01*
Y1826981D01*
X68121Y1826560D01*
X63172D01*
X60466Y1829266D01*
Y1833975D01*
X63662Y1837171D01*
Y1844862D01*
X65500Y1846700D01*
X75586D01*
X77249Y1848363D01*
Y1849050D01*
G01D02*
X79999D01*
X81499Y1847550D01*
G01X82499Y1832613D02*
X81729Y1833383D01*
X79032D01*
X77999Y1832350D01*
G01X71773Y1831679D02*
X77328D01*
X77999Y1832350D01*
G01X35900Y1832700D02*
X34900Y1833700D01*
X27117D01*
X26100Y1832683D01*
X12573D01*
X12560Y1832696D01*
G01X97999Y1843050D02*
X96394D01*
X88044Y1851400D01*
X75849D01*
X73749Y1849300D01*
Y1849050D01*
G01X67349Y1851900D02*
X70899D01*
X73749Y1849050D01*
G01X46499Y1850050D02*
X46249D01*
X38249Y1842050D01*
G01D02*
X37749Y1842550D01*
X30372D01*
X30353Y1842531D01*
X28845D01*
X28826Y1842550D01*
X25999D01*
G01X41749Y1838050D02*
X44999D01*
X46499Y1836550D01*
G01X38249Y1838050D02*
X35742Y1840557D01*
X12573D01*
X12560Y1840570D01*
G01X46999Y1832550D02*
X43549Y1836000D01*
X40299D01*
X38249Y1838050D01*
G01X41749Y1842050D02*
X45000D01*
X47166Y1839884D01*
G01X63849Y1851900D02*
Y1849875D01*
X60449Y1846475D01*
G01X57999Y1830050D02*
X57300Y1830749D01*
Y1843351D01*
X60424Y1846475D01*
X60449D01*
G01X158249Y165050D02*
X159652Y163647D01*
X164448D01*
G01D02*
X166402D01*
X167499Y162550D01*
Y156050D01*
X166999Y155550D01*
G01X200999Y159050D02*
X200499Y158550D01*
X197091D01*
X196097Y159544D01*
X196070D01*
X195752Y159862D01*
X191346D01*
X191028Y159544D01*
X191001D01*
X190007Y158550D01*
X178499D01*
X176749Y160300D01*
Y161050D01*
G01X170198Y163647D02*
X171902D01*
X173515Y162034D01*
X173528D01*
X174512Y161050D01*
X176749D01*
G01X170198Y160447D02*
X170197Y160446D01*
Y154852D01*
X171499Y153550D01*
G01X176749Y156550D02*
X173249Y153050D01*
X171999D01*
X171499Y153550D01*
G01X164448Y160447D02*
X164447Y160446D01*
Y156498D01*
X162499Y154550D01*
X162177D01*
G01X158249Y161050D02*
X160999Y158300D01*
Y155728D01*
X162177Y154550D01*
G01X212578Y287448D02*
X212494Y287364D01*
X207537D01*
G03X203313Y283140I0J-4224D01*
G02X199090Y278917I-4223J0D01*
G01X150611D01*
X150591Y278937D01*
G01X276500Y319500D02*
X275550Y318550D01*
X256894D01*
X253080Y322364D01*
X193941D01*
G03X186870Y319435I0J-10000D01*
G01X179288Y311853D01*
G02X172217Y308924I-7071J7071D01*
G01X150604D01*
X150591Y308937D01*
G01X146499Y443863D02*
X141499D01*
G01X150999D02*
X146499D01*
G01X141499D02*
X138237D01*
X137500Y444600D01*
G01X141499Y427550D02*
X144752D01*
X145439Y426863D01*
G01X137749Y427113D02*
X141062D01*
X141499Y427550D01*
G01X147999Y426863D02*
Y421550D01*
X145999Y419550D01*
X144999D01*
G01X141499Y423050D02*
X144999Y419550D01*
G01X137749Y423113D02*
X141436D01*
X141499Y423050D01*
G01X161999Y426450D02*
X161399Y427050D01*
X160499D01*
X156015Y431534D01*
X156001D01*
X155580Y431955D01*
Y431982D01*
X153200Y434362D01*
Y435979D01*
X150999Y438180D01*
Y440363D01*
G01X158299Y435613D02*
X156787D01*
X152037Y440363D01*
X150999D01*
G01X159600Y446399D02*
X160499Y445500D01*
X160549D01*
X162186Y443863D01*
X162999D01*
G01D02*
X161399Y442263D01*
Y434806D01*
X159646Y433053D01*
X158299D01*
G01X173999Y430050D02*
X174000Y430049D01*
Y426000D01*
X175000Y425000D01*
G01X179750Y420500D02*
X179500D01*
X175000Y425000D01*
G01X156959Y426292D02*
Y427389D01*
X150985Y433363D01*
X150559D01*
G01X146499Y440363D02*
X150559Y436303D01*
Y433363D01*
G01X166850Y424300D02*
Y424400D01*
X164118Y427132D01*
Y427328D01*
X162600Y428846D01*
Y433690D01*
X162980Y434070D01*
Y434151D01*
X164442Y435613D01*
X165699D01*
G01X166850Y424300D02*
X165050D01*
X162000Y421250D01*
G01X165699Y438173D02*
X167399D01*
X168700Y436872D01*
Y426050D01*
X170350Y424400D01*
Y424300D01*
G01X171000Y414500D02*
X176500D01*
G01D02*
Y420250D01*
X176250Y420500D01*
G01X170350Y420300D02*
Y424300D01*
G01X176250Y420500D02*
X170550D01*
X170350Y420300D01*
G01X164448Y569159D02*
X165338D01*
X167200Y567297D01*
Y561000D01*
G01X168997Y533288D02*
Y536297D01*
X170250Y537550D01*
X177999D01*
X179000Y536549D01*
Y535500D01*
G01X174449Y524850D02*
Y525400D01*
X168997Y530852D01*
Y533288D01*
G01X174199Y520600D02*
X174449Y520850D01*
Y524850D01*
G01X179499Y542550D02*
X176424Y539475D01*
X169475D01*
X166436Y536436D01*
Y533289D01*
X166437Y533288D01*
G01X166949Y524850D02*
X166053Y525746D01*
Y528944D01*
X166436Y529327D01*
Y533287D01*
X166437Y533288D01*
G01X167199Y520600D02*
Y524600D01*
X166949Y524850D01*
G01X151699Y524650D02*
X151899D01*
X155949Y520600D01*
X159199D01*
G01X159449Y524850D02*
X163876Y529277D01*
Y533287D01*
X163877Y533288D01*
G01X159199Y520600D02*
Y524600D01*
X159449Y524850D01*
G01X136000Y528750D02*
X135311Y528061D01*
Y524340D01*
X135300Y524329D01*
G01X135499Y517550D02*
Y524130D01*
X135300Y524329D01*
G01X143499Y517613D02*
X139249D01*
X138999Y517363D01*
G01X148249Y517613D02*
X143499D01*
G01X138999Y517363D02*
X135686D01*
X135499Y517550D01*
G01X172499Y491053D02*
X175199Y488353D01*
X176999D01*
G01X181899Y496400D02*
X176549D01*
X172499Y492350D01*
Y491053D01*
G01X137899Y545451D02*
Y540200D01*
X143499Y534600D01*
Y523613D01*
G01X176799Y493850D02*
X176999Y493650D01*
Y490913D01*
G01X185999Y496400D02*
X184949D01*
X182399Y493850D01*
X176799D01*
G01X166437Y549468D02*
X166436Y549469D01*
Y553913D01*
X162849Y557500D01*
X162500D01*
G01X172199Y557108D02*
X174000Y558909D01*
Y561301D01*
X176749Y564050D01*
G01X154049Y544250D02*
X150750Y540951D01*
Y540416D01*
G01X154049Y540050D02*
X151499Y537500D01*
X149000D01*
G01X157749Y566050D02*
Y562000D01*
G01X155999Y535775D02*
Y536550D01*
X157549Y538100D01*
Y540050D01*
G01D02*
X158599Y541100D01*
X168288D01*
X171557Y544369D01*
Y549468D01*
G01X156499Y548550D02*
X157549Y547500D01*
Y544250D01*
G01D02*
X158799Y543000D01*
X167500D01*
X168997Y544497D01*
Y549468D01*
G01X141125Y531550D02*
X136700D01*
X136000Y532250D01*
G01D02*
X136100Y532700D01*
Y534157D01*
X136099Y534158D01*
Y537000D01*
X134899Y538200D01*
G01X135300Y549500D02*
X137661D01*
X139080Y548081D01*
X139119D01*
X142200Y545000D01*
X143750D01*
G01X143500Y557700D02*
Y550300D01*
G01X143750Y545000D02*
Y550050D01*
X143500Y550300D01*
G01X145000Y539050D02*
Y543750D01*
X143750Y545000D01*
G01X157749Y570050D02*
X158999D01*
X159903Y569146D01*
X164435D01*
X164448Y569159D01*
G01X170198D02*
X170211Y569146D01*
X175653D01*
X176749Y568050D01*
G01D02*
Y567300D01*
X177999Y566050D01*
X189499D01*
X190499Y567050D01*
X198999D01*
X200999Y565050D01*
G01X176749Y564050D02*
X174853Y565946D01*
X170211D01*
X170198Y565959D01*
G01X164448D02*
X164357Y566050D01*
X157749D01*
G01X213299Y693800D02*
X205749D01*
X196385Y684436D01*
X150604D01*
X150591Y684449D01*
G01X288999Y723550D02*
X287049Y725500D01*
X255550D01*
X251600Y721550D01*
X238999D01*
X231449Y729100D01*
X231398D01*
X229948Y730550D01*
X223050D01*
X222550Y730050D01*
X198550D01*
X182936Y714436D01*
X156600D01*
X156587Y714449D01*
X150591D01*
G01X172499Y836863D02*
X167499D01*
G01X176499D02*
X172499D01*
G01X167499D02*
X167045Y837317D01*
Y841004D01*
X166499Y841550D01*
G01X110499Y834550D02*
X106499D01*
G01X165499Y815550D02*
X167439Y817490D01*
Y820363D01*
G01X166499Y812363D02*
Y814550D01*
X165499Y815550D01*
G01X169106Y815865D02*
Y816657D01*
X169999Y817550D01*
Y820363D01*
G01X170499Y812363D02*
Y814472D01*
X169106Y815865D01*
G01X181799Y834113D02*
X179249D01*
X178499Y833363D01*
X176499D01*
G01D02*
Y829550D01*
X179999Y826050D01*
G01X160999Y942550D02*
Y934550D01*
X151400Y924951D01*
Y884169D01*
X155019Y880550D01*
X200189D01*
X203439Y883800D01*
Y885300D01*
G01X179499Y820550D02*
X178499D01*
X172559Y826490D01*
Y826863D01*
G01X172499Y833363D02*
X172559Y833303D01*
Y826863D01*
G01X170198Y974671D02*
X174378D01*
X176499Y972550D01*
G01D02*
Y971550D01*
X178499Y969550D01*
X182499D01*
X183499Y968550D01*
X188499D01*
X190999Y971050D01*
X199999D01*
G01X153499Y918550D02*
X155469D01*
X156969Y917050D01*
G01D02*
X158156Y915863D01*
X161999D01*
G01X166499Y916113D02*
X171249D01*
G01D02*
X169500Y917862D01*
Y920950D01*
X171250Y922700D01*
G01X161999Y915863D02*
X162249Y916113D01*
X166499D01*
G01Y922113D02*
Y930499D01*
X171000Y935000D01*
X171100D01*
G01X170198Y971471D02*
X170197Y971470D01*
Y966352D01*
X171499Y965050D01*
G01X176749Y967550D02*
X174749Y965550D01*
X171999D01*
X171499Y965050D01*
G01X105500Y972000D02*
X103100D01*
X102100Y971000D01*
Y968500D01*
G01X105449Y967850D02*
X102599Y965000D01*
X99000D01*
G01X164448Y971471D02*
X164435Y971458D01*
X158341D01*
X158249Y971550D01*
G01D02*
Y968051D01*
X158800Y967500D01*
G01X158249Y975550D02*
X159141Y974658D01*
X164435D01*
X164448Y974671D01*
G01D02*
X165329D01*
X167400Y972600D01*
Y967451D01*
X164999Y965050D01*
G01X172000Y961000D02*
X172550Y961550D01*
X178999D01*
G01X152500Y960000D02*
Y956549D01*
X160999Y948050D01*
Y947274D01*
X161286Y946987D01*
Y946684D01*
X161600Y946370D01*
Y944630D01*
X160999Y944029D01*
Y942550D01*
G01X180025Y918250D02*
X175575Y922700D01*
X174750D01*
G01D02*
X174800Y922500D01*
Y925300D01*
X173100Y927000D01*
X171000D01*
G01X119499Y1106300D02*
X128499D01*
X134999Y1099800D01*
Y1093050D01*
X129499Y1087550D01*
X125999D01*
G01X97499Y1086800D02*
X101999D01*
G01D02*
X104361Y1089162D01*
X122737D01*
X124349Y1087550D01*
X125999D01*
G01X120749Y1093990D02*
X116249D01*
G01X124730Y1094482D02*
X121241D01*
X120749Y1093990D01*
G01X105499Y1080550D02*
X106749Y1079300D01*
X109439D01*
G01X101349Y1081700D02*
X104349D01*
X105499Y1080550D01*
G01X106718Y1076050D02*
X107499D01*
X107999Y1075550D01*
X111499D01*
X111999Y1076050D01*
Y1079300D01*
G01X101349Y1077400D02*
X105149D01*
X106499Y1076050D01*
X106718D01*
G01X212600Y1089961D02*
X150591D01*
G01X123999Y1102050D02*
Y1099213D01*
X124730Y1098482D01*
G01X123999Y1102050D02*
X118499Y1096550D01*
X116249D01*
G01X123999Y1102550D02*
Y1102050D01*
G01X113499Y1109200D02*
X118899D01*
X119499Y1109800D01*
G01D02*
X122949D01*
X124249Y1108500D01*
G01X138600Y1124600D02*
X138150Y1125050D01*
X122249D01*
G01X113499Y1111760D02*
X117510D01*
X119250Y1113500D01*
G01X122249Y1125050D02*
X121999Y1124800D01*
Y1121495D01*
X121257Y1120753D01*
X121245D01*
G01X119250Y1113500D02*
Y1115821D01*
X121245Y1117816D01*
Y1120753D01*
G01X104999Y1136050D02*
X109287D01*
X110737Y1137500D01*
X118250D01*
X119000Y1136750D01*
G01D02*
X123000D01*
G01X127000D02*
X128750D01*
X130500Y1135000D01*
Y1129500D01*
X131491Y1128509D01*
Y1128483D01*
G01X123000Y1136750D02*
X127000D01*
G01X116700Y1063500D02*
Y1075106D01*
X119899Y1078305D01*
Y1081201D01*
X115300Y1085800D01*
X114559D01*
G01X108999Y1102050D02*
X109749Y1101300D01*
Y1099110D01*
G01X101999Y1090300D02*
X102499Y1090800D01*
X112249D01*
X112999Y1091550D01*
Y1097550D01*
X111439Y1099110D01*
X109749D01*
G01X150591Y1119961D02*
X150578Y1119948D01*
X128532D01*
G03X127448Y1119499I0J-1533D01*
G01X126999Y1119050D01*
G01X100500Y1103750D02*
X107026D01*
X108818Y1105542D01*
Y1105569D01*
X109000Y1105751D01*
Y1108500D01*
X108300Y1109200D01*
X106099D01*
G01X100500Y1103750D02*
X99250D01*
X96000Y1107000D01*
G01X119000Y1133250D02*
X117750Y1134500D01*
X113500D01*
G01X100500Y1107250D02*
X101110Y1106640D01*
X106099D01*
G01X100500Y1111750D02*
Y1107250D01*
G01X105499Y1201863D02*
X100686D01*
X99999Y1202550D01*
G01D02*
Y1204550D01*
X100999Y1205550D01*
X106010D01*
X106162Y1205702D01*
G01D02*
X106939Y1206479D01*
Y1210363D01*
G01X115499Y1197550D02*
Y1199363D01*
X112999Y1201863D01*
X109499D01*
G01D02*
Y1210363D01*
G01X116499Y1223863D02*
Y1215050D01*
X117499Y1214050D01*
G01X123299Y1216113D02*
X119562D01*
X117499Y1214050D01*
G01X121000Y1207000D02*
X123299Y1209299D01*
Y1213553D01*
G01X123970Y1221573D02*
X126760Y1224363D01*
X127499D01*
G01D02*
Y1216916D01*
X126018Y1215435D01*
Y1215015D01*
X124556Y1213553D01*
X123299D01*
G01X148500Y1196000D02*
X142000D01*
G01X138499Y1216113D02*
Y1211251D01*
X139750Y1210000D01*
G01D02*
Y1206000D01*
G01Y1202000D02*
Y1198250D01*
X142000Y1196000D01*
G01X139750Y1206000D02*
Y1202000D01*
G01X111999Y1223863D02*
Y1216923D01*
X112059Y1216863D01*
G01D02*
Y1215110D01*
X110499Y1213550D01*
X100999D01*
G01X131250Y1206000D02*
X129000D01*
X127500Y1207500D01*
G01X130699Y1216113D02*
X129013D01*
X127656Y1214756D01*
Y1214336D01*
X127500Y1214180D01*
Y1207500D01*
G01X127000Y1196000D02*
X133000D01*
G01D02*
X134750Y1197750D01*
Y1202000D01*
G01Y1206000D02*
Y1208500D01*
X136250Y1210000D01*
G01X134750Y1202000D02*
Y1206000D01*
G01X136250Y1210000D02*
Y1212750D01*
X134500Y1214500D01*
Y1217500D01*
X133327Y1218673D01*
X130699D01*
G01X111999Y1227363D02*
X106999D01*
G01X116499D02*
X111999D01*
G01X106999D02*
X101812D01*
X100499Y1226050D01*
G01X105999Y1311050D02*
X100700Y1305751D01*
Y1298849D01*
X101686Y1297863D01*
X103499D01*
G01X107999Y1298113D02*
X112749D01*
G01X103499Y1297863D02*
X103749Y1298113D01*
X107999D01*
G01X124550Y1319900D02*
Y1317850D01*
X122200Y1315500D01*
Y1309751D01*
X121578Y1309129D01*
Y1309102D01*
X121157Y1308681D01*
X117881D01*
X117400Y1308200D01*
Y1303431D01*
X112749Y1298780D01*
Y1298113D01*
G01X107999Y1304113D02*
Y1307713D01*
G01X182500Y1275500D02*
X181250Y1276750D01*
X177500D01*
G01D02*
X177137Y1277113D01*
X171499D01*
G01X114939Y1305300D02*
X113499D01*
X109099Y1309700D01*
Y1311201D01*
X100500Y1319800D01*
Y1322900D01*
X103600Y1326000D01*
X109449D01*
X112499Y1329050D01*
G01X170198Y1380183D02*
X170211Y1380170D01*
X172948D01*
X175178Y1382400D01*
X186000D01*
G01X113999Y1380550D02*
Y1375880D01*
X122638Y1367241D01*
Y1364908D01*
X126546Y1361000D01*
X128250D01*
G01X119749Y1352050D02*
X116600Y1355199D01*
Y1363449D01*
X115499Y1364550D01*
G01X120507Y1317050D02*
X120059Y1316602D01*
Y1311800D01*
G01X120507Y1321446D02*
Y1317050D01*
G01X148000Y1346500D02*
X147500D01*
X142450Y1351550D01*
X129749D01*
G01X123249Y1352050D02*
X123749Y1351550D01*
X129749D01*
G01X123249Y1356050D02*
Y1352050D01*
G01X170198Y1376983D02*
X172283D01*
X175479Y1380179D01*
X186770D01*
X187249Y1379700D01*
Y1375800D01*
X189999Y1373050D01*
X191249D01*
G01X102700Y1321363D02*
X116499D01*
G01D02*
X117487Y1320375D01*
Y1314900D01*
X117499Y1314888D01*
Y1311800D01*
G01X119499Y1339050D02*
Y1338050D01*
X116499Y1335050D01*
G01X120249Y1343050D02*
X119499Y1342300D01*
Y1339050D01*
G01X164448Y1376983D02*
X164447Y1376982D01*
Y1373102D01*
X169999Y1367550D01*
X176999D01*
G01X180500Y1376550D02*
X176999Y1373049D01*
Y1367550D01*
G01X131750Y1365000D02*
X131645D01*
X124645Y1372000D01*
X123500D01*
G01X164448Y1380183D02*
X165317D01*
X167499Y1378001D01*
Y1373050D01*
X169999Y1370550D01*
X171499D01*
G01X184600Y1376550D02*
Y1377479D01*
X183538Y1378541D01*
X179490D01*
X171499Y1370550D01*
G01X127749Y1342050D02*
X126749Y1343050D01*
X123749D01*
G01D02*
Y1338658D01*
X114141Y1329050D01*
X112499D01*
G01X131249Y1342050D02*
X131298Y1342001D01*
X135601D01*
X136200Y1342600D01*
G01X137249Y1347675D02*
Y1343649D01*
X136200Y1342600D01*
G01X153500Y1326700D02*
X153100Y1327100D01*
X147400D01*
G01D02*
X140000D01*
G01X129600Y1334250D02*
X131150Y1335800D01*
X138650D01*
G01D02*
Y1334450D01*
X136800Y1332600D01*
Y1327800D01*
X137500Y1327100D01*
X140000D01*
G01X125725Y1326750D02*
Y1322225D01*
X128050Y1319900D01*
G01D02*
X128100Y1319850D01*
Y1316844D01*
X129339Y1315605D01*
X129699D01*
G01X115499Y1476050D02*
Y1472100D01*
X115599Y1472000D01*
G01D02*
X119049D01*
X120499Y1470550D01*
G01X111499Y1472050D02*
Y1476050D01*
G01X103999D02*
Y1472050D01*
G01D02*
X103094D01*
X101693Y1473451D01*
X98097D01*
X96199Y1475350D01*
X95899D01*
G01X113485Y1484981D02*
X113484Y1484980D01*
Y1478065D01*
X115499Y1476050D01*
G01X110925Y1484981D02*
X110924Y1484982D01*
Y1489125D01*
X110499Y1489550D01*
X100999D01*
X97999Y1486550D01*
G01X111499Y1476050D02*
X110924Y1476625D01*
Y1484980D01*
X110925Y1484981D01*
G01X108365D02*
X108364Y1484980D01*
Y1480415D01*
X103999Y1476050D01*
G01X211914Y1504015D02*
X210964D01*
X202409Y1495460D01*
X150604D01*
X150591Y1495473D01*
G01X110925Y1501161D02*
X110924Y1501162D01*
Y1507725D01*
X107699Y1510950D01*
G01X112599Y1513600D02*
Y1539811D01*
X97860Y1554550D01*
X97499D01*
G01X116749Y1513600D02*
X116200Y1514149D01*
Y1538898D01*
X97048Y1558050D01*
X96999D01*
G01X121499Y1511050D02*
X120549Y1510100D01*
X116749D01*
G01D02*
X116045Y1509396D01*
Y1501161D01*
G01X108000Y1517000D02*
Y1514804D01*
X112599Y1510205D01*
Y1510100D01*
G01D02*
X113485Y1509214D01*
Y1501161D01*
G01X150591Y1525473D02*
X142913D01*
X142900Y1525460D01*
X119089D01*
X118999Y1525550D01*
G01X174499Y1653113D02*
Y1656050D01*
X171999Y1658550D01*
G01D02*
Y1662250D01*
G01X147749Y1718550D02*
Y1717550D01*
X150999Y1714300D01*
Y1713550D01*
G01X147749Y1722550D02*
Y1718550D01*
G01X131999Y1710050D02*
X132939Y1710990D01*
Y1714800D01*
G01X131999Y1706800D02*
Y1710050D01*
G01X109499Y1708613D02*
Y1712213D01*
G01X112753Y1716613D02*
Y1716804D01*
X113499Y1717550D01*
X117249D01*
G01X109249Y1716613D02*
X112753D01*
G01X122642Y1704243D02*
Y1706907D01*
X121499Y1708050D01*
G01X152600Y1681150D02*
Y1678000D01*
X152633Y1677967D01*
G01X121499Y1708050D02*
X121099Y1708450D01*
X115399D01*
X113999Y1707050D01*
Y1702613D01*
G01X109499D02*
X105499D01*
X104999Y1702113D01*
G01X113999Y1702613D02*
X109499D01*
G01X109249Y1720613D02*
Y1725800D01*
G01D02*
X111849D01*
X112562Y1725087D01*
Y1720613D01*
G01D02*
X113436D01*
X113939Y1720110D01*
X117249D01*
G01X135499Y1710150D02*
Y1714800D01*
G01X135999Y1706800D02*
Y1709650D01*
X135499Y1710150D01*
G01X179999Y1650427D02*
X179185Y1649613D01*
X174499D01*
G01D02*
X170436D01*
X168999Y1651050D01*
G01X172499Y1700113D02*
X174387D01*
X176750Y1697750D01*
X178500D01*
G01X123749Y1714990D02*
Y1711550D01*
G01X144999Y1711050D02*
X144249Y1711800D01*
Y1718550D01*
G01D02*
X141499Y1721300D01*
X138059D01*
G01X174800Y1670800D02*
Y1678400D01*
G01D02*
Y1685800D01*
G01X161700Y1689550D02*
X163350Y1691200D01*
X170750D01*
G01D02*
X174800Y1687150D01*
Y1685800D01*
G01X157825Y1682050D02*
X155225Y1684650D01*
X152600D01*
G01D02*
X149350D01*
X148100Y1683400D01*
G01X172999Y1775050D02*
X174999Y1777050D01*
Y1780050D01*
X177314Y1782365D01*
Y1782613D01*
G01D02*
X174246Y1785681D01*
X170211D01*
X170198Y1785694D01*
G01Y1782494D02*
X170197Y1782493D01*
Y1773852D01*
X171999Y1772050D01*
X177314D01*
G01Y1778613D02*
Y1772050D01*
G01X158027Y1778300D02*
Y1782715D01*
X158221Y1782909D01*
G01D02*
X164033D01*
X164448Y1782494D01*
G01X158221Y1786909D02*
X163233D01*
X164448Y1785694D01*
G01D02*
X165855D01*
X166999Y1784550D01*
Y1774550D01*
G01X150591Y1900985D02*
X211564D01*
X215499Y1897050D01*
X218499D01*
G01X150591Y1930985D02*
X158064D01*
X165099Y1923950D01*
X211800D01*
X212239Y1923511D01*
X212289D01*
X212669Y1923131D01*
X220449D01*
X221268Y1923950D01*
X227417D01*
X233100Y1929633D01*
Y1929800D01*
G01X183149Y152000D02*
Y150900D01*
X184649Y149400D01*
X211349D01*
X218499Y156550D01*
Y183050D01*
G01X186049Y161200D02*
X186349Y161500D01*
X198449D01*
X201490Y164541D01*
X201561D01*
G01X180249Y161050D02*
X185899D01*
X186049Y161200D01*
G01X180249Y165050D02*
Y161050D01*
G01X218499Y190550D02*
Y183050D01*
G01X180249Y156550D02*
X183149Y153650D01*
Y152000D01*
G01X186649D02*
X191449D01*
G01X193549Y157325D02*
Y154100D01*
X191449Y152000D01*
G01X225298Y281114D02*
Y277549D01*
X223899Y276150D01*
X221799D01*
G01X221498Y281114D02*
Y276451D01*
X221799Y276150D01*
G01X212578Y287448D02*
X212600D01*
X212684Y287364D01*
X216998D01*
G01X221498Y287114D02*
X226248D01*
G01D02*
Y285402D01*
X228650Y283000D01*
G01X216998Y287364D02*
X221248D01*
X221498Y287114D01*
G01X253871Y291410D02*
X253998Y291537D01*
Y295114D01*
G01X244600Y282500D02*
Y275100D01*
G01D02*
Y273750D01*
X240550Y269700D01*
G01X231500Y269350D02*
X231400Y268300D01*
Y262800D01*
G01X240550Y269700D02*
X240200Y269350D01*
X231500D01*
G01X235375Y276850D02*
Y279775D01*
X232150Y283000D01*
G01D02*
X232650Y283500D01*
X236800D01*
G01X185500Y414500D02*
X188000Y417000D01*
Y420750D01*
G01D02*
X184000D01*
G01D02*
X183750Y420500D01*
X179750D01*
G01X220000Y516400D02*
X215400D01*
G01X206499Y514113D02*
X211137D01*
X212000Y513250D01*
G01D02*
X212250D01*
X215400Y516400D01*
G01X180249Y564050D02*
X177999Y561800D01*
Y559300D01*
G01D02*
X183149D01*
G01D02*
Y556450D01*
X183499Y556100D01*
G01X188000Y484500D02*
X186707Y485793D01*
X183499D01*
G01X193549Y564525D02*
X194499Y563575D01*
Y558550D01*
X193999Y558050D01*
G01X186649Y559300D02*
X187899Y558050D01*
X193999D01*
G01X186049Y568400D02*
X186699Y569050D01*
X199652D01*
X200417Y569815D01*
G01X180249Y568050D02*
X185699D01*
X186049Y568400D01*
G01X180249Y572050D02*
Y568050D01*
G01X221499Y687550D02*
Y667901D01*
X227900Y661500D01*
X234600D01*
X263650Y690550D01*
X325999D01*
X350499Y715050D01*
G01X213299Y693800D02*
X216999D01*
G01X221499Y693550D02*
X226249D01*
G01D02*
Y689501D01*
X226250Y689500D01*
G01X216999Y693800D02*
X221249D01*
X221499Y693550D01*
G01X254499Y701550D02*
Y697700D01*
G01X244000Y689900D02*
Y682500D01*
G01D02*
Y681150D01*
X239950Y677100D01*
G01D02*
X240000Y676700D01*
Y670300D01*
X239300Y669600D01*
G01X239950Y677100D02*
X239100Y676250D01*
X230900D01*
G01X234775Y683750D02*
Y690377D01*
X234500Y690652D01*
G01X229750Y689500D02*
X230902Y690652D01*
X234500D01*
G01X237499Y900050D02*
Y827499D01*
X218500Y808500D01*
X192000D01*
X186499Y814001D01*
Y830200D01*
X186100Y830599D01*
Y837391D01*
X186499Y837790D01*
Y841863D01*
X185999Y842363D01*
G01X211750Y894600D02*
X208950Y891800D01*
X208559D01*
G01X209999Y898263D02*
X211750Y896512D01*
Y894600D01*
G01X205999Y891800D02*
Y898263D01*
G01X181799Y831553D02*
X183056D01*
X184518Y833015D01*
Y837771D01*
X184502Y837787D01*
Y840866D01*
X185999Y842363D01*
G01X217500Y812500D02*
X212500D01*
G01X198499Y828613D02*
X203500Y823612D01*
Y822750D01*
G01D02*
X204000D01*
X207500Y819250D01*
G01X211500D02*
Y813500D01*
X212500Y812500D01*
G01X207500Y819250D02*
X211500D01*
G01X189199Y834113D02*
X190756D01*
X192184Y832684D01*
Y825432D01*
X191936Y825184D01*
G01X195350Y823000D02*
X194120D01*
X191936Y825184D01*
G01X203500Y812500D02*
Y819250D01*
G01X190499Y842363D02*
X189199Y841063D01*
Y836673D01*
G01X199500Y819132D02*
X198850Y819782D01*
Y823000D01*
G01D02*
X198500D01*
X194000Y827500D01*
Y835110D01*
X192437Y836673D01*
X189199D01*
G01X203500Y819250D02*
X203303Y819053D01*
X199579D01*
X199500Y819132D01*
G01X188499Y982050D02*
X187999Y981550D01*
Y974050D01*
X186049Y972100D01*
G01X179999Y972550D02*
X180449Y972100D01*
X186049D01*
G01X179999Y976550D02*
Y972550D01*
G01X205999Y898263D02*
X204300D01*
X202637Y896600D01*
X200799D01*
G01X237499Y900050D02*
Y906751D01*
X236000Y908250D01*
G01D02*
X231637Y912613D01*
X229999D01*
G01X183649Y963100D02*
X182099Y961550D01*
X178999D01*
G01X180249Y967550D02*
X183649Y964150D01*
Y963100D01*
G01X193549Y962550D02*
Y968225D01*
G01X187149Y963100D02*
X187699Y962550D01*
X193549D01*
G01X183900Y944500D02*
Y937100D01*
G01D02*
X183850Y937050D01*
Y931600D01*
G01X183900Y925750D02*
X184100Y925500D01*
X194800D01*
G01X183850Y931600D02*
X183900Y931550D01*
Y925750D01*
G01X217500Y1084000D02*
Y1071181D01*
X219381Y1069300D01*
X221800D01*
G01X212600Y1089961D02*
X217461D01*
G01X224500Y1082500D02*
Y1084105D01*
X225300Y1084905D01*
Y1085050D01*
X226800Y1086550D01*
G01D02*
X226400D01*
X222900Y1090050D01*
G01D02*
X218699D01*
X218610Y1089961D01*
X217461D01*
G01D02*
X217500Y1090000D01*
G01X251500Y1136700D02*
X251450Y1136650D01*
X247299D01*
G01X227028Y1071148D02*
X227440Y1071560D01*
X234600D01*
G01D02*
X242000D01*
G01X241500Y1085625D02*
Y1081500D01*
X244300Y1078700D01*
X247300D01*
X247500Y1078500D01*
G01D02*
Y1075500D01*
X243560Y1071560D01*
X242000D01*
G01X234000Y1089500D02*
Y1088500D01*
X228000Y1082500D01*
G01D02*
X227600Y1082100D01*
Y1081500D01*
X224600Y1078500D01*
X223700D01*
G01X191249Y1377050D02*
X188887Y1379412D01*
Y1380379D01*
X186866Y1382400D01*
X186000D01*
G01X216499Y1377550D02*
X215749Y1376800D01*
X200549D01*
G01X194749Y1377050D02*
X200299D01*
X200549Y1376800D01*
G01X194749Y1381050D02*
Y1377050D01*
G01X191249Y1373050D02*
Y1368300D01*
X190499Y1367550D01*
G01X199149Y1362900D02*
Y1360200D01*
X197999Y1359050D01*
G01X199149Y1367400D02*
Y1362900D01*
G01X194749Y1373050D02*
Y1371800D01*
X199149Y1367400D01*
G01X202649D02*
X203499Y1366550D01*
X208999D01*
G01X208049Y1372925D02*
X208999Y1371975D01*
Y1366550D01*
G01X220999Y1497550D02*
Y1488769D01*
X220200Y1487970D01*
Y1486230D01*
X220700Y1485730D01*
Y1473799D01*
X229849Y1464650D01*
X282699D01*
X293999Y1475950D01*
X343699D01*
G01X211914Y1504015D02*
X212129Y1503800D01*
X216999D01*
G01X220999Y1503550D02*
X221249D01*
X225499Y1499300D01*
G01D02*
X229650D01*
G01X216999Y1503800D02*
X220749D01*
X220999Y1503550D01*
G01X261999Y1516050D02*
X258999Y1513050D01*
X252999D01*
G01X241000Y1475800D02*
X233600D01*
G01X223501Y1487433D02*
X224984Y1485950D01*
X232700D01*
G01D02*
X228250Y1481500D01*
Y1480100D01*
G01D02*
Y1478950D01*
X231400Y1475800D01*
X233600D01*
G01X236575Y1493450D02*
Y1495875D01*
X233150Y1499300D01*
G01D02*
X233300Y1499400D01*
X242700D01*
G01X184000Y1695000D02*
X216600Y1662400D01*
Y1635100D01*
X212113Y1630613D01*
X198799D01*
G01D02*
Y1627701D01*
X199500Y1627000D01*
G01X179999Y1647867D02*
Y1644500D01*
G01X178500Y1697750D02*
X181250D01*
X184000Y1695000D01*
G01X188499Y1640613D02*
X195000D01*
G01D02*
X198363D01*
X199000Y1641250D01*
G01X206750Y1649500D02*
Y1652250D01*
X210000Y1655500D01*
G01X203000Y1641250D02*
X203250D01*
X206750Y1644750D01*
Y1649500D01*
G01X199000Y1641250D02*
X203000D01*
G01X197500Y1650000D02*
Y1650050D01*
X196500Y1651050D01*
X192800D01*
G01D02*
X192177Y1650427D01*
X187399D01*
G01X201000Y1655500D02*
X203250Y1653250D01*
Y1649500D01*
G01X192800Y1654550D02*
X191237Y1652987D01*
X187399D01*
G01X192800Y1658800D02*
Y1654550D01*
G01D02*
X193750Y1655500D01*
X201000D01*
G01X203250Y1649500D02*
Y1646500D01*
X202250Y1645500D01*
G01X186549Y1782500D02*
X198949D01*
X201199Y1784750D01*
X201499D01*
G01X180814Y1782613D02*
X180927Y1782500D01*
X186549D01*
G01X180814Y1786613D02*
Y1782613D01*
G01X182649Y1773200D02*
Y1770400D01*
X184999Y1768050D01*
X194999D01*
X200499Y1773550D01*
Y1780050D01*
X201499Y1781050D01*
G01X180814Y1778613D02*
Y1775035D01*
X182649Y1773200D01*
G01X194049Y1778625D02*
Y1772600D01*
X192999Y1771550D01*
G01X186149Y1773200D02*
X187799Y1771550D01*
X192999D01*
G01X227814Y1891113D02*
Y1887513D01*
G01X218100Y1880400D02*
X225500D01*
G01D02*
X230950D01*
X231000Y1880450D01*
G01X240100D02*
Y1875000D01*
G01X231000Y1880450D02*
X240100D01*
G01X243975Y1887950D02*
X243800Y1888100D01*
Y1894834D01*
X245249Y1896283D01*
G01X236100Y1893850D02*
X242000Y1887950D01*
X243975D01*
G01X218499Y1897050D02*
X223371D01*
X223436Y1897115D01*
G01X227814Y1897113D02*
X232064D01*
X232314Y1897363D01*
G01X223436Y1897115D02*
X227812D01*
X227814Y1897113D01*
G01X232314Y1897363D02*
X232327Y1897350D01*
X236100D01*
G01X257499Y1911050D02*
Y1915469D01*
X255777Y1917191D01*
G01X253500Y1911250D02*
X257299D01*
X257499Y1911050D01*
G01X341499Y63050D02*
X342499D01*
X343999Y64550D01*
X347749D01*
G01X337749Y63050D02*
X341499D01*
G01X282800Y87500D02*
X283937Y86363D01*
X287100D01*
G01D02*
X292999D01*
G01X297499Y86613D02*
X302249D01*
G01D02*
Y90699D01*
X302250Y90700D01*
G01X292999Y86363D02*
X293249Y86613D01*
X297499D01*
G01Y92613D02*
Y97550D01*
G01X341499Y67110D02*
X347749D01*
G01X337749Y67050D02*
X341439D01*
X341499Y67110D01*
G01X324800Y94900D02*
X317400D01*
G01X307300Y113300D02*
Y105800D01*
X307000Y105150D01*
G01D02*
X307050Y105200D01*
X316150D01*
G01D02*
X313600Y102650D01*
Y96500D01*
X315200Y94900D01*
X317400D01*
G01X303125Y97650D02*
X302800Y98700D01*
X299600Y101900D01*
X295500D01*
G01X305750Y90700D02*
X303125Y93325D01*
Y97650D01*
G01X293999Y293550D02*
X292999Y294550D01*
Y317050D01*
X287899Y322150D01*
X280899D01*
X278939Y324110D01*
Y327300D01*
G01X326499Y334054D02*
X321748D01*
G01X329748Y333114D02*
X328808Y334054D01*
X326499D01*
G01X305249Y339050D02*
Y343550D01*
G01Y334050D02*
Y339050D01*
G01Y343550D02*
X304845Y343954D01*
X302454D01*
X299000Y340500D01*
G01X284999Y338650D02*
Y338050D01*
X284059Y337110D01*
Y333800D01*
G01X284999Y341800D02*
Y338650D01*
G01X281499Y338550D02*
Y333800D01*
G01X280499Y341800D02*
X281499Y340800D01*
Y338550D01*
G01X326499Y337454D02*
X325659Y336614D01*
X321748D01*
G01X329748Y337114D02*
X329408Y337454D01*
X326499D01*
G01X308749Y343550D02*
X310526D01*
X312912Y345936D01*
G01X318499Y352350D02*
Y349650D01*
X314849Y346000D01*
X314064D01*
X314000Y345936D01*
X312912D01*
G01X327500Y354750D02*
X325100Y352350D01*
X321059D01*
G01X301249Y346050D02*
X302913Y347714D01*
X305999D01*
X309398Y351113D01*
Y355199D01*
X310249Y356050D01*
G01D02*
X319999D01*
X321059Y354990D01*
Y352350D01*
G01X302000Y373000D02*
X302750Y373750D01*
X307000D01*
G01X299999Y366050D02*
X300000Y366051D01*
Y371000D01*
X302000Y373000D01*
G01X315000Y373750D02*
X317000Y375750D01*
Y380000D01*
G01X307000Y373750D02*
X311000D01*
G01D02*
X315000D01*
G01X308749Y339050D02*
X308873Y339174D01*
X315248D01*
G01D02*
Y342399D01*
X318652Y345803D01*
Y345850D01*
X319102Y346300D01*
G01X324644Y367083D02*
X319983D01*
X318450Y365550D01*
Y365200D01*
G01D02*
X318499Y365151D01*
Y359750D01*
G01X326000Y380000D02*
Y378500D01*
X320500Y373000D01*
G01X310249Y360050D02*
X310549Y359750D01*
X315939D01*
G01D02*
Y364211D01*
X314950Y365200D01*
G01D02*
Y370200D01*
X315000Y370250D01*
G01D02*
X317750D01*
X320500Y373000D01*
G01X279939Y733800D02*
Y728610D01*
G01X327999Y740550D02*
X327559Y740990D01*
X323249D01*
G01X331249Y741050D02*
X328499D01*
X327999Y740550D01*
G01X306749Y746050D02*
Y750050D01*
G01Y742050D02*
Y746050D01*
G01Y750050D02*
X301799D01*
X301099Y750750D01*
G01X285499Y745050D02*
X285059Y744610D01*
Y740300D01*
G01X285499Y748300D02*
Y745050D01*
G01X282099D02*
X282499Y744650D01*
Y740300D01*
G01X281499Y748300D02*
Y745650D01*
X282099Y745050D01*
G01X331249D02*
Y749050D01*
X330249Y750050D01*
G01D02*
X328999D01*
X327749Y748800D01*
Y744050D01*
G01D02*
X327599D01*
X327099Y743550D01*
X323249D01*
G01X319499Y759350D02*
Y753050D01*
X318499Y752050D01*
G01X310249Y750050D02*
X316499D01*
X318499Y752050D01*
G01X322059Y759350D02*
Y761990D01*
X321499Y762550D01*
X311249D01*
G01D02*
X311000Y762301D01*
Y758250D01*
G01D02*
Y758050D01*
X306500Y753550D01*
G01X304000Y785500D02*
X310500D01*
G01D02*
X312250Y783750D01*
Y779000D01*
G01D02*
Y776000D01*
X311000Y774750D01*
G01D02*
X307000D01*
G01D02*
X306770D01*
X304570Y772550D01*
X300999D01*
G01X310249Y746050D02*
X316689D01*
X316749Y746110D01*
G01D02*
X317059D01*
X320849Y749900D01*
Y750005D01*
X323894Y753050D01*
X324499D01*
G01X323500Y772300D02*
X319550D01*
X319450Y772200D01*
G01D02*
X319499Y772151D01*
Y766750D01*
G01X311249Y767050D02*
X311549Y766750D01*
X316939D01*
G01X325000Y785500D02*
X319500D01*
G01D02*
X315750Y781750D01*
Y779000D01*
G01X315950Y772200D02*
X316939Y771211D01*
Y766750D01*
G01X315750Y779000D02*
Y772400D01*
X315950Y772200D01*
G01X283499Y1556050D02*
X284059Y1555490D01*
Y1551300D01*
G01X282499Y1559300D02*
Y1557050D01*
X283499Y1556050D01*
G01X279999D02*
X281499Y1554550D01*
Y1551300D01*
G01X278499Y1559300D02*
Y1557550D01*
X279999Y1556050D01*
G01X303249Y1558550D02*
Y1554550D01*
G01D02*
Y1550800D01*
X304499Y1549550D01*
G01X326500Y1550200D02*
X327749Y1551449D01*
Y1553550D01*
G01D02*
X326809Y1554490D01*
X319749D01*
G01X295000Y1513000D02*
Y1521000D01*
X278999Y1537001D01*
Y1544740D01*
X278939Y1544800D01*
G01X313249Y1559610D02*
X313939D01*
X316499Y1557050D01*
Y1550050D01*
X317499Y1549050D01*
G01X303249Y1562550D02*
Y1558550D01*
G01X330300Y1561200D02*
X327749Y1558649D01*
Y1557550D01*
G01D02*
X327249Y1557050D01*
X319749D01*
G01X328600Y1566100D02*
X319700D01*
X318499Y1567301D01*
G01Y1569850D02*
Y1567301D01*
G01D02*
Y1566599D01*
X315750Y1563850D01*
X308049D01*
X306749Y1562550D01*
G01X327000Y1570750D02*
X326100Y1569850D01*
X321059D01*
G01D02*
Y1573090D01*
X320659Y1573490D01*
X310689D01*
X310249Y1573050D01*
G01D02*
Y1569800D01*
G01X304000Y1597000D02*
X310500D01*
G01D02*
X312750Y1594750D01*
Y1591000D01*
G01D02*
Y1588500D01*
X310500Y1586250D01*
G01D02*
X306500D01*
G01D02*
X302699D01*
X299999Y1583550D01*
G01X306749Y1558550D02*
X309499D01*
X310559Y1559610D01*
X313249D01*
G01X318499Y1577250D02*
Y1582551D01*
X318450Y1582600D01*
G01D02*
X323000D01*
G01X324500Y1597000D02*
X319500D01*
G01X315939Y1577250D02*
Y1581611D01*
X314950Y1582600D01*
G01D02*
X314750Y1582800D01*
Y1587000D01*
G01D02*
Y1589500D01*
X316250Y1591000D01*
G01D02*
Y1593750D01*
X319500Y1597000D01*
G01X331622Y1944767D02*
X331204Y1944349D01*
X326971D01*
G01X335971Y1943409D02*
X334499D01*
X333141Y1944767D01*
X331622D01*
G01X288709Y1948042D02*
Y1942700D01*
G01X288358Y1951578D02*
Y1948393D01*
X288709Y1948042D01*
G01X284358Y1951578D02*
X280027D01*
X278999Y1950550D01*
G01D02*
X281858Y1947691D01*
X284999D01*
G01D02*
X286149Y1946541D01*
Y1942700D01*
G01X306199Y1937010D02*
Y1938250D01*
X307999Y1940050D01*
Y1941050D01*
X310471Y1943522D01*
Y1944909D01*
G01Y1948909D02*
X310108Y1949272D01*
Y1953328D01*
G01X310471Y1944909D02*
Y1948909D01*
G01X335971Y1947409D02*
X335520Y1947860D01*
Y1953650D01*
G01D02*
X332103Y1950233D01*
Y1948133D01*
G01D02*
X330879Y1946909D01*
X326971D01*
G01X313608Y1953328D02*
X318328D01*
X319500Y1954500D01*
G01X321640Y1959072D02*
Y1956640D01*
X319500Y1954500D01*
G01X313527Y1962191D02*
X315264D01*
X315474Y1961981D01*
X323209D01*
X324200Y1960990D01*
Y1959072D01*
G01X329500Y1956500D02*
X326928Y1959072D01*
X324200D01*
G01X313527Y1962191D02*
Y1960078D01*
X310499Y1957050D01*
G01X285499Y1930050D02*
X283589Y1931960D01*
Y1936200D01*
G01X323999Y1938550D02*
X323700Y1938849D01*
Y1947849D01*
X322080Y1949469D01*
X320471D01*
G01X313971Y1948909D02*
X316999D01*
X317559Y1949469D01*
X320471D01*
G01X321650Y1971900D02*
X321640Y1971890D01*
Y1966472D01*
G01X330000Y1962500D02*
X328900Y1963600D01*
X323880D01*
X323861Y1963619D01*
X320381D01*
X319080Y1964920D01*
Y1966472D01*
G01X330000Y1962500D02*
X336000D01*
G01X318150Y1971900D02*
X319080Y1970970D01*
Y1966472D01*
G01X313527Y1966191D02*
X313500Y1966218D01*
Y1970250D01*
G01D02*
X315150Y1971900D01*
X318150D01*
G01X299777Y1976191D02*
X305682D01*
X305691Y1976200D01*
G01D02*
X306926D01*
X309300Y1973826D01*
G01X313500Y1973750D02*
X314250Y1974500D01*
X328750D01*
X330000Y1973250D01*
G01D02*
X331750Y1971500D01*
X336000D01*
G01X309300Y1973826D02*
X313424D01*
X313500Y1973750D01*
G01X325500Y1971500D02*
X325000Y1972000D01*
X321800D01*
X321650Y1971900D01*
G01X404249Y56050D02*
X407999D01*
X409999Y54050D01*
G01X404249Y51050D02*
X406999D01*
X409999Y54050D01*
G01X399999Y42800D02*
X405249D01*
X406499Y44050D01*
Y48050D01*
X404249Y50300D01*
Y51050D01*
G01X381999Y57050D02*
X382939Y56110D01*
X387749D01*
G01X378749Y57050D02*
X381999D01*
G01Y53550D02*
X387749D01*
G01X378749Y53050D02*
X379249Y53550D01*
X381999D01*
G01X394199Y39050D02*
X399749D01*
X399999Y39300D01*
G01D02*
X404499D01*
G01X394199Y45050D02*
Y41610D01*
G01X386749Y26050D02*
X389499D01*
X390499Y27050D01*
Y41050D01*
X391059Y41610D01*
X394199D01*
G01X360000Y53000D02*
X359000Y52000D01*
Y47500D01*
G01D02*
X360250Y46250D01*
X363000D01*
G01X370750Y46500D02*
X371000Y46250D01*
Y37500D01*
X371950Y36550D01*
X376499D01*
G01X363000Y46250D02*
X367000D01*
G01D02*
X367250Y46500D01*
X370750D01*
G01X361616Y58933D02*
X358999Y61550D01*
G01D02*
X358559Y61990D01*
X354249D01*
G01X394249Y50990D02*
X400689D01*
X400749Y51050D01*
G01D02*
Y48800D01*
X402999Y46550D01*
G01X381500Y46000D02*
X378850Y43350D01*
Y42300D01*
G01D02*
X380700D01*
X383950Y39050D01*
X386799D01*
G01X386749Y30550D02*
X386799Y30600D01*
Y36490D01*
G01X375350Y42300D02*
X374250Y43400D01*
Y46500D01*
G01X375350Y42300D02*
X377750Y39900D01*
X380600D01*
X384010Y36490D01*
X386799D01*
G01X374250Y46500D02*
Y47750D01*
X369000Y53000D01*
G01X377500Y49000D02*
X376750D01*
X374250Y46500D01*
G01X371700Y85500D02*
X370950Y86250D01*
X366500D01*
G01D02*
X366200Y86550D01*
X360999D01*
G01X402499Y1476850D02*
X401599Y1475950D01*
X343699D01*
G01X682699Y1812604D02*
X674740D01*
X673249Y1814095D01*
Y1820673D01*
X677810Y1825234D01*
X681549D01*
G01X666399Y1814569D02*
Y1820784D01*
X664549Y1822634D01*
X661549D01*
G01X655549Y1818884D02*
X659299Y1822634D01*
X661549D01*
G01X651299Y1818634D02*
X651549Y1818884D01*
X655549D01*
G01X649049Y1810884D02*
X654799D01*
X655049Y1810634D01*
G01X666399Y1812604D02*
X666369Y1812634D01*
X657049D01*
X655049Y1810634D01*
G01X785999Y285550D02*
X771097D01*
X762844Y293803D01*
X762817D01*
X761752Y294868D01*
Y294896D01*
X755825Y300823D01*
X742700Y323900D01*
Y341450D01*
X749500Y348250D01*
G01X746999Y325550D02*
X748625Y323924D01*
X751228D01*
G01Y328924D02*
X747576D01*
X745500Y331000D01*
Y334500D01*
X747000Y336000D01*
X752652D01*
X752978Y335674D01*
G01X751228Y323924D02*
Y328924D01*
G01X758778Y339424D02*
X753228D01*
X752978Y339174D01*
G01D02*
Y343529D01*
X752999Y343550D01*
G01X758778Y336864D02*
X761364D01*
X762000Y337500D01*
Y344500D01*
X758250Y348250D01*
X749500D01*
G01X748000Y333000D02*
X751549D01*
X754728Y329821D01*
Y328924D01*
G01D02*
X761168D01*
X761228Y328984D01*
G01X753000Y362500D02*
X757250Y358250D01*
Y355500D01*
G01Y351500D02*
X758500D01*
X761500Y348500D01*
G01X757250Y355500D02*
Y351500D01*
G01X749946Y724882D02*
X745864D01*
X745696Y725050D01*
G01X749946Y729882D02*
X745696Y725632D01*
Y725050D01*
G01X776999Y690050D02*
X751999D01*
X742000Y700049D01*
Y743000D01*
X746750Y747750D01*
X750500D01*
G01X749946Y729882D02*
X746618D01*
X745000Y731500D01*
Y734800D01*
X746081Y735881D01*
X748378D01*
X748397Y735862D01*
X750466D01*
X751196Y735132D01*
G01Y738632D02*
X749417D01*
X746999Y741050D01*
G01X756996Y739882D02*
X755474D01*
X752306Y743050D01*
X748499D01*
X746999Y741550D01*
Y741050D01*
G01X756996Y737322D02*
X759422D01*
X759822Y737722D01*
Y746178D01*
X758250Y747750D01*
X750500D01*
G01X747500Y733762D02*
X749484D01*
X753196Y730050D01*
X753446Y729882D01*
G01D02*
X753506Y729942D01*
X760446D01*
G01X756000Y761500D02*
X758250Y759250D01*
Y755000D01*
G01X750583Y1126392D02*
X748257D01*
X745599Y1129050D01*
G01X750583Y1131392D02*
X747941D01*
X745599Y1129050D01*
G01X751499Y1140300D02*
X750583Y1139384D01*
Y1131392D01*
G01X751499Y1143800D02*
X748250D01*
X747000Y1142550D01*
G01X747500Y1151750D02*
X757050D01*
X759499Y1149301D01*
Y1147727D01*
X759518Y1147708D01*
Y1142952D01*
X759499Y1142933D01*
Y1141999D01*
X758990Y1141490D01*
X756799D01*
G01X747500Y1151750D02*
X743100Y1147350D01*
Y1102969D01*
X761019Y1085050D01*
X781999D01*
G01X754083Y1131392D02*
Y1135914D01*
X754151Y1135982D01*
G01X760583Y1131452D02*
Y1134466D01*
X759067Y1135982D01*
X754151D01*
G01X756799Y1144050D02*
X751749D01*
X751499Y1143800D01*
G01X752900Y1164800D02*
X755250Y1162450D01*
Y1158500D01*
G01Y1154500D02*
X758898D01*
X761998Y1151400D01*
G01X755250Y1158500D02*
Y1154500D01*
G01X753577Y1536296D02*
X751704D01*
X749300Y1538700D01*
Y1540900D01*
X751946Y1543546D01*
X753827D01*
G01X745600Y1531296D02*
X753577D01*
G01D02*
Y1536296D01*
G01X759127Y1546796D02*
X754077D01*
X753827Y1547046D01*
G01D02*
X751046D01*
X750000Y1546000D01*
G01X759127Y1544236D02*
X761520D01*
X762520Y1545236D01*
Y1550980D01*
X759750Y1553750D01*
X751000D01*
G01D02*
X744250D01*
X740999Y1550499D01*
Y1509550D01*
X757999Y1492550D01*
X791499D01*
G01X763577Y1536356D02*
X757137D01*
X757077Y1536296D01*
G01D02*
Y1537223D01*
X754328Y1539972D01*
X752099D01*
G01X755500Y1568000D02*
X758750Y1564750D01*
Y1561000D01*
G01X739799Y1806634D02*
X736099Y1802934D01*
X732549D01*
G01X739799Y1798634D02*
X738049Y1796884D01*
Y1793884D01*
G01D02*
X739049D01*
X744049Y1798884D01*
G01D02*
X746799D01*
X748049Y1800134D01*
Y1802634D01*
X749269Y1803854D01*
X753949D01*
G01X739799Y1814134D02*
Y1816634D01*
X741549Y1818384D01*
G01D02*
X742299D01*
X744049Y1816634D01*
Y1813884D01*
G01D02*
X745299Y1812634D01*
X748549D01*
X752209Y1808974D01*
X753949D01*
G01Y1806414D02*
X744079D01*
X744049Y1806384D01*
G01D02*
X740049D01*
X739799Y1806634D01*
G01X697299Y1821634D02*
X698665Y1823000D01*
X710761D01*
X711652Y1822109D01*
G01X697299Y1825634D02*
X698032Y1824901D01*
X711245D01*
X711848Y1825504D01*
G01X693799Y1825634D02*
X693399Y1825234D01*
X681549D01*
G01X693799Y1821634D02*
X693099Y1822334D01*
X687049D01*
G01X682699Y1814569D02*
X676080D01*
X675149Y1815500D01*
Y1819885D01*
X677598Y1822334D01*
X687049D01*
G01X750064Y1942213D02*
Y1937713D01*
G01D02*
Y1933615D01*
X749499Y1933050D01*
G01X751000Y1947250D02*
X744150D01*
X743600Y1946700D01*
Y1943400D01*
X744250Y1942750D01*
X749527D01*
X750064Y1942213D01*
G01X757114Y1952213D02*
X752463D01*
X751000Y1950750D01*
G01D02*
X748750D01*
X746000Y1953500D01*
G01X790499Y1899550D02*
X767480D01*
X754649Y1912381D01*
X754622D01*
X753381Y1913622D01*
Y1913649D01*
X741900Y1925130D01*
Y1955247D01*
X744903Y1958250D01*
X749500D01*
G01D02*
X757683D01*
X757702Y1958231D01*
X757728D01*
X759626Y1956333D01*
X760328Y1955632D01*
Y1955605D01*
X760347Y1955586D01*
Y1950053D01*
X759947Y1949653D01*
X757114D01*
G01X746149Y1945000D02*
X746649Y1944500D01*
X751348D01*
X753564Y1942284D01*
Y1942213D01*
G01D02*
X760004D01*
X760064Y1942273D01*
G01X756000Y1972000D02*
X757250Y1970750D01*
Y1965000D01*
G01D02*
Y1961000D01*
G01D02*
X758381Y1959869D01*
X758407D01*
X760082Y1958194D01*
X761966Y1956311D01*
Y1956284D01*
X763477Y1954773D01*
X764514D01*
G01X840499Y182550D02*
X831999D01*
X830453Y181004D01*
Y176949D01*
G01X831749Y167050D02*
X830452Y168347D01*
Y171300D01*
X830453Y171301D01*
Y176949D01*
G01X831499Y162800D02*
X831749Y163050D01*
Y167050D01*
G01X817999Y182050D02*
X826499D01*
X827893Y180656D01*
Y176949D01*
G01X824249Y167050D02*
Y168800D01*
X827893Y172444D01*
Y176949D01*
G01X823999Y162800D02*
Y166800D01*
X824249Y167050D01*
G01X825333Y176949D02*
X825320Y176936D01*
X821885D01*
X818013Y173064D01*
G01X816749Y167050D02*
Y171800D01*
X818013Y173064D01*
G01X816499Y162800D02*
Y166800D01*
X816749Y167050D01*
G01X827893Y193129D02*
X827892Y193130D01*
Y197157D01*
X825499Y199550D01*
Y204050D01*
X824499Y205050D01*
G01X829499Y208300D02*
Y211458D01*
X827774Y213183D01*
G01X829917Y216200D02*
X827774Y214057D01*
Y213183D01*
G01X833999Y208300D02*
Y210662D01*
X836499Y213162D01*
G01X833576Y215432D02*
X834167D01*
X836437Y213162D01*
X836499D01*
G01X838299Y204800D02*
X833999D01*
G01D02*
X833013Y203814D01*
Y193129D01*
G01X829499Y204800D02*
X829999Y204300D01*
Y200550D01*
G01X830453Y193129D02*
Y200096D01*
X829999Y200550D01*
G01X927649Y158500D02*
Y156900D01*
X928749Y155800D01*
X939477D01*
X948999Y165322D01*
Y169120D01*
X940544Y177575D01*
X940474D01*
X936499Y181550D01*
X910999D01*
X894499Y198050D01*
X861999D01*
X840499Y219550D01*
X837999D01*
G01X785999Y285550D02*
X815800D01*
X816500Y286250D01*
G01D02*
Y305309D01*
X818662Y307471D01*
X822873D01*
G01X814700Y267500D02*
X822100D01*
G01D02*
X827450D01*
X827500Y267450D01*
G01X836700D02*
Y261100D01*
X836600Y261000D01*
G01X827500Y267450D02*
X836700D01*
G01X791499Y333050D02*
X790559Y332110D01*
Y327800D01*
G01X797249Y332050D02*
X796249Y333050D01*
X791499D01*
G01X789999Y336550D02*
X787999Y334550D01*
Y327800D01*
G01X797249Y336050D02*
X796249Y337050D01*
X790499D01*
X789999Y336550D01*
G01X772499Y323050D02*
X771685Y323864D01*
X767728D01*
G01X776249Y322550D02*
X772999D01*
X772499Y323050D01*
G01X772873Y326924D02*
X772373Y326424D01*
X767728D01*
G01X776249Y326550D02*
X773247D01*
X772873Y326924D01*
G01X769000Y347500D02*
Y352250D01*
G01X777978Y341924D02*
X774576D01*
X769000Y347500D01*
G01X760750Y355500D02*
Y361250D01*
X762000Y362500D01*
G01X765000Y352250D02*
X764000D01*
X760750Y355500D01*
G01X769000Y352250D02*
X765000D01*
G01X780499Y330050D02*
X781999D01*
X782999Y329050D01*
Y323050D01*
X784749Y321300D01*
X785439D01*
G01X774000Y333500D02*
Y333550D01*
X771500Y336050D01*
Y337750D01*
G01D02*
X769826Y339424D01*
X766178D01*
G01X771500Y341250D02*
X770766Y341984D01*
X766178D01*
G01D02*
Y343822D01*
X761500Y348500D01*
G01X788999Y736050D02*
X787499Y734550D01*
Y728800D01*
G01X791999Y733050D02*
X790059Y731110D01*
Y728800D01*
G01X771105Y722789D02*
X769072Y724822D01*
X766946D01*
G01X774249Y724050D02*
X772366D01*
X771105Y722789D01*
G01X769999Y733050D02*
X774249Y728800D01*
Y728550D01*
G01D02*
X773081Y727382D01*
X766946D01*
G01X776999Y690050D02*
X809300D01*
X810000Y690750D01*
G01D02*
Y705551D01*
X816302Y711853D01*
X820831D01*
G01X781999Y725550D02*
X784939Y722610D01*
Y722300D01*
G01X813200Y670100D02*
X820600D01*
G01D02*
X826050D01*
X826100Y670150D01*
G01X835300D02*
Y663200D01*
G01X826100Y670150D02*
X835300D01*
G01X839175Y677650D02*
X844400D01*
X844450Y677700D01*
G01X795749Y736050D02*
X788999D01*
G01X795749Y732050D02*
X794249Y733550D01*
X792499D01*
X791999Y733050D01*
G01X770000Y751250D02*
Y746000D01*
X773618Y742382D01*
X776696D01*
G01X779500Y736000D02*
X776696Y738804D01*
Y742382D01*
G01X765000Y761500D02*
X761750Y758250D01*
Y755000D01*
G01D02*
Y752750D01*
X763250Y751250D01*
X766000D01*
G01D02*
X770000D01*
G01X774500Y733000D02*
X773500Y734000D01*
X773250D01*
X770000Y737250D01*
Y738750D01*
G01D02*
X768868Y739882D01*
X764396D01*
G01X770000Y742250D02*
X769808Y742442D01*
X764396D01*
G01D02*
Y744604D01*
X761500Y747500D01*
G01X758250Y751000D02*
Y750750D01*
X761500Y747500D01*
G01X758250Y755000D02*
Y751000D01*
G01X792154Y1135926D02*
X790375D01*
X789559Y1135110D01*
Y1131800D01*
G01X795749Y1133050D02*
Y1133800D01*
X793623Y1135926D01*
X792154D01*
G01X771999Y1124550D02*
X770217Y1126332D01*
X767083D01*
G01X775249Y1123550D02*
X772999D01*
X771999Y1124550D01*
G01X772499Y1130050D02*
X771341Y1128892D01*
X767083D01*
G01X775249Y1127550D02*
X774999D01*
X772499Y1130050D01*
G01X820841Y1116216D02*
X818685D01*
X816099Y1113630D01*
Y1094349D01*
X816000Y1094250D01*
G01D02*
X806800Y1085050D01*
X781999D01*
G01X789499Y1138050D02*
X786999Y1135550D01*
Y1131800D01*
G01X795749Y1137050D02*
X794749Y1138050D01*
X789499D01*
G01X779499Y1131050D02*
X784439Y1126110D01*
Y1125300D01*
G01X807499Y1089550D02*
X807977D01*
X814449Y1096022D01*
Y1115949D01*
X821269Y1122769D01*
X834047D01*
X834065Y1122751D01*
X834109D01*
X834760Y1122100D01*
X871099D01*
X873259Y1119941D01*
X878917D01*
X878937Y1119961D01*
G01X812900Y1072900D02*
X820300D01*
G01D02*
X822850D01*
X825700Y1075750D01*
G01X835000D02*
Y1068100D01*
X834500Y1067600D01*
G01X825700Y1075750D02*
X835000D01*
G01X838875Y1083250D02*
X838925Y1083200D01*
X844050D01*
G01X764199Y1144050D02*
X767200D01*
X769500Y1141750D01*
G01D02*
Y1138400D01*
X770000Y1137900D01*
G01X776833Y1143892D02*
X774608D01*
X770000Y1148500D01*
Y1151000D01*
G01X761900Y1164800D02*
X758750Y1161650D01*
Y1158500D01*
G01D02*
X762000Y1155250D01*
X763000D01*
G01D02*
X767000D01*
G01D02*
X767750D01*
X770000Y1153000D01*
Y1151000D01*
G01X769500Y1145250D02*
X768140Y1146610D01*
X764199D01*
G01D02*
Y1149199D01*
X761998Y1151400D01*
G01X836900Y1479050D02*
Y1471400D01*
X836600Y1471100D01*
G01X774542Y1530050D02*
X773356Y1531236D01*
X770077D01*
G01X777431Y1527893D02*
X776699D01*
X774542Y1530050D01*
G01X774577Y1533796D02*
X770077D01*
G01X777431Y1531893D02*
X776480D01*
X774577Y1533796D01*
G01X791499Y1543550D02*
X790253Y1542304D01*
Y1535628D01*
G01X798431Y1542893D02*
X797774Y1543550D01*
X791499D01*
G01X793999Y1541050D02*
X792813Y1539864D01*
Y1535628D01*
G01X798431Y1538893D02*
X796274Y1541050D01*
X793999D01*
G01X822245Y1518722D02*
X817843D01*
X816171Y1517050D01*
Y1497921D01*
X816000Y1497750D01*
G01D02*
X812750D01*
X807550Y1492550D01*
X791499D01*
G01X770500Y1554000D02*
Y1558250D01*
G01X779327Y1548796D02*
X775704D01*
X770500Y1554000D01*
G01X784499Y1529050D02*
X784577Y1529128D01*
X787693D01*
G01X803499Y1496050D02*
X808250D01*
X814117Y1501917D01*
Y1521668D01*
X820399Y1527950D01*
X856619D01*
X857921Y1526648D01*
X863381D01*
X864576Y1525453D01*
X878917D01*
X878937Y1525473D01*
G01X814700Y1480600D02*
X822100D01*
G01D02*
X827650D01*
X827700Y1480650D01*
G01D02*
X829300Y1479050D01*
X836900D01*
G01X774214Y1541656D02*
X772000Y1543870D01*
Y1545750D01*
G01D02*
X770954Y1546796D01*
X766527D01*
G01X763000Y1555000D02*
Y1552883D01*
X766527Y1549356D01*
G01X772000Y1549250D02*
X766633D01*
X766527Y1549356D01*
G01X758750Y1556500D02*
X761600D01*
X763000Y1555100D01*
Y1555000D01*
G01X758750Y1561000D02*
Y1556500D01*
G01X762250Y1561000D02*
Y1565750D01*
X764500Y1568000D01*
G01X766500Y1558250D02*
X764750D01*
X762250Y1560750D01*
Y1561000D01*
G01X770500Y1558250D02*
X766500D01*
G01X833499Y1783800D02*
X829799D01*
X829749Y1783750D01*
X829199D01*
G01D02*
Y1785000D01*
X832249Y1788050D01*
G01D02*
Y1789955D01*
X830612Y1791592D01*
Y1793937D01*
X830452Y1794097D01*
Y1798996D01*
X830453Y1798997D01*
G01X824499Y1783800D02*
X823749Y1783050D01*
X820356D01*
X819599Y1783807D01*
X819593D01*
G01X827893Y1798997D02*
Y1795944D01*
X824749Y1792800D01*
Y1788050D01*
G01D02*
X824644D01*
X822244Y1785650D01*
X821099D01*
X819597Y1784148D01*
Y1783811D01*
X819593Y1783807D01*
G01X825333Y1798997D02*
X819445D01*
X818824Y1798376D01*
X817249Y1796800D01*
Y1793050D01*
G01Y1788050D02*
Y1793050D01*
G01X814999Y1783800D02*
X817249Y1786050D01*
Y1788050D01*
G01X789299Y1804634D02*
X790649Y1803284D01*
X792784D01*
X793000Y1803500D01*
G01X789299Y1800634D02*
X790049Y1801384D01*
X793572D01*
X795849Y1803661D01*
Y1805500D01*
G01X776149Y1803854D02*
X785019D01*
X785799Y1804634D01*
G01D02*
Y1808034D01*
X786699Y1808934D01*
G01X785799Y1795634D02*
Y1800634D01*
G01D02*
X785139Y1801294D01*
X776149D01*
G01X774299Y1817634D02*
X769549D01*
X768549Y1816634D01*
G01X776149Y1806414D02*
X771269D01*
X768549Y1809134D01*
Y1816634D01*
G01X827893Y1815177D02*
X827892Y1815176D01*
Y1810443D01*
X826999Y1809550D01*
X814999D01*
X814499Y1809050D01*
G01X813749Y1821550D02*
X807750D01*
X807000Y1822300D01*
G01X813749Y1825550D02*
X806342D01*
X803500Y1822708D01*
G01X817249Y1825550D02*
X817749Y1825050D01*
X823499D01*
G01X833013Y1815177D02*
Y1818934D01*
X826897Y1825050D01*
X823499D01*
G01X830453Y1815177D02*
Y1818806D01*
X826959Y1822300D01*
X817999D01*
X817249Y1821550D01*
G01D02*
Y1818800D01*
X815499Y1817050D01*
G01X815300Y1885000D02*
X822700D01*
G01X837499Y1876900D02*
Y1884800D01*
G01D02*
X837449Y1884750D01*
X828000D01*
G01D02*
X827750Y1885000D01*
X822700D01*
G01X771499Y1936550D02*
X770896Y1937153D01*
X766564D01*
G01X774749Y1935050D02*
X773499D01*
X771999Y1936550D01*
X771499D01*
G01Y1940050D02*
X771162Y1939713D01*
X766564D01*
G01X774749Y1939050D02*
X772499D01*
X771499Y1940050D01*
G01X790499Y1899550D02*
X809550D01*
X814250Y1904250D01*
X815500D01*
G01D02*
X816000Y1904750D01*
Y1924864D01*
X816501Y1925365D01*
X821436D01*
G01X776814Y1954713D02*
X771787D01*
X770000Y1956500D01*
G01D02*
X769500Y1957000D01*
Y1960250D01*
X769000Y1960750D01*
G01X760750Y1965000D02*
Y1967750D01*
X765000Y1972000D01*
G01Y1960750D02*
X760750Y1965000D01*
G01X769000Y1960750D02*
X765000D01*
G01X792499Y1949050D02*
X788999D01*
X788499Y1948550D01*
Y1942300D01*
G01X796931Y1948393D02*
X793156D01*
X792499Y1949050D01*
G01X794499Y1941050D02*
X793249Y1942300D01*
X791059D01*
G01X796931Y1944393D02*
Y1943482D01*
X794499Y1941050D01*
G01X782999Y1937050D02*
X784249Y1935800D01*
X785939D01*
G01X806499Y1903550D02*
X810101D01*
X813836Y1907285D01*
Y1926887D01*
X820499Y1933550D01*
X865999D01*
X868584Y1930965D01*
X878917D01*
X878937Y1930985D01*
G01X773250Y1944000D02*
Y1946000D01*
X770000Y1949250D01*
G01D02*
Y1949300D01*
X768100Y1951200D01*
Y1951327D01*
X767214Y1952213D01*
X764514D01*
G01Y1954773D02*
X767927D01*
X769950Y1952750D01*
X770000D01*
G01D02*
X772250Y1950500D01*
X774500D01*
X776000Y1949000D01*
G01X916999Y168424D02*
X922478D01*
G01X898544Y163647D02*
X898557Y163634D01*
X910083D01*
X914873Y168424D01*
X916999D01*
G01X922478Y164424D02*
X913373D01*
X909383Y160434D01*
X907499D01*
G01X898544Y160447D02*
X898557Y160434D01*
X907499D01*
G01X892794Y160447D02*
X892781Y160434D01*
X882999D01*
G01X874978Y159924D02*
X875488Y160434D01*
X882999D01*
G01X892794Y163647D02*
X892781Y163634D01*
X886915D01*
X885499Y165050D01*
G01X874978Y163924D02*
X884373D01*
X885499Y165050D01*
G01X853978Y274924D02*
Y269722D01*
X854200Y269500D01*
G01X854400Y264600D02*
X854200Y264800D01*
Y269500D01*
G01X847577Y272131D02*
X849200Y273754D01*
Y276400D01*
X849250Y276800D01*
G01X853978Y280924D02*
X858228D01*
X858478Y281174D01*
G01X849250Y276800D02*
X849228Y276822D01*
Y280924D01*
G01D02*
X853978D01*
G01X878937Y278937D02*
X864187D01*
X861950Y281174D01*
X858478D01*
G01X843700Y312200D02*
X846621Y309279D01*
G03X847478Y308924I857J857D01*
G01X878924D01*
X878937Y308937D01*
G01X840575Y274950D02*
Y273825D01*
X847200Y267200D01*
G01X845750Y276800D02*
X843900Y274950D01*
X840575D01*
G01X898544Y565959D02*
X898543Y565958D01*
Y560506D01*
X899457Y559592D01*
X899685D01*
G01X905196Y562882D02*
X901906Y559592D01*
X899685D01*
G01X886749Y565050D02*
Y560500D01*
G01X894200Y560400D02*
X894251D01*
X895499Y561648D01*
Y567550D01*
X897108Y569159D01*
X898544D01*
G01X902999Y556050D02*
X905999D01*
X906999Y557050D01*
G01X912649Y557800D02*
Y558929D01*
X908696Y562882D01*
G01D02*
Y558747D01*
X906999Y557050D01*
G01X922049Y563025D02*
X921999Y562975D01*
Y557050D01*
G01X916149Y557800D02*
X916899Y557050D01*
X921999D01*
G01X914549Y566900D02*
X916849D01*
X917499Y567550D01*
X926999D01*
X927999Y568550D01*
G01X908696Y566882D02*
X914531D01*
X914549Y566900D01*
G01X908696Y570882D02*
Y566882D01*
G01X892794Y565959D02*
X887658D01*
X886749Y565050D01*
G01X892794Y569159D02*
X888140D01*
X886749Y570550D01*
G01D02*
Y568800D01*
X885499Y567550D01*
X876999D01*
X876806Y567743D01*
X876787D01*
G01X905196Y566882D02*
X902919Y569159D01*
X898544D01*
G01X847200Y672000D02*
X847900Y672700D01*
Y677100D01*
X847950Y677700D01*
G01X852696Y681882D02*
X856946D01*
X857196Y682132D01*
G01X847950Y677700D02*
X847946Y677704D01*
Y681882D01*
G01D02*
X852696D01*
G01X878937Y684449D02*
X864898D01*
X862581Y682132D01*
X857196D01*
G01X852696Y671197D02*
X852700Y671193D01*
Y667500D01*
X852703Y667497D01*
G01X852696Y675882D02*
Y671197D01*
G01X878937Y714449D02*
X867378D01*
X862372Y709443D01*
G02X861665Y709150I-707J706D01*
G01X845350D01*
X841500Y713000D01*
G01X844450Y677700D02*
X844700Y677450D01*
Y667200D01*
X846400Y665500D01*
G01X929499Y971100D02*
X914549D01*
G01X908583Y970392D02*
X913841D01*
X914549Y971100D01*
G01X908583Y974392D02*
Y970392D01*
G01X898544Y971471D02*
X900004D01*
X905083Y966392D01*
G01D02*
Y962966D01*
X905999Y962050D01*
G01X892794Y971471D02*
X892781Y971458D01*
X887017D01*
X886583Y971892D01*
G01D02*
Y967600D01*
G01X877499Y977050D02*
X881499Y981050D01*
X884999D01*
X886583Y979466D01*
Y975892D01*
G01D02*
X891573D01*
X892794Y974671D01*
G01X905083Y970392D02*
X900804Y974671D01*
X898544D01*
G01D02*
X896120D01*
X895499Y974050D01*
Y963550D01*
X894999Y963050D01*
G01X913149Y962100D02*
X910099Y959050D01*
X903549D01*
X900499Y962100D01*
G01X908583Y966392D02*
X908857D01*
X913149Y962100D01*
G01X922049Y967225D02*
Y961050D01*
G01X916649Y962100D02*
X917699Y961050D01*
X922049D01*
G01X852333Y1077716D02*
X852300Y1077300D01*
Y1074000D01*
X851600Y1073300D01*
G01X852333Y1081392D02*
Y1077716D01*
G01X846400Y1078700D02*
X847550Y1079850D01*
Y1083200D01*
G01X852333Y1087392D02*
X856583D01*
X856833Y1087642D01*
G01X847550Y1083200D02*
Y1087359D01*
X847583Y1087392D01*
G01D02*
X852333D01*
G01X856833Y1087642D02*
X857241Y1088050D01*
X864499D01*
X866390Y1089941D01*
X878917D01*
X878937Y1089961D01*
G01X844050Y1083200D02*
Y1074650D01*
X845200Y1073500D01*
X846500D01*
G01X880499Y1367550D02*
X873249D01*
G01X898544Y1376983D02*
X901066D01*
X901999Y1376050D01*
Y1370707D01*
X898842Y1367550D01*
X880499D01*
G01X863949Y1362800D02*
X867749D01*
X868499Y1363550D01*
X869749D01*
G01D02*
Y1359550D01*
G01D02*
Y1354212D01*
X869587Y1354050D01*
G01X873577Y1375796D02*
X874823Y1374550D01*
X882999D01*
G01X892794Y1376983D02*
X885432D01*
X882999Y1374550D01*
G01X873577Y1379796D02*
X873951Y1380170D01*
X879999D01*
G01X892794Y1380183D02*
X880012D01*
X879999Y1380170D01*
G01X891999Y1363550D02*
X873249D01*
G01X898544Y1380183D02*
X901246D01*
X903999Y1377430D01*
Y1367050D01*
X900499Y1363550D01*
X891999D01*
G01X861849Y1372200D02*
Y1376050D01*
G01X869749Y1367550D02*
X863499D01*
X861849Y1369200D01*
Y1372200D01*
G01X847500Y1367000D02*
X847825Y1366675D01*
X856449D01*
G01X858349Y1372200D02*
X856449Y1370300D01*
Y1366675D01*
G01X854327Y1486296D02*
Y1481596D01*
G01D02*
Y1477550D01*
G01X848300Y1483000D02*
Y1486300D01*
X849550Y1487550D01*
Y1488100D01*
G01X854327Y1492296D02*
X858577D01*
X858827Y1492546D01*
G01X849550Y1488100D02*
Y1492269D01*
X849577Y1492296D01*
G01D02*
X854327D01*
G01X858827Y1492546D02*
X867495D01*
X870422Y1495473D01*
X878937D01*
G01X840775Y1486550D02*
Y1482025D01*
X845700Y1477100D01*
G01X846050Y1488100D02*
X842325D01*
X840775Y1486550D01*
G01X886200Y1776200D02*
Y1782099D01*
X886314Y1782213D01*
G01D02*
X892513D01*
X892794Y1782494D01*
G01X898544D02*
Y1779096D01*
X898024Y1778576D01*
X897499Y1778050D01*
X897239Y1777790D01*
Y1771500D01*
G01X904814Y1777613D02*
Y1772865D01*
X902819Y1770870D01*
X897869D01*
X897239Y1771500D01*
G01X914049Y1781000D02*
X914999Y1781950D01*
Y1791500D01*
G01X908314Y1781613D02*
X913436D01*
X914049Y1781000D01*
G01X908314Y1785613D02*
Y1781613D01*
G01X886350Y1786300D02*
X886956Y1785694D01*
X892794D01*
G01D02*
X893855D01*
X895500Y1784049D01*
Y1778551D01*
X892999Y1776050D01*
G01X898544Y1785694D02*
X900734D01*
X902364Y1784064D01*
X904814Y1781613D01*
G01D02*
X899805Y1776604D01*
X899599D01*
G01X912649Y1771700D02*
Y1773278D01*
X908314Y1777613D01*
G01D02*
X916013D01*
X917499Y1779099D01*
Y1796550D01*
G01X921549Y1777125D02*
X921499Y1777075D01*
Y1770050D01*
G01X916149Y1771700D02*
X917799Y1770050D01*
X921499D01*
G01X854814Y1892113D02*
Y1887250D01*
G01D02*
Y1883550D01*
G01X841374Y1892300D02*
Y1891226D01*
X847700Y1884900D01*
Y1881900D01*
G01X850049Y1893850D02*
X849800Y1893400D01*
Y1888300D01*
G01X850049Y1893850D02*
X850551D01*
X854814Y1898113D01*
G01D02*
X859064D01*
X859314Y1898363D01*
G01X850064Y1898113D02*
Y1893865D01*
X850049Y1893850D01*
G01X878937Y1900985D02*
X868512D01*
X867240Y1899713D01*
X860664D01*
X859314Y1898363D01*
G01X846549Y1893850D02*
X842924D01*
X841374Y1892300D01*
G01X925978Y164424D02*
X922999Y161445D01*
Y158550D01*
G01D02*
X927599D01*
X927649Y158500D01*
G01X945999Y166550D02*
X944849Y167700D01*
X932049D01*
G01X925749Y172550D02*
X925978Y172321D01*
Y168424D01*
G01D02*
X926702Y167700D01*
X932049D01*
G01X931149Y158500D02*
X937499D01*
G01X939549Y163825D02*
Y159600D01*
X938449Y158500D01*
X937499D01*
G01X964000Y1639200D02*
X964850D01*
X966950Y1641300D01*
X990302D01*
X990500Y1641102D01*
X1005807D01*
G01X960900Y1636400D02*
X961198Y1636102D01*
X984600D01*
X985498Y1637000D01*
X992102D01*
X993000Y1636102D01*
X1005807D01*
G01X971200Y1660500D02*
X977500D01*
G01X971200Y1665500D02*
X975500D01*
X978000Y1668000D01*
G01X974000Y1670700D02*
X974402Y1671102D01*
X1005807D01*
G01X984211Y1667500D02*
X984500D01*
X985898Y1666102D01*
X1005807D01*
G01X981500Y1653000D02*
X984602Y1656102D01*
X1005807D01*
G01X980800Y1659600D02*
X982302Y1661102D01*
X1005807D01*
G01X982050Y1649302D02*
X983850Y1651102D01*
X1005807D01*
M02*
